(kicad_pcb
	(version 20241229)
	(generator "pcbnew")
	(generator_version "9.0")
	(general
		(thickness 1.6296)
		(legacy_teardrops no)
	)
	(paper "A3")
	(title_block
		(title "Thunderbolt to 10GbE adapter")
		(date "2026-04-21")
		(rev "1.1.0")
		(company "Antmicro Ltd")
		(comment 1 "www.antmicro.com")
	)
	(layers
		(0 "F.Cu" signal)
		(4 "In1.Cu" signal)
		(6 "In2.Cu" signal)
		(8 "In3.Cu" signal)
		(10 "In4.Cu" signal)
		(12 "In5.Cu" signal)
		(14 "In6.Cu" signal)
		(2 "B.Cu" signal)
		(9 "F.Adhes" user "F.Adhesive")
		(11 "B.Adhes" user "B.Adhesive")
		(13 "F.Paste" user)
		(15 "B.Paste" user)
		(5 "F.SilkS" user "F.Silkscreen")
		(7 "B.SilkS" user "B.Silkscreen")
		(1 "F.Mask" user)
		(3 "B.Mask" user)
		(17 "Dwgs.User" user "User.Drawings")
		(19 "Cmts.User" user "User.Comments")
		(21 "Eco1.User" user "User.Eco1")
		(23 "Eco2.User" user "User.Eco2")
		(25 "Edge.Cuts" user)
		(27 "Margin" user)
		(31 "F.CrtYd" user "F.Courtyard")
		(29 "B.CrtYd" user "B.Courtyard")
		(35 "F.Fab" user)
		(33 "B.Fab" user)
	)
	(setup
		(stackup
			(layer "F.SilkS"
				(type "Top Silk Screen")
				(color "White")
			)
			(layer "F.Paste"
				(type "Top Solder Paste")
			)
			(layer "F.Mask"
				(type "Top Solder Mask")
				(color "Black")
				(thickness 0.01)
			)
			(layer "F.Cu"
				(type "copper")
				(thickness 0.035)
			)
			(layer "dielectric 1"
				(type "prepreg")
				(thickness 0.1164)
				(material "2116 RC54%")
				(epsilon_r 4.16)
				(loss_tangent 0.02)
			)
			(layer "In1.Cu"
				(type "copper")
				(thickness 0.0152)
			)
			(layer "dielectric 2"
				(type "core")
				(thickness 0.25)
				(material "FR4 TG170")
				(epsilon_r 4.4)
				(loss_tangent 0.02)
			)
			(layer "In2.Cu"
				(type "copper")
				(thickness 0.0152)
			)
			(layer "dielectric 3"
				(type "prepreg")
				(thickness 0.1164)
				(material "2116 RC54%")
				(epsilon_r 4.16)
				(loss_tangent 0.02) addsublayer
				(thickness 0.1164)
				(material "2116 RC54%")
				(epsilon_r 4.16)
				(loss_tangent 0.02)
			)
			(layer "In3.Cu"
				(type "copper")
				(thickness 0.0152)
			)
			(layer "dielectric 4"
				(type "core")
				(thickness 0.25)
				(material "FR4 TG170")
				(epsilon_r 4.4)
				(loss_tangent 0.02)
			)
			(layer "In4.Cu"
				(type "copper")
				(thickness 0.0152)
			)
			(layer "dielectric 5"
				(type "prepreg")
				(thickness 0.1164)
				(material "2116 RC54%")
				(epsilon_r 4.16)
				(loss_tangent 0.02) addsublayer
				(thickness 0.1164)
				(material "2116 RC54%")
				(epsilon_r 4.16)
				(loss_tangent 0.02)
			)
			(layer "In5.Cu"
				(type "copper")
				(thickness 0.0152)
			)
			(layer "dielectric 6"
				(type "core")
				(thickness 0.25)
				(material "FR4 TG170")
				(epsilon_r 4.4)
				(loss_tangent 0.02)
			)
			(layer "In6.Cu"
				(type "copper")
				(thickness 0.0152)
			)
			(layer "dielectric 7"
				(type "prepreg")
				(thickness 0.1164)
				(material "2116 RC54%")
				(epsilon_r 4.2)
				(loss_tangent 0.02)
			)
			(layer "B.Cu"
				(type "copper")
				(thickness 0.035)
			)
			(layer "B.Mask"
				(type "Bottom Solder Mask")
				(color "Black")
				(thickness 0.01)
			)
			(layer "B.Paste"
				(type "Bottom Solder Paste")
			)
			(layer "B.SilkS"
				(type "Bottom Silk Screen")
				(color "White")
			)
			(copper_finish "None")
			(dielectric_constraints yes)
		)
		(pad_to_mask_clearance 0)
		(allow_soldermask_bridges_in_footprints no)
		(tenting front back)
		(aux_axis_origin 115 155)
		(grid_origin 115 155)
		(pcbplotparams
			(layerselection 0x00000000_00000000_55555555_5755f5ff)
			(plot_on_all_layers_selection 0x00000000_00000000_00000000_00000000)
			(disableapertmacros no)
			(usegerberextensions no)
			(usegerberattributes yes)
			(usegerberadvancedattributes yes)
			(creategerberjobfile yes)
			(dashed_line_dash_ratio 12.000000)
			(dashed_line_gap_ratio 3.000000)
			(svgprecision 4)
			(plotframeref no)
			(mode 1)
			(useauxorigin no)
			(hpglpennumber 1)
			(hpglpenspeed 20)
			(hpglpendiameter 15.000000)
			(pdf_front_fp_property_popups yes)
			(pdf_back_fp_property_popups yes)
			(pdf_metadata yes)
			(pdf_single_document no)
			(dxfpolygonmode yes)
			(dxfimperialunits yes)
			(dxfusepcbnewfont yes)
			(psnegative no)
			(psa4output no)
			(plot_black_and_white yes)
			(sketchpadsonfab no)
			(plotpadnumbers no)
			(hidednponfab no)
			(sketchdnponfab yes)
			(crossoutdnponfab yes)
			(subtractmaskfromsilk no)
			(outputformat 1)
			(mirror no)
			(drillshape 1)
			(scaleselection 1)
			(outputdirectory "")
		)
	)
	(net 0 "")
	(net 1 "VCCA")
	(net 2 "/X710-AT2 PCIe/RSENSE")
	(net 3 "/X710-AT2 PCIe/RBIAS")
	(net 4 "/X710-AT2 PCIe/PCIe_JTAG.JTMS")
	(net 5 "P0_AVDDL")
	(net 6 "DVDD")
	(net 7 "+3V3")
	(net 8 "/X710-AT2 PCIe/PCIe_JTAG.JTDO")
	(net 9 "VCCD")
	(net 10 "AVDDH")
	(net 11 "/X710-AT2 PCIe/PCIe_JTAG.JTDI")
	(net 12 "XFI_VDD")
	(net 13 "/Power input/5V_JACK")
	(net 14 "P1_AVDDL")
	(net 15 "/X710-AT2 PCIe/PCIe_JTAG.~{JRST}")
	(net 16 "/X710-AT2 PCIe/PCIe_JTAG.JTCK")
	(net 17 "Net-(U2-PG)")
	(net 18 "+1V88")
	(net 19 "Net-(D5-C)")
	(net 20 "XGB_AVDDH")
	(net 21 "XFI_PVDD")
	(net 22 "PLL_VDD")
	(net 23 "GND")
	(net 24 "/X710-AT2 10GbE/25MHZ_OSC.+")
	(net 25 "/X710-AT2 10GbE/25MHZ_OSC_AC.+")
	(net 26 "/X710-AT2 10GbE/25MHZ_OSC.-")
	(net 27 "/X710-AT2 PCIe/PCIe_{x4}_AC.TX0+")
	(net 28 "/X710-AT2 PCIe/PCIe_{x4}_AC.TX0-")
	(net 29 "/X710-AT2 PCIe/PCIe_{x4}_AC.TX1+")
	(net 30 "/X710-AT2 PCIe/PCIe_{x4}_AC.TX1-")
	(net 31 "/X710-AT2 PCIe/PCIe_{x4}_AC.TX2+")
	(net 32 "/X710-AT2 PCIe/PCIe_{x4}_AC.TX2-")
	(net 33 "/X710-AT2 PCIe/PCIe_{x4}_AC.TX3+")
	(net 34 "/X710-AT2 PCIe/PCIe_{x4}_AC.TX3-")
	(net 35 "/X710-AT2 Misc/POR_BYPASS")
	(net 36 "/2xRJ45/Ethernet_P0.D2-")
	(net 37 "/2xRJ45/Ethernet_P0.D1-")
	(net 38 "/2xRJ45/Ethernet_P0.D3-")
	(net 39 "/2xRJ45/Ethernet_P0.D2+")
	(net 40 "+5V")
	(net 41 "/2xRJ45/Ethernet_P0.D4+")
	(net 42 "/2xRJ45/Ethernet_P0.D1+")
	(net 43 "/2xRJ45/Ethernet_P0.D4-")
	(net 44 "/2xRJ45/Ethernet_P0.D3+")
	(net 45 "/2xRJ45/Ethernet_P1.D1-")
	(net 46 "/2xRJ45/Ethernet_P1.D2-")
	(net 47 "/2xRJ45/Ethernet_P1.D2+")
	(net 48 "/2xRJ45/Ethernet_P1.D3+")
	(net 49 "/2xRJ45/Ethernet_P1.D3-")
	(net 50 "/2xRJ45/Ethernet_P1.D4+")
	(net 51 "/2xRJ45/Ethernet_P1.D4-")
	(net 52 "/2xRJ45/Ethernet_P1.D1+")
	(net 53 "+5V_USB")
	(net 54 "Net-(D8-C)")
	(net 55 "/X710-AT2 10GbE/25MHZ_OSC_AC.-")
	(net 56 "/X710-AT2 10GbE/3V3_OSC")
	(net 57 "+3V3_TB")
	(net 58 "/X710-AT2 Misc/50MHZ_XTAL_R.+")
	(net 59 "/X710-AT2 Misc/50MHZ_XTAL_R.-")
	(net 60 "/2xRJ45/~{P0_LED_LINK_10G}")
	(net 61 "/2xRJ45/~{P0_LED_ACT}")
	(net 62 "/X710-AT2 10GbE/RESCAL_RES_P")
	(net 63 "/X710-AT2 10GbE/BIAS_RDAC")
	(net 64 "/X710-AT2 10GbE/OSC_SEL")
	(net 65 "/2xRJ45/~{P1_LINK_LESS_THAN_10G}")
	(net 66 "/2xRJ45/~{P1_LED_LINK_10G}")
	(net 67 "/2xRJ45/~{P1_LED_ACT}")
	(net 68 "/TB Controller - Power/VCC_0P9")
	(net 69 "/PD and TB DC-DC/AUX.+")
	(net 70 "/X710-AT2 10GbE/MDC3_SCL3")
	(net 71 "/X710-AT2 10GbE/MDIO3_SDA3")
	(net 72 "/X710-AT2 10GbE/MDC2_SCL2")
	(net 73 "/X710-AT2 Misc/~{SMBALRT}")
	(net 74 "/X710-AT2 Misc/LAN_PWR_GOOD")
	(net 75 "/X710-AT2 Misc/AUX_PWR")
	(net 76 "/X710-AT2 10GbE/MDIO2_SDA2")
	(net 77 "/X710-AT2 10GbE/MDC1_SCL1")
	(net 78 "/X710-AT2 10GbE/MDIO1_SDA1")
	(net 79 "/PD and TB DC-DC/AUX.-")
	(net 80 "/X710 DCDC converters/3V3_VCC")
	(net 81 "/X710-AT2 Misc/FLSH_SCK")
	(net 82 "/X710-AT2 Misc/GPIO5_POR_BYPASS")
	(net 83 "/X710 DCDC converters/VCCD_VCC")
	(net 84 "/X710-AT2 Misc/RSVDL33")
	(net 85 "/X710-AT2 Misc/RSVDK40_1P88V")
	(net 86 "/X710-AT2 RSVD/DEBUG_EN")
	(net 87 "/X710-AT2 Misc/RSVD_J11_VSS")
	(net 88 "/X710-AT2 Misc/~{PHY_TRST}")
	(net 89 "/X710-AT2 RSVD/DEBUG_Y20")
	(net 90 "/X710-AT2 RSVD/DEBUG_W7")
	(net 91 "/X710-AT2 RSVD/DEBUG_Y16")
	(net 92 "/X710-AT2 RSVD/RSVDY24_VSS")
	(net 93 "/X710-AT2 RSVD/RSVDY22_VSS")
	(net 94 "/X710-AT2 RSVD/RSVDW5_VSS")
	(net 95 "/X710-AT2 RSVD/RSVDN9_VSS")
	(net 96 "/X710-AT2 RSVD/RSVDW1_VSS")
	(net 97 "/X710-AT2 RSVD/RSVDP22_VSS")
	(net 98 "/X710-AT2 RSVD/RSVDY18_VSS")
	(net 99 "/X710-AT2 RSVD/RSVDP8_VSS")
	(net 100 "/X710-AT2 10GbE/MDC0_SCL0")
	(net 101 "/X710-AT2 RSVD/RSVDD8_1P88V")
	(net 102 "/X710-AT2 10GbE/MDIO0_SDA0")
	(net 103 "/X710-AT2 Misc/MAIN_PWR_OK")
	(net 104 "/X710-AT2 Misc/PHY_TCK")
	(net 105 "/X710-AT2 Misc/PHY_TMS")
	(net 106 "/X710-AT2 Misc/PHY_TDI")
	(net 107 "/X710-AT2 Misc/PHY_TDO")
	(net 108 "/X710 DCDC converters/1V88_VCC")
	(net 109 "/X710 DCDC converters/1V0_VCC")
	(net 110 "/X710-AT2 10GbE/~{PHY_RESET_3V3_R}")
	(net 111 "/X710-AT2 10GbE/~{P0_INT}")
	(net 112 "/X710-AT2 10GbE/25MHZ_OSC_R.+")
	(net 113 "/X710-AT2 10GbE/EN_OSC")
	(net 114 "/X710-AT2 10GbE/25MHZ_OSC_R.-")
	(net 115 "/X710-AT2 Misc/50MHZ_XTAL.+")
	(net 116 "/X710 DCDC converters/DVDD_VCC")
	(net 117 "/X710 DCDC converters/3V3_SW")
	(net 118 "/X710 DCDC converters/3V3_BST")
	(net 119 "/X710 DCDC converters/VCCD_BST")
	(net 120 "/X710-AT2 Misc/50MHZ_XTAL.-")
	(net 121 "/X710-AT2 10GbE/~{P0_INT_R}")
	(net 122 "/X710-AT2 10GbE/MDIO0_I2C0.MDIO")
	(net 123 "/X710-AT2 10GbE/~{P1_INT_R}")
	(net 124 "/X710-AT2 10GbE/~{P1_INT}")
	(net 125 "/X710-AT2 10GbE/MDIO0_I2C0.MDC")
	(net 126 "/X710-AT2 Misc/~{PCI_DIS}")
	(net 127 "/X710-AT2 Misc/~{DEV_DIS}")
	(net 128 "/2xRJ45/~{P0_LINK_LESS_THAN_10G}")
	(net 129 "/X710-AT2 RSVD/RSVDE19_1P88V")
	(net 130 "/X710-AT2 10GbE/TPIN_3")
	(net 131 "/X710-AT2 10GbE/TPIN_5")
	(net 132 "/X710-AT2 Misc/XTAL_BYPASS")
	(net 133 "/2xRJ45/P0_CT")
	(net 134 "/2xRJ45/P1_CT")
	(net 135 "+1V88_CT")
	(net 136 "+1V0")
	(net 137 "/X710-AT2 Misc/NCSI.RXD_1")
	(net 138 "/X710-AT2 Misc/NCSI.TXD_1")
	(net 139 "/X710-AT2 Misc/NCSI.RXD_0")
	(net 140 "/X710-AT2 Misc/NCSI.TXD_0")
	(net 141 "/X710-AT2 Misc/NCSI.ARB_OUT")
	(net 142 "/X710-AT2 Misc/NCSI.CRS_DV")
	(net 143 "/X710-AT2 Misc/NCSI.TX_EN")
	(net 144 "/X710-AT2 Misc/NCSI.REF_CLK")
	(net 145 "/X710-AT2 Misc/NCSI.ARB_IN")
	(net 146 "/X710-AT2 10GbE/~{PHY_RESET_3V3}")
	(net 147 "/X710-AT2 Misc/MDIO.MDIO")
	(net 148 "/X710-AT2 Misc/MDIO.MDC")
	(net 149 "/X710-AT2 Misc/REFCLK_SEL")
	(net 150 "/X710-AT2 Misc/~{PHY_RESET}")
	(net 151 "/Fan controller/SENSE")
	(net 152 "/Fan controller/FREQ")
	(net 153 "/X710 DCDC converters/VCCD_SW")
	(net 154 "/Fan controller/PWM")
	(net 155 "/Fan controller/TACH")
	(net 156 "/Fan controller/D0")
	(net 157 "/Fan controller/DMIN")
	(net 158 "/Fan controller/SLOPE")
	(net 159 "/X710-AT2 PCIe/CLK+")
	(net 160 "/X710-AT2 PCIe/CLK-")
	(net 161 "Net-(U2-VIN)")
	(net 162 "Net-(U2-BST)")
	(net 163 "Net-(U2-SW)")
	(net 164 "Net-(D2-A)")
	(net 165 "Net-(U3-SS)")
	(net 166 "Net-(U2-FB)")
	(net 167 "/TB Controller/PA_TX0_P")
	(net 168 "/TB Controller/PA_TX1_P")
	(net 169 "/TB Controller/PA_TX0_N")
	(net 170 "PP_HV")
	(net 171 "Net-(U3-VOUT_3V3)")
	(net 172 "Net-(U3-LDO_1V8A)")
	(net 173 "PP_5V0")
	(net 174 "/TB Controller/PA_TX1_N")
	(net 175 "Net-(U3-LDO_1V8D)")
	(net 176 "Net-(U3-LDO_BMC)")
	(net 177 "Net-(U4A-VCC3P3_ANA_PCIE)")
	(net 178 "Net-(U4A-VCC3P3_ANA_USB2)")
	(net 179 "Net-(U4A-VCC3P3_LC)")
	(net 180 "Net-(U4A-VCC0P9_LVR_SENSE)")
	(net 181 "Net-(U4A-VCC3P3_S0)")
	(net 182 "VBUS")
	(net 183 "Net-(U4B-PCIE_RBIAS)")
	(net 184 "Net-(U4C-DPSRC_HPD)")
	(net 185 "Net-(U4C-DPSRC_RBIAS)")
	(net 186 "Net-(U4C-GPIO_3)")
	(net 187 "Net-(U4C-GPIO_4)")
	(net 188 "Net-(U4C-GPIO_5)")
	(net 189 "Net-(U4C-GPIO_6)")
	(net 190 "Net-(U4C-GPIO_7)")
	(net 191 "Net-(U4C-GPIO_8)")
	(net 192 "Net-(U4C-POC_GPIO_1)")
	(net 193 "Net-(U4C-POC_GPIO_2)")
	(net 194 "Net-(U4C-POC_GPIO_3)")
	(net 195 "Net-(D4-C)")
	(net 196 "Net-(Q1-B)")
	(net 197 "Net-(Q1-C)")
	(net 198 "Net-(U3-I2C_SDA2)")
	(net 199 "Net-(U3-I2C_SCL2)")
	(net 200 "Net-(U3-I2C_IRQ2Z)")
	(net 201 "Net-(U3-GPIO0(HD3_AMSEL))")
	(net 202 "Net-(U3-GPIO4(HPD_TXRX))")
	(net 203 "Net-(U3-GPIO6)")
	(net 204 "Net-(U3-GPIO7)")
	(net 205 "Net-(U3-UART_RX)")
	(net 206 "Net-(U3-DEBUG_CTL2(GPIO17,_I2CADDR_B5))")
	(net 207 "Net-(U3-DEBUG_CTL1(GPIO16,_I2CADDR_B4))")
	(net 208 "Net-(U3-I2C_ADDR)")
	(net 209 "Net-(U3-MRESET(GPIO11))")
	(net 210 "Net-(U3-HRESET)")
	(net 211 "Net-(U3-BUSPOWERZ(GPIO10))")
	(net 212 "Net-(U3-R_OSC)")
	(net 213 "/TB Controller/PCIE_CLK_JHL_P")
	(net 214 "/TB Controller/PCIE_CLK_JHL_N")
	(net 215 "/USB-C connector/VBUS")
	(net 216 "Net-(U4B-PCIE_CLKREQ_N)")
	(net 217 "Net-(U4C-DPSNK0_HPD)")
	(net 218 "Net-(U4C-DPSNK0_DDC_CLK)")
	(net 219 "Net-(U4C-DPSNK0_DDC_DATA)")
	(net 220 "Net-(U4C-DPSNK1_HPD)")
	(net 221 "Net-(U4C-DPSNK1_DDC_CLK)")
	(net 222 "Net-(U4C-DPSNK1_DDC_DATA)")
	(net 223 "Net-(U4C-DPSNK_RBIAS)")
	(net 224 "Net-(U4D-TDI)")
	(net 225 "Net-(U4D-TMS)")
	(net 226 "Net-(U4D-TCK)")
	(net 227 "Net-(U4D-TDO)")
	(net 228 "Net-(U4E-PA_USB2_RBIAS)")
	(net 229 "Net-(U4D-RSENSE)")
	(net 230 "Net-(U4D-RBIAS)")
	(net 231 "Net-(U4E-PB_LSTX)")
	(net 232 "Net-(U4E-PB_LSRX)")
	(net 233 "Net-(U4E-PB_DPSRC_HPD)")
	(net 234 "Net-(U4E-PB_USB2_RBIAS)")
	(net 235 "Net-(U4C-POC_GPIO_5)")
	(net 236 "Net-(U4C-POC_GPIO_6)")
	(net 237 "Net-(U4D-TEST_EN)")
	(net 238 "Net-(U4D-TEST_PWR_GOOD)")
	(net 239 "/TB Controller/PA_AUX_P")
	(net 240 "/TB Controller/PA_AUX_N")
	(net 241 "/X710 DCDC converters/1V88_SW")
	(net 242 "unconnected-(U4E-PB_RX1_N-PadA7)")
	(net 243 "unconnected-(U4E-PB_TX1_P-PadA9)")
	(net 244 "unconnected-(U4E-PB_TX0_P-PadA11)")
	(net 245 "unconnected-(U4E-PB_RX0_P-PadA13)")
	(net 246 "unconnected-(U4F-ATEST_P-PadA23)")
	(net 247 "unconnected-(U4C-DPSNK0_ML0_P-PadAB7)")
	(net 248 "unconnected-(U4C-DPSNK0_ML1_P-PadAB9)")
	(net 249 "unconnected-(U4C-DPSNK0_ML2_P-PadAB11)")
	(net 250 "unconnected-(U4C-DPSNK0_ML3_P-PadAB13)")
	(net 251 "unconnected-(U4C-DPSNK1_ML0_P-PadAB15)")
	(net 252 "unconnected-(U4C-DPSNK1_ML1_P-PadAB17)")
	(net 253 "unconnected-(U4C-DPSNK1_ML2_P-PadAB19)")
	(net 254 "unconnected-(U4C-DPSNK1_ML3_P-PadAB21)")
	(net 255 "unconnected-(U4F-THERMDA2-PadAB23)")
	(net 256 "unconnected-(U4C-DPSNK0_ML0_N-PadAC7)")
	(net 257 "unconnected-(U4C-DPSNK0_ML1_N-PadAC9)")
	(net 258 "unconnected-(U4C-DPSNK0_ML2_N-PadAC11)")
	(net 259 "unconnected-(U4C-DPSNK0_ML3_N-PadAC13)")
	(net 260 "unconnected-(U4C-DPSNK1_ML0_N-PadAC15)")
	(net 261 "unconnected-(U4C-DPSNK1_ML1_N-PadAC17)")
	(net 262 "unconnected-(U4C-DPSNK1_ML2_N-PadAC19)")
	(net 263 "unconnected-(U4C-DPSNK1_ML3_N-PadAC21)")
	(net 264 "unconnected-(U4F-THERMDA1-PadAC23)")
	(net 265 "unconnected-(U4E-PB_RX1_P-PadB7)")
	(net 266 "unconnected-(U4E-PB_TX1_N-PadB9)")
	(net 267 "unconnected-(U4E-PB_TX0_N-PadB11)")
	(net 268 "unconnected-(U4E-PB_RX0_N-PadB13)")
	(net 269 "unconnected-(U4F-ATEST_N-PadB23)")
	(net 270 "unconnected-(U4E-PB_USB2_D_N-PadD19)")
	(net 271 "unconnected-(U4F-USB2_ATEST-PadE18)")
	(net 272 "unconnected-(U4E-PB_USB2_D_P-PadE19)")
	(net 273 "unconnected-(U4C-DPSRC_ML3_N-PadJ1)")
	(net 274 "unconnected-(U4C-DPSRC_ML3_P-PadJ2)")
	(net 275 "unconnected-(U4C-DPSRC_ML2_N-PadL1)")
	(net 276 "unconnected-(U4C-DPSRC_ML2_P-PadL2)")
	(net 277 "unconnected-(U4C-DPSRC_ML1_N-PadN1)")
	(net 278 "unconnected-(U4C-DPSRC_ML1_P-PadN2)")
	(net 279 "unconnected-(U4C-DPSRC_ML0_N-PadR1)")
	(net 280 "unconnected-(U4C-DPSRC_ML0_P-PadR2)")
	(net 281 "unconnected-(U4F-PCIE_ATEST-PadV18)")
	(net 282 "unconnected-(U4C-DPSNK0_AUX_N-PadW11)")
	(net 283 "unconnected-(U4C-DPSNK1_AUX_N-PadW12)")
	(net 284 "unconnected-(U4E-PB_DPSRC_AUX_N-PadW16)")
	(net 285 "unconnected-(U4C-DPSRC_AUX_P-PadW19)")
	(net 286 "unconnected-(U4C-DPSNK0_AUXP-PadY11)")
	(net 287 "unconnected-(U4C-DPSNK1_AUXP-PadY12)")
	(net 288 "unconnected-(U4E-PB_DPSRC_AUX_P-PadY16)")
	(net 289 "unconnected-(U4C-DPSRC_AUX_N-PadY19)")
	(net 290 "unconnected-(U3-HV_GATE2-PadA9)")
	(net 291 "unconnected-(U3-SENSEN-PadA10)")
	(net 292 "unconnected-(U3-HV_GATE1-PadB9)")
	(net 293 "unconnected-(U3-SENSEP-PadB10)")
	(net 294 "unconnected-(U3-GPIO1(CONFIG0)-PadC2)")
	(net 295 "unconnected-(U3-GPIO2-PadD10)")
	(net 296 "unconnected-(U3-GPIO5(HPD_RX)-PadE10)")
	(net 297 "unconnected-(U3-SWD_DATA-PadF4)")
	(net 298 "unconnected-(U3-SWD_CLK-PadG4)")
	(net 299 "unconnected-(U3-GPIO3(HD3_EN)-PadG11)")
	(net 300 "unconnected-(U3-GPIO8-PadH6)")
	(net 301 "unconnected-(U3-NC-PadL11)")
	(net 302 "/X710 DCDC converters/1V88_BST")
	(net 303 "/PD and TB DC-DC/SMPS_LDO")
	(net 304 "/PD and TB DC-DC/TPS_3V3")
	(net 305 "/PD and TB DC-DC/USB3.CC2")
	(net 306 "/PD and TB DC-DC/USB3.CC1")
	(net 307 "/X710 DCDC converters/1V0_BST")
	(net 308 "/PD and TB DC-DC/USB3.TX0_P")
	(net 309 "/PD and TB DC-DC/USB3.TX1_P")
	(net 310 "/X710 DCDC converters/1V0_SW")
	(net 311 "/PD and TB DC-DC/USB3.TX0_N")
	(net 312 "/PD and TB DC-DC/USB3.TX1_N")
	(net 313 "/X710 DCDC converters/DVDD_SW")
	(net 314 "/TB Controller/PCIex4.RX0+")
	(net 315 "/TB Controller/TB_PCIE_TX0_N")
	(net 316 "/TB Controller/TB_PCIE_TX1_N")
	(net 317 "/TB Controller/PCIex4.RX1+")
	(net 318 "/TB Controller/TB_PCIE_TX2_N")
	(net 319 "/TB Controller/PCIex4.RX2+")
	(net 320 "/TB Controller/TB_PCIE_TX3_N")
	(net 321 "/TB Controller/PCIex4.RX3+")
	(net 322 "/TB Controller/PCIex4.RX0-")
	(net 323 "/TB Controller/TB_PCIE_TX0_P")
	(net 324 "/TB Controller/PCIex4.RX1-")
	(net 325 "/TB Controller/TB_PCIE_TX1_P")
	(net 326 "/TB Controller/PCIex4.RX2-")
	(net 327 "/TB Controller/TB_PCIE_TX2_P")
	(net 328 "/TB Controller/PCIex4.RX3-")
	(net 329 "/TB Controller/TB_PCIE_TX3_P")
	(net 330 "/TB Controller/XTAL_25_IN")
	(net 331 "/TB Controller/XTAL_25_OUT")
	(net 332 "/X710 DCDC converters/DVDD_BST")
	(net 333 "/X710 DCDC converters/3V3_FB")
	(net 334 "/X710 DCDC converters/+3V3_OUT")
	(net 335 "/X710 DCDC converters/+VCCD_OUT")
	(net 336 "/X710 DCDC converters/VCCD_FB")
	(net 337 "/X710 DCDC converters/1V88_FB")
	(net 338 "/X710 DCDC converters/+1V88_OUT")
	(net 339 "/X710 DCDC converters/+1V0_OUT")
	(net 340 "/X710 DCDC converters/1V0_FB")
	(net 341 "/X710 DCDC converters/+DVDD_OUT")
	(net 342 "/X710 DCDC converters/DVDD_FB")
	(net 343 "/X710 flash memory/+3V3_FLASH")
	(net 344 "/Power input/5V_EN")
	(net 345 "/Power input/5V_VDD")
	(net 346 "/Power input/5V_VDRV")
	(net 347 "/Power input/5V_BOOT")
	(net 348 "/Power input/5V_PHASE")
	(net 349 "/Power input/5V_OUT")
	(net 350 "/X710 flash memory/FLASH.~{CE}")
	(net 351 "/X710 flash memory/FLASH.MISO")
	(net 352 "/X710 flash memory/FLASH.MOSI")
	(net 353 "/X710 flash memory/FLASH.CLK")
	(net 354 "/Power input/5V_SW")
	(net 355 "/X710 DCDC converters/DVDD_PG")
	(net 356 "/TB Controller - Power/0P9_BUFFERED")
	(net 357 "/PD and TB DC-DC/TB_FLASH.MISO")
	(net 358 "/TB flash memory/FLASH_WP")
	(net 359 "/PD and TB DC-DC/TB_FLASH.~{CE}")
	(net 360 "/PD and TB DC-DC/USB3.RX0_P")
	(net 361 "/PD and TB DC-DC/USB3.SBU2")
	(net 362 "/PD and TB DC-DC/USB3.RX1_P")
	(net 363 "/PD and TB DC-DC/USB3.RX0_N")
	(net 364 "/PD and TB DC-DC/USB3.RX1_N")
	(net 365 "/PD and TB DC-DC/USB3.D_B_P")
	(net 366 "/PD and TB DC-DC/USB3.D_A_N")
	(net 367 "/PD and TB DC-DC/USB3.D_B_N")
	(net 368 "/PD and TB DC-DC/USB3.D_A_P")
	(net 369 "/PD and TB DC-DC/USB3.SBU1")
	(net 370 "/TB flash memory/FLASH_HOLD")
	(net 371 "/TB Controller/~{PE_WAKE}")
	(net 372 "/PD and TB DC-DC/I2C1.IRQ")
	(net 373 "/PD and TB DC-DC/I2C1.SCL")
	(net 374 "/PD and TB DC-DC/HPD")
	(net 375 "/PD and TB DC-DC/I2C1.SDA")
	(net 376 "/PD and TB DC-DC/LSX_1.LSX_P2R")
	(net 377 "/PD and TB DC-DC/RESET_N")
	(net 378 "/X710 DCDC converters/3V3_PG")
	(net 379 "/X710 DCDC converters/VCCD_PG")
	(net 380 "/X710 DCDC converters/1V88_PG")
	(net 381 "/X710 DCDC converters/1V0_PG")
	(net 382 "/X710 DCDC converters/VCCD_EN")
	(net 383 "/PD and TB DC-DC/LSX_1.LSX_R2P")
	(net 384 "/X710 DCDC converters/1V88_EN")
	(net 385 "/X710 DCDC converters/1V0_EN")
	(net 386 "/X710 DCDC converters/DVDD_EN")
	(net 387 "/X710 flash memory/~{HOLD}")
	(net 388 "/X710 flash memory/~{WP}")
	(net 389 "/Power input/5V_MODE1")
	(net 390 "/Power input/5V_MODE2")
	(net 391 "/Power input/5V_FB")
	(net 392 "/TB Controller/~{PE_RST}")
	(net 393 "/TB Controller/REFCLK.+")
	(net 394 "/TB Controller/REFCLK.-")
	(net 395 "/PD and TB DC-DC/USB_RP.D-")
	(net 396 "/PD and TB DC-DC/USB_RP.D+")
	(net 397 "/PD and TB DC-DC/TB_FLASH.CLK")
	(net 398 "/PD and TB DC-DC/TB_FLASH.MOSI")
	(net 399 "Net-(D4-A)")
	(net 400 "Net-(U5-XOUT)")
	(net 401 "Net-(U5-XIN{slash}CLKIN)")
	(net 402 "Net-(C52-Pad2)")
	(net 403 "Net-(C55-Pad2)")
	(net 404 "Net-(C58-Pad2)")
	(net 405 "Net-(C66-Pad2)")
	(net 406 "Net-(J3-LED_YG_Y-)")
	(net 407 "Net-(J4-LED_YG_Y-)")
	(net 408 "Net-(J3-LED_YG_G-)")
	(net 409 "Net-(J4-LED_YG_G-)")
	(net 410 "Net-(J3-LED_GRN-)")
	(net 411 "Net-(J4-LED_GRN-)")
	(net 412 "Net-(D15-C)")
	(net 413 "Net-(D3-C)")
	(net 414 "Net-(D6-C)")
	(net 415 "Net-(D7-C)")
	(net 416 "Net-(D9-C)")
	(net 417 "Net-(D10-C)")
	(net 418 "Net-(D11-C)")
	(net 419 "Net-(D11-A)")
	(net 420 "Net-(D16-A)")
	(net 421 "Net-(D18-A)")
	(net 422 "unconnected-(J2-Pad7)")
	(net 423 "unconnected-(J2-Pad1)")
	(net 424 "unconnected-(J8-Pad10)")
	(net 425 "unconnected-(J8-Pad7)")
	(net 426 "Net-(L2-Pad1)")
	(net 427 "Net-(U14H-SVR_IND)")
	(net 428 "Net-(Q2-C)")
	(net 429 "Net-(Q3-C)")
	(net 430 "Net-(Q4-C)")
	(net 431 "Net-(Q5-C)")
	(net 432 "Net-(Q7-G)")
	(net 433 "Net-(Q8-G)")
	(net 434 "Net-(U1-ISET)")
	(net 435 "Net-(R75-Pad1)")
	(net 436 "Net-(R77-Pad1)")
	(net 437 "Net-(U15-A)")
	(net 438 "Net-(U17-B_{2})")
	(net 439 "Net-(U17-A_{2})")
	(net 440 "Net-(U14D-NCSI_ARB_OUT)")
	(net 441 "Net-(U14D-NCSI_CRS_DV)")
	(net 442 "Net-(U14D-NCSI_RXD_0)")
	(net 443 "Net-(U14D-NCSI_RXD_1)")
	(net 444 "Net-(U14D-SMBCLK)")
	(net 445 "Net-(U14D-SMBD)")
	(net 446 "Net-(R216-Pad1)")
	(net 447 "unconnected-(U1-FLG-Pad3)")
	(net 448 "unconnected-(U14A-PER_4_P-PadAA27)")
	(net 449 "unconnected-(U14G-RSVDR29_NC-PadR29)")
	(net 450 "unconnected-(U14A-PER_6_N-PadAA35)")
	(net 451 "unconnected-(U14A-PER_7_P-PadY38)")
	(net 452 "unconnected-(U14E-RSVDN27_NC-PadN27)")
	(net 453 "unconnected-(U14F-XTAL_PTP_XTAL_N-PadH42)")
	(net 454 "unconnected-(U14G-RSVDP32_NC-PadP32)")
	(net 455 "unconnected-(U14F-RSVDR33_NC-PadR33)")
	(net 456 "unconnected-(U14B-SER1_TX_N-PadB10)")
	(net 457 "unconnected-(U14C-LED1_1-PadU7)")
	(net 458 "unconnected-(U14E-RSVDV22_NC-PadV22)")
	(net 459 "unconnected-(U14F-RSVDH14_NC-PadH14)")
	(net 460 "unconnected-(U14E-RSVDM26_NC-PadM26)")
	(net 461 "unconnected-(U14E-RSVDV28_NC-PadV28)")
	(net 462 "unconnected-(U14E-RSVDT24_NC-PadT24)")
	(net 463 "unconnected-(U14A-PER_5_N-PadAA31)")
	(net 464 "unconnected-(U14F-RSVDM34_NC-PadM34)")
	(net 465 "unconnected-(U14H-RSVDV10_NC-PadV10)")
	(net 466 "unconnected-(U14G-RSVDK28_NC-PadK28)")
	(net 467 "unconnected-(U14E-RSVDW27_NC-PadW27)")
	(net 468 "unconnected-(U14C-SDP2_1-PadJ7)")
	(net 469 "unconnected-(U14C-LED1_0-PadU5)")
	(net 470 "unconnected-(U14F-RSVDK30_NC-PadK30)")
	(net 471 "unconnected-(U14A-PER_4_N-PadAB28)")
	(net 472 "unconnected-(U14F-RSVDM36_NC-PadM36)")
	(net 473 "unconnected-(U14G-RSVDV30_NC-PadV30)")
	(net 474 "unconnected-(U14F-RSVDN35_NC-PadN35)")
	(net 475 "unconnected-(U14B-SER0_TX_P-PadA17)")
	(net 476 "unconnected-(U14G-RSVDK36_NC-PadK36)")
	(net 477 "unconnected-(U14E-RSVDP26_NC-PadP26)")
	(net 478 "unconnected-(U14E-RSVDR27_NC-PadR27)")
	(net 479 "unconnected-(U14G-RSVDU33_NC-PadU33)")
	(net 480 "unconnected-(U14E-RSVDJ25_NC-PadJ25)")
	(net 481 "unconnected-(U14C-LED3_1-PadR5)")
	(net 482 "unconnected-(U14E-RSVDW25_NC-PadW25)")
	(net 483 "unconnected-(U14E-RSVDR23_NC-PadR23)")
	(net 484 "unconnected-(U14F-RSVDL35_NC-PadL35)")
	(net 485 "unconnected-(U14G-RSVDT32_NC-PadT32)")
	(net 486 "unconnected-(U14C-SDP1_3-PadH6)")
	(net 487 "unconnected-(U14A-PET_4_P-PadAD26)")
	(net 488 "unconnected-(U14F-RSVDR37_NC-PadR37)")
	(net 489 "unconnected-(U14D-GPIO_1-PadW41)")
	(net 490 "unconnected-(U14A-PER_7_N-PadAA39)")
	(net 491 "unconnected-(U14C-SDP1_0-PadR7)")
	(net 492 "unconnected-(U14G-RSVDR31_NC-PadR31)")
	(net 493 "unconnected-(U14E-RSVDT26_NC-PadT26)")
	(net 494 "unconnected-(U14E-RSVDM28_NC-PadM28)")
	(net 495 "unconnected-(U14C-SDP3_2-PadM6)")
	(net 496 "unconnected-(U14C-SDP3_1-PadN7)")
	(net 497 "unconnected-(U14E-RSVDR25_NC-PadR25)")
	(net 498 "unconnected-(U14G-RSVDK34_NC-PadK34)")
	(net 499 "unconnected-(U14E-RSVDK24_NC-PadK24)")
	(net 500 "unconnected-(U14E-RSVDW23_NC-PadW23)")
	(net 501 "unconnected-(U14E-RSVDP24_NC-PadP24)")
	(net 502 "unconnected-(U14E-RSVDP28_NC-PadP28)")
	(net 503 "unconnected-(U14G-RSVDN31_NC-PadN31)")
	(net 504 "unconnected-(U14G-RSVDA41_NC-PadA41)")
	(net 505 "unconnected-(U14E-RSVDL27_NC-PadL27)")
	(net 506 "unconnected-(U14F-RSVDP36_NC-PadP36)")
	(net 507 "unconnected-(U14E-RSVDU25_NC-PadU25)")
	(net 508 "unconnected-(U14G-RSVDB42_NC-PadB42)")
	(net 509 "unconnected-(U14B-SER1_TX_P-PadA9)")
	(net 510 "unconnected-(U14G-RSVDU35_NC-PadU35)")
	(net 511 "unconnected-(U14A-PET_6_N-PadAD36)")
	(net 512 "unconnected-(U14B-SER1_RX_N-PadA5)")
	(net 513 "unconnected-(U14C-SDP3_3-PadM8)")
	(net 514 "unconnected-(U14F-SYNCE_CLKOUT_3-PadE13)")
	(net 515 "unconnected-(U14E-RSVDL25_NC-PadL25)")
	(net 516 "unconnected-(U14A-PET_7_N-PadAD40)")
	(net 517 "unconnected-(U14G-RSVDD20_NC-PadD20)")
	(net 518 "unconnected-(U14B-SER0_TX_N-PadB18)")
	(net 519 "unconnected-(U14G-RSVDT30_NC-PadT30)")
	(net 520 "unconnected-(U14G-RSVDP30_NC-PadP30)")
	(net 521 "unconnected-(U14G-RSVDL29_NC-PadL29)")
	(net 522 "unconnected-(U14F-SYNCE_LOCK_1-PadE9)")
	(net 523 "unconnected-(U14G-RSVDV34_NC-PadV34)")
	(net 524 "unconnected-(U14E-RSVDV24_NC-PadV24)")
	(net 525 "unconnected-(U14F-RSVDN33_NC-PadN33)")
	(net 526 "unconnected-(U14F-XTAL_PTP_XTAL_P-PadJ41)")
	(net 527 "unconnected-(U14F-RSVDP34_NC-PadP34)")
	(net 528 "unconnected-(U14G-RSVDJ39_NC-PadJ39)")
	(net 529 "unconnected-(U14E-RSVDU29_NC-PadU29)")
	(net 530 "unconnected-(U14E-RSVDT28_NC-PadT28)")
	(net 531 "unconnected-(U14F-SYNCE_LOCK_0-PadF8)")
	(net 532 "unconnected-(U14A-PET_4_N-PadAD28)")
	(net 533 "unconnected-(U14E-RSVDN23_NC-PadN23)")
	(net 534 "unconnected-(U14F-RSVDJ15_NC-PadJ15)")
	(net 535 "unconnected-(U14C-SDP1_1-PadP4)")
	(net 536 "unconnected-(U14A-PET_5_N-PadAD32)")
	(net 537 "unconnected-(U14C-SDP2_2-PadE7)")
	(net 538 "unconnected-(U14B-SER0_RX_P-PadB14)")
	(net 539 "unconnected-(U14E-RSVDU23_NC-PadU23)")
	(net 540 "unconnected-(U14E-RSVDK22_NC-PadK22)")
	(net 541 "unconnected-(U14F-RSVDG15_NC-PadG15)")
	(net 542 "unconnected-(U14E-RSVDL23_NC-PadL23)")
	(net 543 "unconnected-(U14F-SYNCE_CLKOUT_1-PadF10)")
	(net 544 "unconnected-(U14A-PER_5_P-PadY30)")
	(net 545 "unconnected-(U14B-SER1_RX_P-PadB6)")
	(net 546 "unconnected-(U14F-RSVDK32_NC-PadK32)")
	(net 547 "unconnected-(U14C-SDP1_2-PadP6)")
	(net 548 "unconnected-(U14B-SER0_RX_N-PadA13)")
	(net 549 "unconnected-(U14E-RSVDM22_NC-PadM22)")
	(net 550 "unconnected-(U14C-SDP2_3-PadG7)")
	(net 551 "unconnected-(U14D-GPIO_4-PadH8)")
	(net 552 "unconnected-(U14E-RSVDV26_NC-PadV26)")
	(net 553 "unconnected-(U14E-RSVDR9_NC-PadR9)")
	(net 554 "unconnected-(U14C-LED3_0-PadR3)")
	(net 555 "unconnected-(U14F-SYNCE_CLKOUT_0-PadG9)")
	(net 556 "unconnected-(U14E-RSVDJ23_NC-PadJ23)")
	(net 557 "unconnected-(U14E-RSVDU9_NC-PadU9)")
	(net 558 "unconnected-(U14F-P1_PTP_SYNC0-PadH10)")
	(net 559 "unconnected-(U14F-P0_PTP_SYNC1-PadN41)")
	(net 560 "unconnected-(U14G-RSVDM30_NC-PadM30)")
	(net 561 "unconnected-(U14F-P1_PTP_SYNC1-PadH12)")
	(net 562 "unconnected-(U14G-RSVDC21_NC-PadC21)")
	(net 563 "unconnected-(U14A-PER_6_P-PadY34)")
	(net 564 "unconnected-(U14E-RSVDM24_NC-PadM24)")
	(net 565 "unconnected-(U14F-SYNCE_LOCK_2-PadE11)")
	(net 566 "unconnected-(U14G-RSVDD32_NC-PadD32)")
	(net 567 "unconnected-(U14F-SYNCE_CLKOUT_2-PadG11)")
	(net 568 "unconnected-(U14G-RSVDV32_NC-PadV32)")
	(net 569 "unconnected-(U14F-SYNCE_LOCK_3-PadF12)")
	(net 570 "unconnected-(U14G-RSVDM32_NC-PadM32)")
	(net 571 "unconnected-(U14A-PET_7_P-PadAC39)")
	(net 572 "unconnected-(U14H-RSVDV8_NC-PadV8)")
	(net 573 "unconnected-(U14E-RSVDT22_NC-PadT22)")
	(net 574 "unconnected-(U14C-SDP3_0-PadN5)")
	(net 575 "unconnected-(U14F-RSVDG13_NC-PadG13)")
	(net 576 "unconnected-(U14G-RSVDN29_NC-PadN29)")
	(net 577 "unconnected-(U14E-RSVDN25_NC-PadN25)")
	(net 578 "unconnected-(U14D-GPIO_3-PadV42)")
	(net 579 "unconnected-(U14A-PET_5_P-PadAC31)")
	(net 580 "unconnected-(U14C-SDP0_3-PadL5)")
	(net 581 "unconnected-(U14A-PET_6_P-PadAC35)")
	(net 582 "unconnected-(U14G-RSVDU31_NC-PadU31)")
	(net 583 "unconnected-(U14C-SDP2_0-PadF6)")
	(net 584 "unconnected-(U14E-RSVDU27_NC-PadU27)")
	(net 585 "unconnected-(U14G-RSVDK26_NC-PadK26)")
	(net 586 "unconnected-(U14F-RSVDH16_NC-PadH16)")
	(net 587 "unconnected-(U14F-P0_PTP_SYNC0-PadN39)")
	(net 588 "unconnected-(U15-NC-Pad1)")
	(net 589 "unconnected-(U20-GL-Pad10)")
	(net 590 "unconnected-(U20-GL-Pad10)_1")
	(net 591 "unconnected-(U20-GL-Pad10)_2")
	(net 592 "unconnected-(U20-P_{GOOD}-Pad14)")
	(net 593 "unconnected-(U21-STAT-Pad4)")
	(net 594 "unconnected-(Y4-NC-Pad2)")
	(net 595 "/TB Controller/PCIex4.TX3-")
	(net 596 "/TB Controller/PCIex4.TX0+")
	(net 597 "/TB Controller/PCIex4.TX0-")
	(net 598 "/TB Controller/PCIex4.TX2-")
	(net 599 "/TB Controller/PCIex4.TX1-")
	(net 600 "/TB Controller/PCIex4.TX1+")
	(net 601 "/TB Controller/PCIex4.TX3+")
	(net 602 "/TB Controller/PCIex4.TX2+")
	(footprint "antmicro-footprints:R_0402_1005Metric"
		(layer "F.Cu")
		(at 173.105 79.341)
		(descr "Resistor SMD 0402")
		(tags "resistor SMD 0402")
		(property "Reference" "R173"
			(at -1.105 1.659 0)
			(layer "F.SilkS")
			(effects
				(font
					(size 0.7 0.7)
					(thickness 0.15)
				)
				(justify left bottom)
			)
		)
		(property "Value" "R_2k_0402"
			(at -1.011843 1.772047 0)
			(layer "F.Fab")
			(effects
				(font
					(size 0.7 0.7)
					(thickness 0.15)
				)
				(justify left bottom)
			)
		)
		(property "Datasheet" "https://www.bourns.com/docs/product-datasheets/cr.pdf"
			(at 0 0 0)
			(layer "F.Fab")
			(hide yes)
			(effects
				(font
					(size 1.27 1.27)
					(thickness 0.15)
				)
			)
		)
		(property "Description" "SMD Chip Resistor, 2 kohm, ± 1%, 62.5 mW, 0402 [1005 Metric], Thick Film, General Purpose"
			(at 0 0 0)
			(layer "F.Fab")
			(hide yes)
			(effects
				(font
					(size 1.27 1.27)
					(thickness 0.15)
				)
			)
		)
		(property "MPN" "CR0402-FX-2001GLF"
			(at 0 0 0)
			(unlocked yes)
			(layer "F.Fab")
			(hide yes)
			(effects
				(font
					(size 1 1)
					(thickness 0.15)
				)
			)
		)
		(property "Manufacturer" "Bourns"
			(at 0 0 0)
			(unlocked yes)
			(layer "F.Fab")
			(hide yes)
			(effects
				(font
					(size 1 1)
					(thickness 0.15)
				)
			)
		)
		(property "License" "Apache-2.0"
			(at 0 0 0)
			(unlocked yes)
			(layer "F.Fab")
			(hide yes)
			(effects
				(font
					(size 1 1)
					(thickness 0.15)
				)
			)
		)
		(property "Author" "Antmicro"
			(at 0 0 0)
			(unlocked yes)
			(layer "F.Fab")
			(hide yes)
			(effects
				(font
					(size 1 1)
					(thickness 0.15)
				)
			)
		)
		(property "Val" "2k"
			(at 0 0 0)
			(unlocked yes)
			(layer "F.Fab")
			(hide yes)
			(effects
				(font
					(size 1 1)
					(thickness 0.15)
				)
			)
		)
		(property "Tolerance" "1%"
			(at 0 0 0)
			(unlocked yes)
			(layer "F.Fab")
			(hide yes)
			(effects
				(font
					(size 1 1)
					(thickness 0.15)
				)
			)
		)
		(sheetname "/X710-AT2 Misc/")
		(sheetfile "x710-at2-mics.kicad_sch")
		(attr smd)
		(fp_rect
			(start -0.925 -0.47)
			(end 0.925 0.47)
			(stroke
				(width 0.05)
				(type default)
			)
			(fill no)
			(layer "F.CrtYd")
		)
		(fp_rect
			(start -0.5 -0.25)
			(end 0.5 0.25)
			(stroke
				(width 0.15)
				(type solid)
			)
			(fill no)
			(layer "F.Fab")
		)
		(fp_text user "${REFERENCE}"
			(at -0.95 3.168 0)
			(layer "F.Fab")
			(effects
				(font
					(size 0.7 0.7)
					(thickness 0.15)
				)
				(justify left bottom)
			)
		)
		(fp_text user "Author: Antmicro"
			(at -0.95 4.169 0)
			(layer "F.Fab")
			(effects
				(font
					(size 0.7 0.7)
					(thickness 0.15)
				)
				(justify left bottom)
			)
		)
		(fp_text user "License: Apache-2.0"
			(at -0.95 5.169 0)
			(layer "F.Fab")
			(effects
				(font
					(size 0.7 0.7)
					(thickness 0.15)
				)
				(justify left bottom)
			)
		)
		(pad "1" smd roundrect
			(at -0.48 0)
			(size 0.59 0.64)
			(layers "F.Cu" "F.Mask" "F.Paste")
			(roundrect_rratio 0.25)
			(net 148 "/X710-AT2 Misc/MDIO.MDC")
			(pintype "passive")
		)
		(pad "2" smd roundrect
			(at 0.48 0)
			(size 0.59 0.64)
			(layers "F.Cu" "F.Mask" "F.Paste")
			(roundrect_rratio 0.25)
			(net 18 "+1V88")
			(pintype "passive")
		)
	)
	(footprint "antmicro-footprints:C_Pol_EIA-B"
		(layer "F.Cu")
		(at 137.75 57.5 90)
		(property "Reference" "C325"
			(at 2.7 1.85 90)
			(layer "F.SilkS")
			(effects
				(font
					(size 0.7 0.7)
					(thickness 0.15)
				)
				(justify left bottom)
			)
		)
		(property "Value" "C_Pol_330u_6.3V_KEMET-T520-B"
			(at 0 2.85 90)
			(layer "F.Fab")
			(effects
				(font
					(size 0.7 0.7)
					(thickness 0.15)
				)
				(justify left bottom)
			)
		)
		(property "Datasheet" "https://www.kemet.com/en/us/capacitors/product/T520B337M006ATE040.html"
			(at 0 0 90)
			(layer "F.Fab")
			(hide yes)
			(effects
				(font
					(size 1.27 1.27)
					(thickness 0.15)
				)
			)
		)
		(property "Description" "Tantalum Polymer Capacitor, KO-CAP®, 330 µF, ± 20%, 6.3 V, B, 0.04 ohm, 1411 [3528 Metric]"
			(at 0 0 90)
			(layer "F.Fab")
			(hide yes)
			(effects
				(font
					(size 1.27 1.27)
					(thickness 0.15)
				)
			)
		)
		(property "Val" "330u"
			(at 0 0 90)
			(unlocked yes)
			(layer "F.Fab")
			(hide yes)
			(effects
				(font
					(size 1 1)
					(thickness 0.15)
				)
			)
		)
		(property "MPN" "T520B337M006ATE040"
			(at 0 0 90)
			(unlocked yes)
			(layer "F.Fab")
			(hide yes)
			(effects
				(font
					(size 1 1)
					(thickness 0.15)
				)
			)
		)
		(property "Manufacturer" "KEMET"
			(at 0 0 90)
			(unlocked yes)
			(layer "F.Fab")
			(hide yes)
			(effects
				(font
					(size 1 1)
					(thickness 0.15)
				)
			)
		)
		(property "License" "Apache-2.0"
			(at 0 0 90)
			(unlocked yes)
			(layer "F.Fab")
			(hide yes)
			(effects
				(font
					(size 1 1)
					(thickness 0.15)
				)
			)
		)
		(property "Author" "Antmicro"
			(at 0 0 90)
			(unlocked yes)
			(layer "F.Fab")
			(hide yes)
			(effects
				(font
					(size 1 1)
					(thickness 0.15)
				)
			)
		)
		(property "Voltage" "6.3V"
			(at 0 0 90)
			(unlocked yes)
			(layer "F.Fab")
			(hide yes)
			(effects
				(font
					(size 1 1)
					(thickness 0.15)
				)
			)
		)
		(property "Dielectric" "template_dielectric"
			(at 0 0 90)
			(unlocked yes)
			(layer "F.Fab")
			(hide yes)
			(effects
				(font
					(size 1 1)
					(thickness 0.15)
				)
			)
		)
		(sheetname "/Power input/")
		(sheetfile "power_input.kicad_sch")
		(attr smd dnp)
		(fp_line
			(start -2.521 -1.676)
			(end -2.123 -1.676)
			(stroke
				(width 0.15)
				(type solid)
			)
			(layer "F.SilkS")
		)
		(fp_line
			(start -1.8 -1.6)
			(end 1.8 -1.6)
			(stroke
				(width 0.15)
				(type solid)
			)
			(layer "F.SilkS")
		)
		(fp_line
			(start -2.325 -1.475)
			(end -2.325 -1.878)
			(stroke
				(width 0.15)
				(type solid)
			)
			(layer "F.SilkS")
		)
		(fp_line
			(start 1.8 -1.3)
			(end 1.8 -1.6)
			(stroke
				(width 0.15)
				(type solid)
			)
			(layer "F.SilkS")
		)
		(fp_line
			(start -1.8 -1.3)
			(end -1.8 -1.6)
			(stroke
				(width 0.15)
				(type solid)
			)
			(layer "F.SilkS")
		)
		(fp_line
			(start 1.8 1.3)
			(end 1.8 1.6)
			(stroke
				(width 0.15)
				(type solid)
			)
			(layer "F.SilkS")
		)
		(fp_line
			(start -1.8 1.3)
			(end -1.8 1.6)
			(stroke
				(width 0.15)
				(type solid)
			)
			(layer "F.SilkS")
		)
		(fp_line
			(start 1.8 1.6)
			(end -1.8 1.6)
			(stroke
				(width 0.15)
				(type solid)
			)
			(layer "F.SilkS")
		)
		(fp_line
			(start 1.959 -1.75)
			(end -1.97 -1.75)
			(stroke
				(width 0.05)
				(type solid)
			)
			(layer "F.CrtYd")
		)
		(fp_line
			(start 1.959 -1.75)
			(end 1.959 -1.35)
			(stroke
				(width 0.05)
				(type solid)
			)
			(layer "F.CrtYd")
		)
		(fp_line
			(start -1.97 -1.75)
			(end -1.97 -1.35)
			(stroke
				(width 0.05)
				(type solid)
			)
			(layer "F.CrtYd")
		)
		(fp_line
			(start 2.399 -1.35)
			(end 1.959 -1.35)
			(stroke
				(width 0.05)
				(type solid)
			)
			(layer "F.CrtYd")
		)
		(fp_line
			(start 2.399 -1.35)
			(end 2.4 1.35)
			(stroke
				(width 0.05)
				(type solid)
			)
			(layer "F.CrtYd")
		)
		(fp_line
			(start -1.97 -1.35)
			(end -2.41 -1.35)
			(stroke
				(width 0.05)
				(type solid)
			)
			(layer "F.CrtYd")
		)
		(fp_line
			(start -2.411 -1.35)
			(end -2.41 1.35)
			(stroke
				(width 0.05)
				(type solid)
			)
			(layer "F.CrtYd")
		)
		(fp_line
			(start 2.4 1.35)
			(end 1.96 1.35)
			(stroke
				(width 0.05)
				(type solid)
			)
			(layer "F.CrtYd")
		)
		(fp_line
			(start 1.96 1.35)
			(end 1.96 1.75)
			(stroke
				(width 0.05)
				(type solid)
			)
			(layer "F.CrtYd")
		)
		(fp_line
			(start -1.97 1.35)
			(end -2.41 1.35)
			(stroke
				(width 0.05)
				(type solid)
			)
			(layer "F.CrtYd")
		)
		(fp_line
			(start -1.97 1.35)
			(end -1.97 1.75)
			(stroke
				(width 0.05)
				(type solid)
			)
			(layer "F.CrtYd")
		)
		(fp_line
			(start 1.96 1.75)
			(end -1.97 1.75)
			(stroke
				(width 0.05)
				(type solid)
			)
			(layer "F.CrtYd")
		)
		(fp_line
			(start -1.7 1.324)
			(end -1.551 1.475)
			(stroke
				(width 0.15)
				(type solid)
			)
			(layer "F.Fab")
		)
		(fp_rect
			(start -1.72 -1.5)
			(end 1.719 1.499)
			(stroke
				(width 0.15)
				(type solid)
			)
			(fill no)
			(layer "F.Fab")
		)
		(fp_text user "License: Apache-2.0"
			(at -2.665 5.65 90)
			(layer "F.Fab")
			(effects
				(font
					(size 0.7 0.7)
					(thickness 0.15)
				)
				(justify left bottom)
			)
		)
		(fp_text user "${REFERENCE}"
			(at -2.665 4.45 90)
			(layer "F.Fab")
			(effects
				(font
					(size 0.7 0.7)
					(thickness 0.15)
				)
				(justify left bottom)
			)
		)
		(fp_text user "Author: Antmicro"
			(at -2.665 6.85 90)
			(layer "F.Fab")
			(effects
				(font
					(size 0.7 0.7)
					(thickness 0.15)
				)
				(justify left bottom)
			)
		)
		(pad "1" smd roundrect
			(at -1.551 0 90)
			(size 1.2 2.2)
			(layers "F.Cu" "F.Mask" "F.Paste")
			(roundrect_rratio 0.1)
			(net 40 "+5V")
			(pintype "passive")
		)
		(pad "2" smd roundrect
			(at 1.55 0 90)
			(size 1.2 2.2)
			(layers "F.Cu" "F.Mask" "F.Paste")
			(roundrect_rratio 0.1)
			(net 23 "GND")
			(pintype "passive")
		)
	)
	(footprint "antmicro-footprints:R_0402_1005Metric"
		(layer "F.Cu")
		(at 119.25 66.5 180)
		(descr "Resistor SMD 0402")
		(tags "resistor SMD 0402")
		(property "Reference" "R134"
			(at -3.45 -1.4 180)
			(layer "F.SilkS")
			(effects
				(font
					(size 0.7 0.7)
					(thickness 0.15)
				)
				(justify left bottom)
			)
		)
		(property "Value" "R_10k_0402"
			(at -1.011843 1.772047 180)
			(layer "F.Fab")
			(effects
				(font
					(size 0.7 0.7)
					(thickness 0.15)
				)
				(justify left bottom)
			)
		)
		(property "Datasheet" "https://www.bourns.com/docs/product-datasheets/cr.pdf"
			(at 0 0 180)
			(layer "F.Fab")
			(hide yes)
			(effects
				(font
					(size 1.27 1.27)
					(thickness 0.15)
				)
			)
		)
		(property "Description" "SMD Chip Resistor, 10 kohm, ± 1%, 62.5 mW, 0402 [1005 Metric], Thick Film, General Purpose"
			(at 0 0 180)
			(layer "F.Fab")
			(hide yes)
			(effects
				(font
					(size 1.27 1.27)
					(thickness 0.15)
				)
			)
		)
		(property "MPN" "CR0402-FX-1002GLF"
			(at 0 0 180)
			(unlocked yes)
			(layer "F.Fab")
			(hide yes)
			(effects
				(font
					(size 1 1)
					(thickness 0.15)
				)
			)
		)
		(property "Manufacturer" "Bourns"
			(at 0 0 180)
			(unlocked yes)
			(layer "F.Fab")
			(hide yes)
			(effects
				(font
					(size 1 1)
					(thickness 0.15)
				)
			)
		)
		(property "License" "Apache-2.0"
			(at 0 0 180)
			(unlocked yes)
			(layer "F.Fab")
			(hide yes)
			(effects
				(font
					(size 1 1)
					(thickness 0.15)
				)
			)
		)
		(property "Author" "Antmicro"
			(at 0 0 180)
			(unlocked yes)
			(layer "F.Fab")
			(hide yes)
			(effects
				(font
					(size 1 1)
					(thickness 0.15)
				)
			)
		)
		(property "Val" "10k"
			(at 0 0 180)
			(unlocked yes)
			(layer "F.Fab")
			(hide yes)
			(effects
				(font
					(size 1 1)
					(thickness 0.15)
				)
			)
		)
		(property "Tolerance" "1%"
			(at 0 0 180)
			(unlocked yes)
			(layer "F.Fab")
			(hide yes)
			(effects
				(font
					(size 1 1)
					(thickness 0.15)
				)
			)
		)
		(sheetname "/X710-AT2 RSVD/")
		(sheetfile "x710-at2-rsvd.kicad_sch")
		(attr smd)
		(fp_rect
			(start -0.925 -0.47)
			(end 0.925 0.47)
			(stroke
				(width 0.05)
				(type default)
			)
			(fill no)
			(layer "F.CrtYd")
		)
		(fp_rect
			(start -0.5 -0.25)
			(end 0.5 0.25)
			(stroke
				(width 0.15)
				(type solid)
			)
			(fill no)
			(layer "F.Fab")
		)
		(fp_text user "${REFERENCE}"
			(at -0.95 3.168 180)
			(layer "F.Fab")
			(effects
				(font
					(size 0.7 0.7)
					(thickness 0.15)
				)
				(justify left bottom)
			)
		)
		(fp_text user "Author: Antmicro"
			(at -0.95 4.169 180)
			(layer "F.Fab")
			(effects
				(font
					(size 0.7 0.7)
					(thickness 0.15)
				)
				(justify left bottom)
			)
		)
		(fp_text user "License: Apache-2.0"
			(at -0.95 5.169 180)
			(layer "F.Fab")
			(effects
				(font
					(size 0.7 0.7)
					(thickness 0.15)
				)
				(justify left bottom)
			)
		)
		(pad "1" smd roundrect
			(at -0.48 0 180)
			(size 0.59 0.64)
			(layers "F.Cu" "F.Mask" "F.Paste")
			(roundrect_rratio 0.25)
			(net 23 "GND")
			(pintype "passive")
		)
		(pad "2" smd roundrect
			(at 0.48 0 180)
			(size 0.59 0.64)
			(layers "F.Cu" "F.Mask" "F.Paste")
			(roundrect_rratio 0.25)
			(net 90 "/X710-AT2 RSVD/DEBUG_W7")
			(pintype "passive")
		)
	)
	(footprint "antmicro-footprints:JHL6340SLLSQ"
		(layer "F.Cu")
		(at 128.5 123.95 180)
		(property "Reference" "U4"
			(at 4.9 6.15 0)
			(unlocked yes)
			(layer "F.SilkS")
			(effects
				(font
					(size 0.7 0.7)
					(thickness 0.15)
				)
			)
		)
		(property "Value" "JHL6340SLLSQ"
			(at 0 6.4 180)
			(unlocked yes)
			(layer "F.Fab")
			(effects
				(font
					(size 0.7 0.7)
					(thickness 0.15)
				)
			)
		)
		(property "Datasheet" "https://www.thunderbolttechnology.net/sites/default/files/18-241_ThunderboltController_Brief_HI.pdf"
			(at 0 0 180)
			(layer "F.Fab")
			(hide yes)
			(effects
				(font
					(size 1.27 1.27)
					(thickness 0.15)
				)
			)
		)
		(property "Description" "Thunderbolt™ 3 Controller, I/O"
			(at 0 0 180)
			(layer "F.Fab")
			(hide yes)
			(effects
				(font
					(size 1.27 1.27)
					(thickness 0.15)
				)
			)
		)
		(property "Manufacturer" "Intel"
			(at 0 0 180)
			(unlocked yes)
			(layer "F.Fab")
			(hide yes)
			(effects
				(font
					(size 1 1)
					(thickness 0.15)
				)
			)
		)
		(property "MPN" "JHL6340SLLSQ"
			(at 0 0 180)
			(unlocked yes)
			(layer "F.Fab")
			(hide yes)
			(effects
				(font
					(size 1 1)
					(thickness 0.15)
				)
			)
		)
		(property "Author" "Antmicro"
			(at 0 0 180)
			(unlocked yes)
			(layer "F.Fab")
			(hide yes)
			(effects
				(font
					(size 1 1)
					(thickness 0.15)
				)
			)
		)
		(property "License" "Apache-2.0"
			(at 0 0 180)
			(unlocked yes)
			(layer "F.Fab")
			(hide yes)
			(effects
				(font
					(size 1 1)
					(thickness 0.15)
				)
			)
		)
		(sheetname "/TB Controller/")
		(sheetfile "tb.kicad_sch")
		(attr smd)
		(fp_line
			(start 5.35 -5.35)
			(end 5.35 5.35)
			(stroke
				(width 0.1)
				(type solid)
			)
			(layer "F.SilkS")
		)
		(fp_line
			(start 5.35 -5.35)
			(end -5.35 -5.35)
			(stroke
				(width 0.1)
				(type solid)
			)
			(layer "F.SilkS")
		)
		(fp_line
			(start -5.35 5.35)
			(end 5.35 5.35)
			(stroke
				(width 0.1)
				(type solid)
			)
			(layer "F.SilkS")
		)
		(fp_line
			(start -5.35 5.35)
			(end -5.35 -5.35)
			(stroke
				(width 0.1)
				(type solid)
			)
			(layer "F.SilkS")
		)
		(fp_circle
			(center -5.7 -5.7)
			(end -5.6 -5.7)
			(stroke
				(width 0.2)
				(type solid)
			)
			(fill no)
			(layer "F.SilkS")
		)
		(fp_rect
			(start -5.6 -5.6)
			(end 5.6 5.6)
			(stroke
				(width 0.05)
				(type solid)
			)
			(fill no)
			(layer "F.CrtYd")
		)
		(fp_line
			(start 5.35 5.35)
			(end -5.35 5.35)
			(stroke
				(width 0.15)
				(type solid)
			)
			(layer "F.Fab")
		)
		(fp_line
			(start 5.35 -5.35)
			(end 5.35 5.35)
			(stroke
				(width 0.15)
				(type solid)
			)
			(layer "F.Fab")
		)
		(fp_line
			(start -4.35 -5.35)
			(end 5.35 -5.35)
			(stroke
				(width 0.15)
				(type solid)
			)
			(layer "F.Fab")
		)
		(fp_line
			(start -4.35 -5.35)
			(end -5.35 -4.35)
			(stroke
				(width 0.15)
				(type solid)
			)
			(layer "F.Fab")
		)
		(fp_line
			(start -5.35 5.35)
			(end -5.35 -4.35)
			(stroke
				(width 0.15)
				(type solid)
			)
			(layer "F.Fab")
		)
		(fp_text user "${REFERENCE}"
			(at 0 7.8 180)
			(unlocked yes)
			(layer "F.Fab")
			(effects
				(font
					(size 0.7 0.7)
					(thickness 0.15)
				)
			)
		)
		(fp_text user "License: Apache-2.0"
			(at 0 10.45 180)
			(layer "F.Fab")
			(effects
				(font
					(size 0.7 0.7)
					(thickness 0.15)
				)
			)
		)
		(fp_text user "Author: Antmicro"
			(at 0.05 9 180)
			(layer "F.Fab")
			(effects
				(font
					(size 0.7 0.7)
					(thickness 0.15)
				)
			)
		)
		(pad "A1" smd circle
			(at -5.06 -5.06 180)
			(size 0.254 0.254)
			(layers "F.Cu" "F.Mask" "F.Paste")
			(net 23 "GND")
			(pinfunction "SVR_VSS")
			(pintype "power_in")
		)
		(pad "A2" smd oval
			(at -4.6 -5.06 180)
			(size 0.1578 0.3302)
			(layers "F.Cu" "F.Mask" "F.Paste")
			(net 57 "+3V3_TB")
			(pinfunction "VCC3P3_SVR")
			(pintype "power_in")
		)
		(pad "A3" smd oval
			(at -4.14 -5.06 180)
			(size 0.1578 0.3302)
			(layers "F.Cu" "F.Mask" "F.Paste")
			(net 57 "+3V3_TB")
			(pinfunction "VCC3P3_SVR")
			(pintype "passive")
		)
		(pad "A4" smd oval
			(at -3.68 -5.06 180)
			(size 0.1578 0.3302)
			(layers "F.Cu" "F.Mask" "F.Paste")
			(net 376 "/PD and TB DC-DC/LSX_1.LSX_P2R")
			(pinfunction "PA_LSRX")
			(pintype "input")
		)
		(pad "A5" smd oval
			(at -3.22 -5.06 180)
			(size 0.1578 0.3302)
			(layers "F.Cu" "F.Mask" "F.Paste")
			(net 383 "/PD and TB DC-DC/LSX_1.LSX_R2P")
			(pinfunction "PA_LSTX")
			(pintype "output")
		)
		(pad "A6" smd oval
			(at -2.76 -5.06 180)
			(size 0.1578 0.3302)
			(layers "F.Cu" "F.Mask" "F.Paste")
			(net 23 "GND")
			(pinfunction "VSS_ANA")
			(pintype "passive")
		)
		(pad "A7" smd oval
			(at -2.3 -5.06 180)
			(size 0.1578 0.3302)
			(layers "F.Cu" "F.Mask" "F.Paste")
			(net 242 "unconnected-(U4E-PB_RX1_N-PadA7)")
			(pinfunction "PB_RX1_N")
			(pintype "input+no_connect")
		)
		(pad "A8" smd oval
			(at -1.84 -5.06 180)
			(size 0.1578 0.3302)
			(layers "F.Cu" "F.Mask" "F.Paste")
			(net 23 "GND")
			(pinfunction "VSS_ANA")
			(pintype "passive")
		)
		(pad "A9" smd oval
			(at -1.38 -5.06 180)
			(size 0.1578 0.3302)
			(layers "F.Cu" "F.Mask" "F.Paste")
			(net 243 "unconnected-(U4E-PB_TX1_P-PadA9)")
			(pinfunction "PB_TX1_P")
			(pintype "output+no_connect")
		)
		(pad "A10" smd oval
			(at -0.92 -5.06 180)
			(size 0.1578 0.3302)
			(layers "F.Cu" "F.Mask" "F.Paste")
			(net 23 "GND")
			(pinfunction "VSS_ANA")
			(pintype "passive")
		)
		(pad "A11" smd oval
			(at -0.46 -5.06 180)
			(size 0.1578 0.3302)
			(layers "F.Cu" "F.Mask" "F.Paste")
			(net 244 "unconnected-(U4E-PB_TX0_P-PadA11)")
			(pinfunction "PB_TX0_P")
			(pintype "output+no_connect")
		)
		(pad "A12" smd oval
			(at 0 -5.06 180)
			(size 0.1578 0.3302)
			(layers "F.Cu" "F.Mask" "F.Paste")
			(net 23 "GND")
			(pinfunction "VSS_ANA")
			(pintype "passive")
		)
		(pad "A13" smd oval
			(at 0.46 -5.06 180)
			(size 0.1578 0.3302)
			(layers "F.Cu" "F.Mask" "F.Paste")
			(net 245 "unconnected-(U4E-PB_RX0_P-PadA13)")
			(pinfunction "PB_RX0_P")
			(pintype "input+no_connect")
		)
		(pad "A14" smd oval
			(at 0.92 -5.06 180)
			(size 0.1578 0.3302)
			(layers "F.Cu" "F.Mask" "F.Paste")
			(net 23 "GND")
			(pinfunction "VSS_ANA")
			(pintype "passive")
		)
		(pad "A15" smd oval
			(at 1.38 -5.06 180)
			(size 0.1578 0.3302)
			(layers "F.Cu" "F.Mask" "F.Paste")
			(net 362 "/PD and TB DC-DC/USB3.RX1_P")
			(pinfunction "PA_RX1_P")
			(pintype "input")
		)
		(pad "A16" smd oval
			(at 1.84 -5.06 180)
			(size 0.1578 0.3302)
			(layers "F.Cu" "F.Mask" "F.Paste")
			(net 23 "GND")
			(pinfunction "VSS_ANA")
			(pintype "passive")
		)
		(pad "A17" smd oval
			(at 2.3 -5.06 180)
			(size 0.1578 0.3302)
			(layers "F.Cu" "F.Mask" "F.Paste")
			(net 168 "/TB Controller/PA_TX1_P")
			(pinfunction "PA_TX1_P")
			(pintype "output")
		)
		(pad "A18" smd oval
			(at 2.76 -5.06 180)
			(size 0.1578 0.3302)
			(layers "F.Cu" "F.Mask" "F.Paste")
			(net 23 "GND")
			(pinfunction "VSS_ANA")
			(pintype "passive")
		)
		(pad "A19" smd oval
			(at 3.22 -5.06 180)
			(size 0.1578 0.3302)
			(layers "F.Cu" "F.Mask" "F.Paste")
			(net 167 "/TB Controller/PA_TX0_P")
			(pinfunction "PA_TX0_P")
			(pintype "output")
		)
		(pad "A20" smd oval
			(at 3.68 -5.06 180)
			(size 0.1578 0.3302)
			(layers "F.Cu" "F.Mask" "F.Paste")
			(net 23 "GND")
			(pinfunction "VSS_ANA")
			(pintype "passive")
		)
		(pad "A21" smd oval
			(at 4.14 -5.06 180)
			(size 0.1578 0.3302)
			(layers "F.Cu" "F.Mask" "F.Paste")
			(net 363 "/PD and TB DC-DC/USB3.RX0_N")
			(pinfunction "PA_RX0_N")
			(pintype "input")
		)
		(pad "A22" smd oval
			(at 4.6 -5.06 180)
			(size 0.1578 0.3302)
			(layers "F.Cu" "F.Mask" "F.Paste")
			(net 23 "GND")
			(pinfunction "VSS_ANA")
			(pintype "passive")
		)
		(pad "A23" smd circle
			(at 5.06 -5.06 180)
			(size 0.254 0.254)
			(layers "F.Cu" "F.Mask" "F.Paste")
			(net 246 "unconnected-(U4F-ATEST_P-PadA23)")
			(pinfunction "ATEST_P")
			(pintype "passive+no_connect")
		)
		(pad "AA1" smd oval
			(at -5.06 4.14 270)
			(size 0.1578 0.3302)
			(layers "F.Cu" "F.Mask" "F.Paste")
			(net 191 "Net-(U4C-GPIO_8)")
			(pinfunction "GPIO_8")
			(pintype "bidirectional")
		)
		(pad "AA2" smd circle
			(at -4.6 4.14 180)
			(size 0.254 0.254)
			(layers "F.Cu" "F.Mask" "F.Paste")
			(net 217 "Net-(U4C-DPSNK0_HPD)")
			(pinfunction "DPSNK0_HPD")
			(pintype "passive")
		)
		(pad "AA22" smd circle
			(at 4.6 4.14 180)
			(size 0.254 0.254)
			(layers "F.Cu" "F.Mask" "F.Paste")
			(net 23 "GND")
			(pinfunction "VSS_ANA")
			(pintype "passive")
		)
		(pad "AA23" smd oval
			(at 5.06 4.14 270)
			(size 0.1578 0.3302)
			(layers "F.Cu" "F.Mask" "F.Paste")
			(net 23 "GND")
			(pinfunction "VSS_ANA")
			(pintype "passive")
		)
		(pad "AB1" smd oval
			(at -5.06 4.6 270)
			(size 0.1578 0.3302)
			(layers "F.Cu" "F.Mask" "F.Paste")
			(net 23 "GND")
			(pinfunction "VSS")
			(pintype "passive")
		)
		(pad "AB2" smd circle
			(at -4.6 4.6 180)
			(size 0.254 0.254)
			(layers "F.Cu" "F.Mask" "F.Paste")
			(net 23 "GND")
			(pinfunction "MONDC_DPSRC")
			(pintype "passive")
		)
		(pad "AB3" smd circle
			(at -4.14 4.6 180)
			(size 0.254 0.254)
			(layers "F.Cu" "F.Mask" "F.Paste")
			(net 398 "/PD and TB DC-DC/TB_FLASH.MOSI")
			(pinfunction "EE_DI")
			(pintype "output")
		)
		(pad "AB4" smd circle
			(at -3.68 4.6 180)
			(size 0.254 0.254)
			(layers "F.Cu" "F.Mask" "F.Paste")
			(net 397 "/PD and TB DC-DC/TB_FLASH.CLK")
			(pinfunction "EE_CLK")
			(pintype "output")
		)
		(pad "AB5" smd circle
			(at -3.22 4.6 180)
			(size 0.254 0.254)
			(layers "F.Cu" "F.Mask" "F.Paste")
			(net 238 "Net-(U4D-TEST_PWR_GOOD)")
			(pinfunction "TEST_PWR_GOOD")
			(pintype "input")
		)
		(pad "AB6" smd circle
			(at -2.76 4.6 180)
			(size 0.254 0.254)
			(layers "F.Cu" "F.Mask" "F.Paste")
			(net 23 "GND")
			(pinfunction "VSS_ANA")
			(pintype "passive")
		)
		(pad "AB7" smd circle
			(at -2.3 4.6 180)
			(size 0.254 0.254)
			(layers "F.Cu" "F.Mask" "F.Paste")
			(net 247 "unconnected-(U4C-DPSNK0_ML0_P-PadAB7)")
			(pinfunction "DPSNK0_ML0_P")
			(pintype "input+no_connect")
		)
		(pad "AB8" smd circle
			(at -1.84 4.6 180)
			(size 0.254 0.254)
			(layers "F.Cu" "F.Mask" "F.Paste")
			(net 23 "GND")
			(pinfunction "VSS_ANA")
			(pintype "passive")
		)
		(pad "AB9" smd circle
			(at -1.38 4.6 180)
			(size 0.254 0.254)
			(layers "F.Cu" "F.Mask" "F.Paste")
			(net 248 "unconnected-(U4C-DPSNK0_ML1_P-PadAB9)")
			(pinfunction "DPSNK0_ML1_P")
			(pintype "input+no_connect")
		)
		(pad "AB10" smd circle
			(at -0.92 4.6 180)
			(size 0.254 0.254)
			(layers "F.Cu" "F.Mask" "F.Paste")
			(net 23 "GND")
			(pinfunction "VSS_ANA")
			(pintype "passive")
		)
		(pad "AB11" smd circle
			(at -0.46 4.6 180)
			(size 0.254 0.254)
			(layers "F.Cu" "F.Mask" "F.Paste")
			(net 249 "unconnected-(U4C-DPSNK0_ML2_P-PadAB11)")
			(pinfunction "DPSNK0_ML2_P")
			(pintype "input+no_connect")
		)
		(pad "AB12" smd circle
			(at 0 4.6 180)
			(size 0.254 0.254)
			(layers "F.Cu" "F.Mask" "F.Paste")
			(net 23 "GND")
			(pinfunction "VSS_ANA")
			(pintype "passive")
		)
		(pad "AB13" smd circle
			(at 0.46 4.6 180)
			(size 0.254 0.254)
			(layers "F.Cu" "F.Mask" "F.Paste")
			(net 250 "unconnected-(U4C-DPSNK0_ML3_P-PadAB13)")
			(pinfunction "DPSNK0_ML3_P")
			(pintype "input+no_connect")
		)
		(pad "AB14" smd circle
			(at 0.92 4.6 180)
			(size 0.254 0.254)
			(layers "F.Cu" "F.Mask" "F.Paste")
			(net 23 "GND")
			(pinfunction "VSS_ANA")
			(pintype "passive")
		)
		(pad "AB15" smd circle
			(at 1.38 4.6 180)
			(size 0.254 0.254)
			(layers "F.Cu" "F.Mask" "F.Paste")
			(net 251 "unconnected-(U4C-DPSNK1_ML0_P-PadAB15)")
			(pinfunction "DPSNK1_ML0_P")
			(pintype "input+no_connect")
		)
		(pad "AB16" smd circle
			(at 1.84 4.6 180)
			(size 0.254 0.254)
			(layers "F.Cu" "F.Mask" "F.Paste")
			(net 23 "GND")
			(pinfunction "VSS_ANA")
			(pintype "passive")
		)
		(pad "AB17" smd circle
			(at 2.3 4.6 180)
			(size 0.254 0.254)
			(layers "F.Cu" "F.Mask" "F.Paste")
			(net 252 "unconnected-(U4C-DPSNK1_ML1_P-PadAB17)")
			(pinfunction "DPSNK1_ML1_P")
			(pintype "input+no_connect")
		)
		(pad "AB18" smd circle
			(at 2.76 4.6 180)
			(size 0.254 0.254)
			(layers "F.Cu" "F.Mask" "F.Paste")
			(net 23 "GND")
			(pinfunction "VSS_ANA")
			(pintype "passive")
		)
		(pad "AB19" smd circle
			(at 3.22 4.6 180)
			(size 0.254 0.254)
			(layers "F.Cu" "F.Mask" "F.Paste")
			(net 253 "unconnected-(U4C-DPSNK1_ML2_P-PadAB19)")
			(pinfunction "DPSNK1_ML2_P")
			(pintype "input+no_connect")
		)
		(pad "AB20" smd circle
			(at 3.68 4.6 180)
			(size 0.254 0.254)
			(layers "F.Cu" "F.Mask" "F.Paste")
			(net 23 "GND")
			(pinfunction "VSS_ANA")
			(pintype "passive")
		)
		(pad "AB21" smd circle
			(at 4.14 4.6 180)
			(size 0.254 0.254)
			(layers "F.Cu" "F.Mask" "F.Paste")
			(net 254 "unconnected-(U4C-DPSNK1_ML3_P-PadAB21)")
			(pinfunction "DPSNK1_ML3_P")
			(pintype "input+no_connect")
		)
		(pad "AB22" smd circle
			(at 4.6 4.6 180)
			(size 0.254 0.254)
			(layers "F.Cu" "F.Mask" "F.Paste")
			(net 23 "GND")
			(pinfunction "VSS_ANA")
			(pintype "passive")
		)
		(pad "AB23" smd oval
			(at 5.06 4.6 270)
			(size 0.1578 0.3302)
			(layers "F.Cu" "F.Mask" "F.Paste")
			(net 255 "unconnected-(U4F-THERMDA2-PadAB23)")
			(pinfunction "THERMDA2")
			(pintype "passive+no_connect")
		)
		(pad "AC1" smd circle
			(at -5.06 5.06 180)
			(size 0.254 0.254)
			(layers "F.Cu" "F.Mask" "F.Paste")
			(net 23 "GND")
			(pinfunction "TEST_EDM")
			(pintype "passive")
		)
		(pad "AC2" smd oval
			(at -4.6 5.06 180)
			(size 0.1578 0.3302)
			(layers "F.Cu" "F.Mask" "F.Paste")
			(net 23 "GND")
			(pinfunction "VSS")
			(pintype "passive")
		)
		(pad "AC3" smd oval
			(at -4.14 5.06 180)
			(size 0.1578 0.3302)
			(layers "F.Cu" "F.Mask" "F.Paste")
			(net 359 "/PD and TB DC-DC/TB_FLASH.~{CE}")
			(pinfunction "EE_CS_N")
			(pintype "output")
		)
		(pad "AC4" smd oval
			(at -3.68 5.06 180)
			(size 0.1578 0.3302)
			(layers "F.Cu" "F.Mask" "F.Paste")
			(net 357 "/PD and TB DC-DC/TB_FLASH.MISO")
			(pinfunction "EE_D0")
			(pintype "input")
		)
		(pad "AC5" smd oval
			(at -3.22 5.06 180)
			(size 0.1578 0.3302)
			(layers "F.Cu" "F.Mask" "F.Paste")
			(net 216 "Net-(U4B-PCIE_CLKREQ_N)")
			(pinfunction "PCIE_CLKREQ_N")
			(pintype "output")
		)
		(pad "AC6" smd oval
			(at -2.76 5.06 180)
			(size 0.1578 0.3302)
			(layers "F.Cu" "F.Mask" "F.Paste")
			(net 23 "GND")
			(pinfunction "VSS_ANA")
			(pintype "passive")
		)
		(pad "AC7" smd oval
			(at -2.3 5.06 180)
			(size 0.1578 0.3302)
			(layers "F.Cu" "F.Mask" "F.Paste")
			(net 256 "unconnected-(U4C-DPSNK0_ML0_N-PadAC7)")
			(pinfunction "DPSNK0_ML0_N")
			(pintype "input+no_connect")
		)
		(pad "AC8" smd oval
			(at -1.84 5.06 180)
			(size 0.1578 0.3302)
			(layers "F.Cu" "F.Mask" "F.Paste")
			(net 23 "GND")
			(pinfunction "VSS_ANA")
			(pintype "passive")
		)
		(pad "AC9" smd oval
			(at -1.38 5.06 180)
			(size 0.1578 0.3302)
			(layers "F.Cu" "F.Mask" "F.Paste")
			(net 257 "unconnected-(U4C-DPSNK0_ML1_N-PadAC9)")
			(pinfunction "DPSNK0_ML1_N")
			(pintype "input+no_connect")
		)
		(pad "AC10" smd oval
			(at -0.92 5.06 180)
			(size 0.1578 0.3302)
			(layers "F.Cu" "F.Mask" "F.Paste")
			(net 23 "GND")
			(pinfunction "VSS_ANA")
			(pintype "passive")
		)
		(pad "AC11" smd oval
			(at -0.46 5.06 180)
			(size 0.1578 0.3302)
			(layers "F.Cu" "F.Mask" "F.Paste")
			(net 258 "unconnected-(U4C-DPSNK0_ML2_N-PadAC11)")
			(pinfunction "DPSNK0_ML2_N")
			(pintype "input+no_connect")
		)
		(pad "AC12" smd oval
			(at 0 5.06 180)
			(size 0.1578 0.3302)
			(layers "F.Cu" "F.Mask" "F.Paste")
			(net 23 "GND")
			(pinfunction "VSS_ANA")
			(pintype "passive")
		)
		(pad "AC13" smd oval
			(at 0.46 5.06 180)
			(size 0.1578 0.3302)
			(layers "F.Cu" "F.Mask" "F.Paste")
			(net 259 "unconnected-(U4C-DPSNK0_ML3_N-PadAC13)")
			(pinfunction "DPSNK0_ML3_N")
			(pintype "input+no_connect")
		)
		(pad "AC14" smd oval
			(at 0.92 5.06 180)
			(size 0.1578 0.3302)
			(layers "F.Cu" "F.Mask" "F.Paste")
			(net 23 "GND")
			(pinfunction "VSS_ANA")
			(pintype "passive")
		)
		(pad "AC15" smd oval
			(at 1.38 5.06 180)
			(size 0.1578 0.3302)
			(layers "F.Cu" "F.Mask" "F.Paste")
			(net 260 "unconnected-(U4C-DPSNK1_ML0_N-PadAC15)")
			(pinfunction "DPSNK1_ML0_N")
			(pintype "input+no_connect")
		)
		(pad "AC16" smd oval
			(at 1.84 5.06 180)
			(size 0.1578 0.3302)
			(layers "F.Cu" "F.Mask" "F.Paste")
			(net 23 "GND")
			(pinfunction "VSS_ANA")
			(pintype "passive")
		)
		(pad "AC17" smd oval
			(at 2.3 5.06 180)
			(size 0.1578 0.3302)
			(layers "F.Cu" "F.Mask" "F.Paste")
			(net 261 "unconnected-(U4C-DPSNK1_ML1_N-PadAC17)")
			(pinfunction "DPSNK1_ML1_N")
			(pintype "input+no_connect")
		)
		(pad "AC18" smd oval
			(at 2.76 5.06 180)
			(size 0.1578 0.3302)
			(layers "F.Cu" "F.Mask" "F.Paste")
			(net 23 "GND")
			(pinfunction "VSS_ANA")
			(pintype "passive")
		)
		(pad "AC19" smd oval
			(at 3.22 5.06 180)
			(size 0.1578 0.3302)
			(layers "F.Cu" "F.Mask" "F.Paste")
			(net 262 "unconnected-(U4C-DPSNK1_ML2_N-PadAC19)")
			(pinfunction "DPSNK1_ML2_N")
			(pintype "input+no_connect")
		)
		(pad "AC20" smd oval
			(at 3.68 5.06 180)
			(size 0.1578 0.3302)
			(layers "F.Cu" "F.Mask" "F.Paste")
			(net 23 "GND")
			(pinfunction "VSS_ANA")
			(pintype "passive")
		)
		(pad "AC21" smd oval
			(at 4.14 5.06 180)
			(size 0.1578 0.3302)
			(layers "F.Cu" "F.Mask" "F.Paste")
			(net 263 "unconnected-(U4C-DPSNK1_ML3_N-PadAC21)")
			(pinfunction "DPSNK1_ML3_N")
			(pintype "input+no_connect")
		)
		(pad "AC22" smd oval
			(at 4.6 5.06 180)
			(size 0.1578 0.3302)
			(layers "F.Cu" "F.Mask" "F.Paste")
			(net 23 "GND")
			(pinfunction "VSS_ANA")
			(pintype "passive")
		)
		(pad "AC23" smd circle
			(at 5.06 5.06 180)
			(size 0.254 0.254)
			(layers "F.Cu" "F.Mask" "F.Paste")
			(net 264 "unconnected-(U4F-THERMDA1-PadAC23)")
			(pinfunction "THERMDA1")
			(pintype "passive+no_connect")
		)
		(pad "B1" smd oval
			(at -5.06 -4.6 270)
			(size 0.1578 0.3302)
			(layers "F.Cu" "F.Mask" "F.Paste")
			(net 23 "GND")
			(pinfunction "SVR_VSS")
			(pintype "passive")
		)
		(pad "B2" smd circle
			(at -4.6 -4.6 180)
			(size 0.254 0.254)
			(layers "F.Cu" "F.Mask" "F.Paste")
			(net 23 "GND")
			(pinfunction "SVR_VSS")
			(pintype "passive")
		)
		(pad "B3" smd circle
			(at -4.14 -4.6 180)
			(size 0.254 0.254)
			(layers "F.Cu" "F.Mask" "F.Paste")
			(net 57 "+3V3_TB")
			(pinfunction "VCC3P3_SVR")
			(pintype "passive")
		)
		(pad "B4" smd circle
			(at -3.68 -4.6 180)
			(size 0.254 0.254)
			(layers "F.Cu" "F.Mask" "F.Paste")
			(net 231 "Net-(U4E-PB_LSTX)")
			(pinfunction "PB_LSTX")
			(pintype "output")
		)
		(pad "B5" smd circle
			(at -3.22 -4.6 180)
			(size 0.254 0.254)
			(layers "F.Cu" "F.Mask" "F.Paste")
			(net 232 "Net-(U4E-PB_LSRX)")
			(pinfunction "PB_LSRX")
			(pintype "input")
		)
		(pad "B6" smd circle
			(at -2.76 -4.6 180)
			(size 0.254 0.254)
			(layers "F.Cu" "F.Mask" "F.Paste")
			(net 23 "GND")
			(pinfunction "VSS_ANA")
			(pintype "passive")
		)
		(pad "B7" smd circle
			(at -2.3 -4.6 180)
			(size 0.254 0.254)
			(layers "F.Cu" "F.Mask" "F.Paste")
			(net 265 "unconnected-(U4E-PB_RX1_P-PadB7)")
			(pinfunction "PB_RX1_P")
			(pintype "input+no_connect")
		)
		(pad "B8" smd circle
			(at -1.84 -4.6 180)
			(size 0.254 0.254)
			(layers "F.Cu" "F.Mask" "F.Paste")
			(net 23 "GND")
			(pinfunction "VSS_ANA")
			(pintype "passive")
		)
		(pad "B9" smd circle
			(at -1.38 -4.6 180)
			(size 0.254 0.254)
			(layers "F.Cu" "F.Mask" "F.Paste")
			(net 266 "unconnected-(U4E-PB_TX1_N-PadB9)")
			(pinfunction "PB_TX1_N")
			(pintype "output+no_connect")
		)
		(pad "B10" smd circle
			(at -0.92 -4.6 180)
			(size 0.254 0.254)
			(layers "F.Cu" "F.Mask" "F.Paste")
			(net 23 "GND")
			(pinfunction "VSS_ANA")
			(pintype "passive")
		)
		(pad "B11" smd circle
			(at -0.46 -4.6 180)
			(size 0.254 0.254)
			(layers "F.Cu" "F.Mask" "F.Paste")
			(net 267 "unconnected-(U4E-PB_TX0_N-PadB11)")
			(pinfunction "PB_TX0_N")
			(pintype "output+no_connect")
		)
		(pad "B12" smd circle
			(at 0 -4.6 180)
			(size 0.254 0.254)
			(layers "F.Cu" "F.Mask" "F.Paste")
			(net 23 "GND")
			(pinfunction "VSS_ANA")
			(pintype "passive")
		)
		(pad "B13" smd circle
			(at 0.46 -4.6 180)
			(size 0.254 0.254)
			(layers "F.Cu" "F.Mask" "F.Paste")
			(net 268 "unconnected-(U4E-PB_RX0_N-PadB13)")
			(pinfunction "PB_RX0_N")
			(pintype "input+no_connect")
		)
		(pad "B14" smd circle
			(at 0.92 -4.6 180)
			(size 0.254 0.254)
			(layers "F.Cu" "F.Mask" "F.Paste")
			(net 23 "GND")
			(pinfunction "VSS_ANA")
			(pintype "passive")
		)
		(pad "B15" smd circle
			(at 1.38 -4.6 180)
			(size 0.254 0.254)
			(layers "F.Cu" "F.Mask" "F.Paste")
			(net 364 "/PD and TB DC-DC/USB3.RX1_N")
			(pinfunction "PA_RX1_N")
			(pintype "input")
		)
		(pad "B16" smd circle
			(at 1.84 -4.6 180)
			(size 0.254 0.254)
			(layers "F.Cu" "F.Mask" "F.Paste")
			(net 23 "GND")
			(pinfunction "VSS_ANA")
			(pintype "passive")
		)
		(pad "B17" smd circle
			(at 2.3 -4.6 180)
			(size 0.254 0.254)
			(layers "F.Cu" "F.Mask" "F.Paste")
			(net 174 "/TB Controller/PA_TX1_N")
			(pinfunction "PA_TX1_N")
			(pintype "output")
		)
		(pad "B18" smd circle
			(at 2.76 -4.6 180)
			(size 0.254 0.254)
			(layers "F.Cu" "F.Mask" "F.Paste")
			(net 23 "GND")
			(pinfunction "VSS_ANA")
			(pintype "passive")
		)
		(pad "B19" smd circle
			(at 3.22 -4.6 180)
			(size 0.254 0.254)
			(layers "F.Cu" "F.Mask" "F.Paste")
			(net 169 "/TB Controller/PA_TX0_N")
			(pinfunction "PA_TX0_N")
			(pintype "output")
		)
		(pad "B20" smd circle
			(at 3.68 -4.6 180)
			(size 0.254 0.254)
			(layers "F.Cu" "F.Mask" "F.Paste")
			(net 23 "GND")
			(pinfunction "VSS_ANA")
			(pintype "passive")
		)
		(pad "B21" smd circle
			(at 4.14 -4.6 180)
			(size 0.254 0.254)
			(layers "F.Cu" "F.Mask" "F.Paste")
			(net 360 "/PD and TB DC-DC/USB3.RX0_P")
			(pinfunction "PA_RX0_P")
			(pintype "input")
		)
		(pad "B22" smd circle
			(at 4.6 -4.6 180)
			(size 0.254 0.254)
			(layers "F.Cu" "F.Mask" "F.Paste")
			(net 23 "GND")
			(pinfunction "VSS_ANA")
			(pintype "passive")
		)
		(pad "B23" smd oval
			(at 5.06 -4.6 270)
			(size 0.1578 0.3302)
			(layers "F.Cu" "F.Mask" "F.Paste")
			(net 269 "unconnected-(U4F-ATEST_N-PadB23)")
			(pinfunction "ATEST_N")
			(pintype "passive+no_connect")
		)
		(pad "C1" smd oval
			(at -5.06 -4.14 270)
			(size 0.1578 0.3302)
			(layers "F.Cu" "F.Mask" "F.Paste")
			(net 426 "Net-(L2-Pad1)")
			(pinfunction "SVR_IND")
			(pintype "power_out")
		)
		(pad "C2" smd circle
			(at -4.6 -4.14 180)
			(size 0.254 0.254)
			(layers "F.Cu" "F.Mask" "F.Paste")
			(net 426 "Net-(L2-Pad1)")
			(pinfunction "SVR_IND")
			(pintype "passive")
		)
		(pad "C22" smd circle
			(at 4.6 -4.14 180)
			(size 0.254 0.254)
			(layers "F.Cu" "F.Mask" "F.Paste")
			(net 23 "GND")
			(pinfunction "MONDC_CIO_1")
			(pintype "passive")
		)
		(pad "C23" smd oval
			(at 5.06 -4.14 270)
			(size 0.1578 0.3302)
			(layers "F.Cu" "F.Mask" "F.Paste")
			(net 23 "GND")
			(pinfunction "MONDC_CIO_0")
			(pintype "passive")
		)
		(pad "D1" smd oval
			(at -5.06 -3.68 270)
			(size 0.1578 0.3302)
			(layers "F.Cu" "F.Mask" "F.Paste")
			(net 426 "Net-(L2-Pad1)")
			(pinfunction "SVR_IND")
			(pintype "passive")
		)
		(pad "D2" smd circle
			(at -4.6 -3.68 180)
			(size 0.254 0.254)
			(layers "F.Cu" "F.Mask" "F.Paste")
			(net 235 "Net-(U4C-POC_GPIO_5)")
			(pinfunction "POC_GPIO_5")
			(pintype "bidirectional")
		)
		(pad "D4" smd circle
			(at -3.9 -3.9 180)
			(size 0.254 0.254)
			(layers "F.Cu" "F.Mask" "F.Paste")
			(net 193 "Net-(U4C-POC_GPIO_2)")
			(pinfunction "POC_GPIO_2")
			(pintype "bidirectional")
		)
		(pad "D5" smd circle
			(at -3.25 -3.9 180)
			(size 0.254 0.254)
			(layers "F.Cu" "F.Mask" "F.Paste")
			(net 23 "GND")
			(pinfunction "VSS")
			(pintype "passive")
		)
		(pad "D6" smd circle
			(at -2.6 -3.9 180)
			(size 0.254 0.254)
			(layers "F.Cu" "F.Mask" "F.Paste")
			(net 23 "GND")
			(pinfunction "MONDC_SVR")
			(pintype "passive")
		)
		(pad "D8" smd circle
			(at -1.95 -3.9 180)
			(size 0.254 0.254)
			(layers "F.Cu" "F.Mask" "F.Paste")
			(net 23 "GND")
			(pinfunction "VSS_ANA")
			(pintype "passive")
		)
		(pad "D9" smd circle
			(at -1.3 -3.9 180)
			(size 0.254 0.254)
			(layers "F.Cu" "F.Mask" "F.Paste")
			(net 23 "GND")
			(pinfunction "VSS_ANA")
			(pintype "passive")
		)
		(pad "D11" smd circle
			(at -0.65 -3.9 180)
			(size 0.254 0.254)
			(layers "F.Cu" "F.Mask" "F.Paste")
			(net 23 "GND")
			(pinfunction "VSS_ANA")
			(pintype "passive")
		)
		(pad "D12" smd circle
			(at 0 -3.9 180)
			(size 0.254 0.254)
			(layers "F.Cu" "F.Mask" "F.Paste")
			(net 23 "GND")
			(pinfunction "VSS_ANA")
			(pintype "passive")
		)
		(pad "D13" smd circle
			(at 0.65 -3.9 180)
			(size 0.254 0.254)
			(layers "F.Cu" "F.Mask" "F.Paste")
			(net 23 "GND")
			(pinfunction "VSS_ANA")
			(pintype "passive")
		)
		(pad "D15" smd circle
			(at 1.3 -3.9 180)
			(size 0.254 0.254)
			(layers "F.Cu" "F.Mask" "F.Paste")
			(net 23 "GND")
			(pinfunction "VSS_ANA")
			(pintype "passive")
		)
		(pad "D16" smd circle
			(at 1.95 -3.9 180)
			(size 0.254 0.254)
			(layers "F.Cu" "F.Mask" "F.Paste")
			(net 23 "GND")
			(pinfunction "VSS_ANA")
			(pintype "passive")
		)
		(pad "D18" smd circle
			(at 2.6 -3.9 180)
			(size 0.254 0.254)
			(layers "F.Cu" "F.Mask" "F.Paste")
			(net 23 "GND")
			(pinfunction "VSS_ANA")
			(pintype "passive")
		)
		(pad "D19" smd circle
			(at 3.25 -3.9 180)
			(size 0.254 0.254)
			(layers "F.Cu" "F.Mask" "F.Paste")
			(net 270 "unconnected-(U4E-PB_USB2_D_N-PadD19)")
			(pinfunction "PB_USB2_D_N")
			(pintype "bidirectional+no_connect")
		)
		(pad "D20" smd circle
			(at 3.9 -3.9 180)
			(size 0.254 0.254)
			(layers "F.Cu" "F.Mask" "F.Paste")
			(net 395 "/PD and TB DC-DC/USB_RP.D-")
			(pinfunction "PA_USB2_D_N")
			(pintype "bidirectional")
		)
		(pad "D22" smd circle
			(at 4.6 -3.68 180)
			(size 0.254 0.254)
			(layers "F.Cu" "F.Mask" "F.Paste")
			(net 330 "/TB Controller/XTAL_25_IN")
			(pinfunction "XTAL_25_IN")
			(pintype "input")
		)
		(pad "D23" smd oval
			(at 5.06 -3.68 270)
			(size 0.1578 0.3302)
			(layers "F.Cu" "F.Mask" "F.Paste")
			(net 331 "/TB Controller/XTAL_25_OUT")
			(pinfunction "XTAL_25_OUT")
			(pintype "input")
		)
		(pad "E1" smd oval
			(at -5.06 -3.22 270)
			(size 0.1578 0.3302)
			(layers "F.Cu" "F.Mask" "F.Paste")
			(net 237 "Net-(U4D-TEST_EN)")
			(pinfunction "TEST_EN")
			(pintype "input")
		)
		(pad "E2" smd circle
			(at -4.6 -3.22 180)
			(size 0.254 0.254)
			(layers "F.Cu" "F.Mask" "F.Paste")
			(net 192 "Net-(U4C-POC_GPIO_1)")
			(pinfunction "POC_GPIO_1")
			(pintype "bidirectional")
		)
		(pad "E4" smd circle
			(at -3.9 -3.25 180)
			(size 0.254 0.254)
			(layers "F.Cu" "F.Mask" "F.Paste")
			(net 23 "GND")
			(pinfunction "VSS")
			(pintype "passive")
		)
		(pad "E5" smd circle
			(at -3.25 -3.25 180)
			(size 0.254 0.254)
			(layers "F.Cu" "F.Mask" "F.Paste")
			(net 23 "GND")
			(pinfunction "VSS")
			(pintype "passive")
		)
		(pad "E6" smd circle
			(at -2.6 -3.25 180)
			(size 0.254 0.254)
			(layers "F.Cu" "F.Mask" "F.Paste")
			(net 23 "GND")
			(pinfunction "VSS")
			(pintype "passive")
		)
		(pad "E8" smd circle
			(at -1.95 -3.25 180)
			(size 0.254 0.254)
			(layers "F.Cu" "F.Mask" "F.Paste")
			(net 23 "GND")
			(pinfunction "VSS_ANA")
			(pintype "passive")
		)
		(pad "E9" smd circle
			(at -1.3 -3.25 180)
			(size 0.254 0.254)
			(layers "F.Cu" "F.Mask" "F.Paste")
			(net 23 "GND")
			(pinfunction "VSS_ANA")
			(pintype "passive")
		)
		(pad "E11" smd circle
			(at -0.65 -3.25 180)
			(size 0.254 0.254)
			(layers "F.Cu" "F.Mask" "F.Paste")
			(net 23 "GND")
			(pinfunction "VSS_ANA")
			(pintype "passive")
		)
		(pad "E12" smd circle
			(at 0 -3.25 180)
			(size 0.254 0.254)
			(layers "F.Cu" "F.Mask" "F.Paste")
			(net 68 "/TB Controller - Power/VCC_0P9")
			(pinfunction "VCC0P9_SVR_ANA")
			(pintype "power_in")
		)
		(pad "E13" smd circle
			(at 0.65 -3.25 180)
			(size 0.254 0.254)
			(layers "F.Cu" "F.Mask" "F.Paste")
			(net 68 "/TB Controller - Power/VCC_0P9")
			(pinfunction "VCC0P9_SVR_ANA")
			(pintype "passive")
		)
		(pad "E15" smd circle
			(at 1.3 -3.25 180)
			(size 0.254 0.254)
			(layers "F.Cu" "F.Mask" "F.Paste")
			(net 23 "GND")
			(pinfunction "VSS_ANA")
			(pintype "passive")
		)
		(pad "E16" smd circle
			(at 1.95 -3.25 180)
			(size 0.254 0.254)
			(layers "F.Cu" "F.Mask" "F.Paste")
			(net 23 "GND")
			(pinfunction "VSS_ANA")
			(pintype "passive")
		)
		(pad "E18" smd circle
			(at 2.6 -3.25 180)
			(size 0.254 0.254)
			(layers "F.Cu" "F.Mask" "F.Paste")
			(net 271 "unconnected-(U4F-USB2_ATEST-PadE18)")
			(pinfunction "USB2_ATEST")
			(pintype "passive+no_connect")
		)
		(pad "E19" smd circle
			(at 3.25 -3.25 180)
			(size 0.254 0.254)
			(layers "F.Cu" "F.Mask" "F.Paste")
			(net 272 "unconnected-(U4E-PB_USB2_D_P-PadE19)")
			(pinfunction "PB_USB2_D_P")
			(pintype "bidirectional+no_connect")
		)
		(pad "E20" smd circle
			(at 3.9 -3.25 180)
			(size 0.254 0.254)
			(layers "F.Cu" "F.Mask" "F.Paste")
			(net 396 "/PD and TB DC-DC/USB_RP.D+")
			(pinfunction "PA_USB2_D_P")
			(pintype "bidirectional")
		)
		(pad "E22" smd circle
			(at 4.6 -3.22 180)
			(size 0.254 0.254)
			(layers "F.Cu" "F.Mask" "F.Paste")
			(net 23 "GND")
			(pinfunction "VSS_ANA")
			(pintype "passive")
		)
		(pad "E23" smd oval
			(at 5.06 -3.22 270)
			(size 0.1578 0.3302)
			(layers "F.Cu" "F.Mask" "F.Paste")
			(net 23 "GND")
			(pinfunction "VSS_ANA")
			(pintype "passive")
		)
		(pad "F1" smd oval
			(at -5.06 -2.76 270)
			(size 0.1578 0.3302)
			(layers "F.Cu" "F.Mask" "F.Paste")
			(net 236 "Net-(U4C-POC_GPIO_6)")
			(pinfunction "POC_GPIO_6")
			(pintype "bidirectional")
		)
		(pad "F2" smd circle
			(at -4.6 -2.76 180)
			(size 0.254 0.254)
			(layers "F.Cu" "F.Mask" "F.Paste")
			(net 371 "/TB Controller/~{PE_WAKE}")
			(pinfunction "POC_GPIO_4")
			(pintype "bidirectional")
		)
		(pad "F4" smd circle
			(at -3.9 -2.6 180)
			(size 0.254 0.254)
			(layers "F.Cu" "F.Mask" "F.Paste")
			(net 377 "/PD and TB DC-DC/RESET_N")
			(pinfunction "RESET_N")
			(pintype "input")
		)
		(pad "F5" smd circle
			(at -3.25 -2.6 180)
			(size 0.254 0.254)
			(layers "F.Cu" "F.Mask" "F.Paste")
			(net 23 "GND")
			(pinfunction "VSS")
			(pintype "passive")
		)
		(pad "F6" smd circle
			(at -2.6 -2.6 180)
			(size 0.254 0.254)
			(layers "F.Cu" "F.Mask" "F.Paste")
			(net 23 "GND")
			(pinfunction "VSS")
			(pintype "passive")
		)
		(pad "F8" smd circle
			(at -1.95 -2.6 180)
			(size 0.254 0.254)
			(layers "F.Cu" "F.Mask" "F.Paste")
			(net 57 "+3V3_TB")
			(pinfunction "VCC3P3_SX")
			(pintype "power_in")
		)
		(pad "F9" smd circle
			(at -1.3 -2.6 180)
			(size 0.254 0.254)
			(layers "F.Cu" "F.Mask" "F.Paste")
			(net 23 "GND")
			(pinfunction "VSS_ANA")
			(pintype "passive")
		)
		(pad "F11" smd circle
			(at -0.65 -2.6 180)
			(size 0.254 0.254)
			(layers "F.Cu" "F.Mask" "F.Paste")
			(net 68 "/TB Controller - Power/VCC_0P9")
			(pinfunction "VCC0P9_SVR_ANA")
			(pintype "passive")
		)
		(pad "F12" smd circle
			(at 0 -2.6 180)
			(size 0.254 0.254)
			(layers "F.Cu" "F.Mask" "F.Paste")
			(net 68 "/TB Controller - Power/VCC_0P9")
			(pinfunction "VCC0P9_SVR_ANA")
			(pintype "passive")
		)
		(pad "F13" smd circle
			(at 0.65 -2.6 180)
			(size 0.254 0.254)
			(layers "F.Cu" "F.Mask" "F.Paste")
			(net 68 "/TB Controller - Power/VCC_0P9")
			(pinfunction "VCC0P9_SVR_ANA")
			(pintype "passive")
		)
		(pad "F15" smd circle
			(at 1.3 -2.6 180)
			(size 0.254 0.254)
			(layers "F.Cu" "F.Mask" "F.Paste")
			(net 68 "/TB Controller - Power/VCC_0P9")
			(pinfunction "VCC0P9_SVR_ANA")
			(pintype "passive")
		)
		(pad "F16" smd circle
			(at 1.95 -2.6 180)
			(size 0.254 0.254)
			(layers "F.Cu" "F.Mask" "F.Paste")
			(net 23 "GND")
			(pinfunction "VSS_ANA")
			(pintype "passive")
		)
		(pad "F18" smd circle
			(at 2.6 -2.6 180)
			(size 0.254 0.254)
			(layers "F.Cu" "F.Mask" "F.Paste")
			(net 180 "Net-(U4A-VCC0P9_LVR_SENSE)")
			(pinfunction "VCC0P9_LVR")
			(pintype "power_in")
		)
		(pad "F19" smd circle
			(at 3.25 -2.6 180)
			(size 0.254 0.254)
			(layers "F.Cu" "F.Mask" "F.Paste")
			(net 234 "Net-(U4E-PB_USB2_RBIAS)")
			(pinfunction "PB_USB2_RBIAS")
			(pintype "passive")
		)
		(pad "F20" smd circle
			(at 3.9 -2.6 180)
			(size 0.254 0.254)
			(layers "F.Cu" "F.Mask" "F.Paste")
			(net 23 "GND")
			(pinfunction "VSS_ANA")
			(pintype "passive")
		)
		(pad "F22" smd circle
			(at 4.6 -2.76 180)
			(size 0.254 0.254)
			(layers "F.Cu" "F.Mask" "F.Paste")
			(net 320 "/TB Controller/TB_PCIE_TX3_N")
			(pinfunction "PCIE_TX3_N")
			(pintype "input")
		)
		(pad "F23" smd oval
			(at 5.06 -2.76 270)
			(size 0.1578 0.3302)
			(layers "F.Cu" "F.Mask" "F.Paste")
			(net 329 "/TB Controller/TB_PCIE_TX3_P")
			(pinfunction "PCIE_TX3_P")
			(pintype "input")
		)
		(pad "G1" smd oval
			(at -5.06 -2.3 270)
			(size 0.1578 0.3302)
			(layers "F.Cu" "F.Mask" "F.Paste")
			(net 184 "Net-(U4C-DPSRC_HPD)")
			(pinfunction "DPSRC_HPD")
			(pintype "passive")
		)
		(pad "G2" smd circle
			(at -4.6 -2.3 180)
			(size 0.254 0.254)
			(layers "F.Cu" "F.Mask" "F.Paste")
			(net 233 "Net-(U4E-PB_DPSRC_HPD)")
			(pinfunction "PB_DPSRC_HPD")
			(pintype "input")
		)
		(pad "G22" smd circle
			(at 4.6 -2.3 180)
			(size 0.254 0.254)
			(layers "F.Cu" "F.Mask" "F.Paste")
			(net 23 "GND")
			(pinfunction "VSS_ANA")
			(pintype "passive")
		)
		(pad "G23" smd oval
			(at 5.06 -2.3 270)
			(size 0.1578 0.3302)
			(layers "F.Cu" "F.Mask" "F.Paste")
			(net 23 "GND")
			(pinfunction "VSS_ANA")
			(pintype "passive")
		)
		(pad "H1" smd oval
			(at -5.06 -1.84 270)
			(size 0.1578 0.3302)
			(layers "F.Cu" "F.Mask" "F.Paste")
			(net 23 "GND")
			(pinfunction "VSS_ANA")
			(pintype "passive")
		)
		(pad "H2" smd circle
			(at -4.6 -1.84 180)
			(size 0.254 0.254)
			(layers "F.Cu" "F.Mask" "F.Paste")
			(net 23 "GND")
			(pinfunction "VSS_ANA")
			(pintype "passive")
		)
		(pad "H4" smd circle
			(at -3.9 -1.95 180)
			(size 0.254 0.254)
			(layers "F.Cu" "F.Mask" "F.Paste")
			(net 194 "Net-(U4C-POC_GPIO_3)")
			(pinfunction "POC_GPIO_3")
			(pintype "bidirectional")
		)
		(pad "H5" smd circle
			(at -3.25 -1.95 180)
			(size 0.254 0.254)
			(layers "F.Cu" "F.Mask" "F.Paste")
			(net 23 "GND")
			(pinfunction "VSS")
			(pintype "passive")
		)
		(pad "H6" smd circle
			(at -2.6 -1.95 180)
			(size 0.254 0.254)
			(layers "F.Cu" "F.Mask" "F.Paste")
			(net 230 "Net-(U4D-RBIAS)")
			(pinfunction "RBIAS")
			(pintype "passive")
		)
		(pad "H8" smd circle
			(at -1.95 -1.95 180)
			(size 0.254 0.254)
			(layers "F.Cu" "F.Mask" "F.Paste")
			(net 23 "GND")
			(pinfunction "VSS")
			(pintype "passive")
		)
		(pad "H9" smd circle
			(at -1.3 -1.95 180)
			(size 0.254 0.254)
			(layers "F.Cu" "F.Mask" "F.Paste")
			(net 57 "+3V3_TB")
			(pinfunction "VCC3P3A")
			(pintype "power_in")
		)
		(pad "H11" smd circle
			(at -0.65 -1.95 180)
			(size 0.254 0.254)
			(layers "F.Cu" "F.Mask" "F.Paste")
			(net 180 "Net-(U4A-VCC0P9_LVR_SENSE)")
			(pinfunction "VCC0P9_LVR_SENSE")
			(pintype "power_in")
		)
		(pad "H12" smd circle
			(at 0 -1.95 180)
			(size 0.254 0.254)
			(layers "F.Cu" "F.Mask" "F.Paste")
			(net 23 "GND")
			(pinfunction "VSS_ANA")
			(pintype "passive")
		)
		(pad "H13" smd circle
			(at 0.65 -1.95 180)
			(size 0.254 0.254)
			(layers "F.Cu" "F.Mask" "F.Paste")
			(net 23 "GND")
			(pinfunction "VSS_ANA")
			(pintype "passive")
		)
		(pad "H15" smd circle
			(at 1.3 -1.95 180)
			(size 0.254 0.254)
			(layers "F.Cu" "F.Mask" "F.Paste")
			(net 23 "GND")
			(pinfunction "VSS_ANA")
			(pintype "passive")
		)
		(pad "H16" smd circle
			(at 1.95 -1.95 180)
			(size 0.254 0.254)
			(layers "F.Cu" "F.Mask" "F.Paste")
			(net 23 "GND")
			(pinfunction "VSS_ANA")
			(pintype "passive")
		)
		(pad "H18" smd circle
			(at 2.6 -1.95 180)
			(size 0.254 0.254)
			(layers "F.Cu" "F.Mask" "F.Paste")
			(net 180 "Net-(U4A-VCC0P9_LVR_SENSE)")
			(pinfunction "VCC0P9_LVR")
			(pintype "passive")
		)
		(pad "H19" smd circle
			(at 3.25 -1.95 180)
			(size 0.254 0.254)
			(layers "F.Cu" "F.Mask" "F.Paste")
			(net 228 "Net-(U4E-PA_USB2_RBIAS)")
			(pinfunction "PA_USB2_RBIAS")
			(pintype "passive")
		)
		(pad "H20" smd circle
			(at 3.9 -1.95 180)
			(size 0.254 0.254)
			(layers "F.Cu" "F.Mask" "F.Paste")
			(net 23 "GND")
			(pinfunction "VSS_ANA")
			(pintype "passive")
		)
		(pad "H22" smd circle
			(at 4.6 -1.84 180)
			(size 0.254 0.254)
			(layers "F.Cu" "F.Mask" "F.Paste")
			(net 595 "/TB Controller/PCIex4.TX3-")
			(pinfunction "PCIE_RX3_N")
			(pintype "input")
		)
		(pad "H23" smd oval
			(at 5.06 -1.84 270)
			(size 0.1578 0.3302)
			(layers "F.Cu" "F.Mask" "F.Paste")
			(net 601 "/TB Controller/PCIex4.TX3+")
			(pinfunction "PCIE_RX3_P")
			(pintype "input")
		)
		(pad "J1" smd oval
			(at -5.06 -1.38 270)
			(size 0.1578 0.3302)
			(layers "F.Cu" "F.Mask" "F.Paste")
			(net 273 "unconnected-(U4C-DPSRC_ML3_N-PadJ1)")
			(pinfunction "DPSRC_ML3_N")
			(pintype "output+no_connect")
		)
		(pad "J2" smd circle
			(at -4.6 -1.38 180)
			(size 0.254 0.254)
			(layers "F.Cu" "F.Mask" "F.Paste")
			(net 274 "unconnected-(U4C-DPSRC_ML3_P-PadJ2)")
			(pinfunction "DPSRC_ML3_P")
			(pintype "output+no_connect")
		)
		(pad "J4" smd circle
			(at -3.9 -1.3 180)
			(size 0.254 0.254)
			(layers "F.Cu" "F.Mask" "F.Paste")
			(net 372 "/PD and TB DC-DC/I2C1.IRQ")
			(pinfunction "POC_GPIO_0")
			(pintype "bidirectional")
		)
		(pad "J5" smd circle
			(at -3.25 -1.3 180)
			(size 0.254 0.254)
			(layers "F.Cu" "F.Mask" "F.Paste")
			(net 23 "GND")
			(pinfunction "VSS_ANA")
			(pintype "passive")
		)
		(pad "J6" smd circle
			(at -2.6 -1.3 180)
			(size 0.254 0.254)
			(layers "F.Cu" "F.Mask" "F.Paste")
			(net 229 "Net-(U4D-RSENSE)")
			(pinfunction "RSENSE")
			(pintype "passive")
		)
		(pad "J8" smd circle
			(at -1.95 -1.3 180)
			(size 0.254 0.254)
			(layers "F.Cu" "F.Mask" "F.Paste")
			(net 23 "GND")
			(pinfunction "VSS")
			(pintype "passive")
		)
		(pad "J9" smd circle
			(at -1.3 -1.3 180)
			(size 0.254 0.254)
			(layers "F.Cu" "F.Mask" "F.Paste")
			(net 68 "/TB Controller - Power/VCC_0P9")
			(pinfunction "VCC0P9_SVR_SENSE")
			(pintype "power_in")
		)
		(pad "J11" smd circle
			(at -0.65 -1.3 180)
			(size 0.254 0.254)
			(layers "F.Cu" "F.Mask" "F.Paste")
			(net 180 "Net-(U4A-VCC0P9_LVR_SENSE)")
			(pinfunction "VCC0P9_LVR")
			(pintype "passive")
		)
		(pad "J12" smd circle
			(at 0 -1.3 180)
			(size 0.254 0.254)
			(layers "F.Cu" "F.Mask" "F.Paste")
			(net 23 "GND")
			(pinfunction "VSS")
			(pintype "passive")
		)
		(pad "J13" smd circle
			(at 0.65 -1.3 180)
			(size 0.254 0.254)
			(layers "F.Cu" "F.Mask" "F.Paste")
			(net 23 "GND")
			(pinfunction "VSS")
			(pintype "passive")
		)
		(pad "J15" smd circle
			(at 1.3 -1.3 180)
			(size 0.254 0.254)
			(layers "F.Cu" "F.Mask" "F.Paste")
			(net 23 "GND")
			(pinfunction "VSS")
			(pintype "passive")
		)
		(pad "J16" smd circle
			(at 1.95 -1.3 180)
			(size 0.254 0.254)
			(layers "F.Cu" "F.Mask" "F.Paste")
			(net 178 "Net-(U4A-VCC3P3_ANA_USB2)")
			(pinfunction "VCC3P3_ANA_USB2")
			(pintype "power_in")
		)
		(pad "J18" smd circle
			(at 2.6 -1.3 180)
			(size 0.254 0.254)
			(layers "F.Cu" "F.Mask" "F.Paste")
			(net 23 "GND")
			(pinfunction "VSS_ANA")
			(pintype "passive")
		)
		(pad "J19" smd circle
			(at 3.25 -1.3 180)
			(size 0.254 0.254)
			(layers "F.Cu" "F.Mask" "F.Paste")
			(net 23 "GND")
			(pinfunction "VSS_ANA")
			(pintype "passive")
		)
		(pad "J20" smd circle
			(at 3.9 -1.3 180)
			(size 0.254 0.254)
			(layers "F.Cu" "F.Mask" "F.Paste")
			(net 23 "GND")
			(pinfunction "VSS_ANA")
			(pintype "passive")
		)
		(pad "J22" smd circle
			(at 4.6 -1.38 180)
			(size 0.254 0.254)
			(layers "F.Cu" "F.Mask" "F.Paste")
			(net 23 "GND")
			(pinfunction "VSS_ANA")
			(pintype "passive")
		)
		(pad "J23" smd oval
			(at 5.06 -1.38 270)
			(size 0.1578 0.3302)
			(layers "F.Cu" "F.Mask" "F.Paste")
			(net 23 "GND")
			(pinfunction "VSS_ANA")
			(pintype "passive")
		)
		(pad "K1" smd oval
			(at -5.06 -0.92 270)
			(size 0.1578 0.3302)
			(layers "F.Cu" "F.Mask" "F.Paste")
			(net 23 "GND")
			(pinfunction "VSS_ANA")
			(pintype "passive")
		)
		(pad "K2" smd circle
			(at -4.6 -0.92 180)
			(size 0.254 0.254)
			(layers "F.Cu" "F.Mask" "F.Paste")
			(net 23 "GND")
			(pinfunction "VSS_ANA")
			(pintype "passive")
		)
		(pad "K22" smd circle
			(at 4.6 -0.92 180)
			(size 0.254 0.254)
			(layers "F.Cu" "F.Mask" "F.Paste")
			(net 318 "/TB Controller/TB_PCIE_TX2_N")
			(pinfunction "PCIE_TX2_N")
			(pintype "input")
		)
		(pad "K23" smd oval
			(at 5.06 -0.92 270)
			(size 0.1578 0.3302)
			(layers "F.Cu" "F.Mask" "F.Paste")
			(net 327 "/TB Controller/TB_PCIE_TX2_P")
			(pinfunction "PCIE_TX2_P")
			(pintype "input")
		)
		(pad "L1" smd oval
			(at -5.06 -0.46 270)
			(size 0.1578 0.3302)
			(layers "F.Cu" "F.Mask" "F.Paste")
			(net 275 "unconnected-(U4C-DPSRC_ML2_N-PadL1)")
			(pinfunction "DPSRC_ML2_N")
			(pintype "output+no_connect")
		)
		(pad "L2" smd circle
			(at -4.6 -0.46 180)
			(size 0.254 0.254)
			(layers "F.Cu" "F.Mask" "F.Paste")
			(net 276 "unconnected-(U4C-DPSRC_ML2_P-PadL2)")
			(pinfunction "DPSRC_ML2_P")
			(pintype "output+no_connect")
		)
		(pad "L4" smd circle
			(at -3.9 -0.65 180)
			(size 0.254 0.254)
			(layers "F.Cu" "F.Mask" "F.Paste")
			(net 392 "/TB Controller/~{PE_RST}")
			(pinfunction "PERST_N")
			(pintype "input")
		)
		(pad "L5" smd circle
			(at -3.25 -0.65 180)
			(size 0.254 0.254)
			(layers "F.Cu" "F.Mask" "F.Paste")
			(net 23 "GND")
			(pinfunction "VSS_ANA")
			(pintype "passive")
		)
		(pad "L6" smd circle
			(at -2.6 -0.65 180)
			(size 0.254 0.254)
			(layers "F.Cu" "F.Mask" "F.Paste")
			(net 402 "Net-(C52-Pad2)")
			(pinfunction "VCC0P9_ANA_DPSRC")
			(pintype "power_in")
		)
		(pad "L8" smd circle
			(at -1.95 -0.65 180)
			(size 0.254 0.254)
			(layers "F.Cu" "F.Mask" "F.Paste")
			(net 402 "Net-(C52-Pad2)")
			(pinfunction "VCC0P9_DP")
			(pintype "passive")
		)
		(pad "L9" smd circle
			(at -1.3 -0.65 180)
			(size 0.254 0.254)
			(layers "F.Cu" "F.Mask" "F.Paste")
			(net 68 "/TB Controller - Power/VCC_0P9")
			(pinfunction "VCC0P9_SVR")
			(pintype "power_in")
		)
		(pad "L11" smd circle
			(at -0.65 -0.65 180)
			(size 0.254 0.254)
			(layers "F.Cu" "F.Mask" "F.Paste")
			(net 402 "Net-(C52-Pad2)")
			(pinfunction "VCC0P9_DP")
			(pintype "power_in")
		)
		(pad "L12" smd circle
			(at 0 -0.65 180)
			(size 0.254 0.254)
			(layers "F.Cu" "F.Mask" "F.Paste")
			(net 402 "Net-(C52-Pad2)")
			(pinfunction "VCC0P9_DP")
			(pintype "passive")
		)
		(pad "L13" smd circle
			(at 0.65 -0.65 180)
			(size 0.254 0.254)
			(layers "F.Cu" "F.Mask" "F.Paste")
			(net 23 "GND")
			(pinfunction "VSS")
			(pintype "passive")
		)
		(pad "L15" smd circle
			(at 1.3 -0.65 180)
			(size 0.254 0.254)
			(layers "F.Cu" "F.Mask" "F.Paste")
			(net 23 "GND")
			(pinfunction "FUSE_VQPS_64")
			(pintype "passive")
		)
		(pad "L16" smd circle
			(at 1.95 -0.65 180)
			(size 0.254 0.254)
			(layers "F.Cu" "F.Mask" "F.Paste")
			(net 177 "Net-(U4A-VCC3P3_ANA_PCIE)")
			(pinfunction "VCC3P3_ANA_PCIE")
			(pintype "power_in")
		)
		(pad "L18" smd circle
			(at 2.6 -0.65 180)
			(size 0.254 0.254)
			(layers "F.Cu" "F.Mask" "F.Paste")
			(net 403 "Net-(C55-Pad2)")
			(pinfunction "VCC0P9_ANA_PCIE_2")
			(pintype "power_in")
		)
		(pad "L19" smd circle
			(at 3.25 -0.65 180)
			(size 0.254 0.254)
			(layers "F.Cu" "F.Mask" "F.Paste")
			(net 403 "Net-(C55-Pad2)")
			(pinfunction "VCC0P9_ANA_PCIE_1")
			(pintype "power_in")
		)
		(pad "L20" smd circle
			(at 3.9 -0.65 180)
			(size 0.254 0.254)
			(layers "F.Cu" "F.Mask" "F.Paste")
			(net 23 "GND")
			(pinfunction "VSS_ANA")
			(pintype "passive")
		)
		(pad "L22" smd circle
			(at 4.6 -0.46 180)
			(size 0.254 0.254)
			(layers "F.Cu" "F.Mask" "F.Paste")
			(net 23 "GND")
			(pinfunction "VSS_ANA")
			(pintype "passive")
		)
		(pad "L23" smd oval
			(at 5.06 -0.46 270)
			(size 0.1578 0.3302)
			(layers "F.Cu" "F.Mask" "F.Paste")
			(net 23 "GND")
			(pinfunction "VSS_ANA")
			(pintype "passive")
		)
		(pad "M1" smd oval
			(at -5.06 0 270)
			(size 0.1578 0.3302)
			(layers "F.Cu" "F.Mask" "F.Paste")
			(net 23 "GND")
			(pinfunction "VSS_ANA")
			(pintype "passive")
		)
		(pad "M2" smd circle
			(at -4.6 0 180)
			(size 0.254 0.254)
			(layers "F.Cu" "F.Mask" "F.Paste")
			(net 23 "GND")
			(pinfunction "VSS_ANA")
			(pintype "passive")
		)
		(pad "M4" smd circle
			(at -3.9 0 180)
			(size 0.254 0.254)
			(layers "F.Cu" "F.Mask" "F.Paste")
			(net 374 "/PD and TB DC-DC/HPD")
			(pinfunction "PA_DPSRC_HPD")
			(pintype "input")
		)
		(pad "M5" smd circle
			(at -3.25 0 180)
			(size 0.254 0.254)
			(layers "F.Cu" "F.Mask" "F.Paste")
			(net 23 "GND")
			(pinfunction "VSS_ANA")
			(pintype "passive")
		)
		(pad "M6" smd circle
			(at -2.6 0 180)
			(size 0.254 0.254)
			(layers "F.Cu" "F.Mask" "F.Paste")
			(net 402 "Net-(C52-Pad2)")
			(pinfunction "VCC0P9_ANA_DPSRC")
			(pintype "passive")
		)
		(pad "M8" smd circle
			(at -1.95 0 180)
			(size 0.254 0.254)
			(layers "F.Cu" "F.Mask" "F.Paste")
			(net 402 "Net-(C52-Pad2)")
			(pinfunction "VCC0P9_DP")
			(pintype "passive")
		)
		(pad "M9" smd circle
			(at -1.3 0 180)
			(size 0.254 0.254)
			(layers "F.Cu" "F.Mask" "F.Paste")
			(net 68 "/TB Controller - Power/VCC_0P9")
			(pinfunction "VCC0P9_SVR")
			(pintype "passive")
		)
		(pad "M11" smd circle
			(at -0.65 0 180)
			(size 0.254 0.254)
			(layers "F.Cu" "F.Mask" "F.Paste")
			(net 23 "GND")
			(pinfunction "VSS")
			(pintype "passive")
		)
		(pad "M12" smd circle
			(at 0 0 180)
			(size 0.254 0.254)
			(layers "F.Cu" "F.Mask" "F.Paste")
			(net 23 "GND")
			(pinfunction "VSS")
			(pintype "passive")
		)
		(pad "M13" smd circle
			(at 0.65 0 180)
			(size 0.254 0.254)
			(layers "F.Cu" "F.Mask" "F.Paste")
			(net 403 "Net-(C55-Pad2)")
			(pinfunction "VCC0P9_PCIE")
			(pintype "power_in")
		)
		(pad "M15" smd circle
			(at 1.3 0 180)
			(size 0.254 0.254)
			(layers "F.Cu" "F.Mask" "F.Paste")
			(net 403 "Net-(C55-Pad2)")
			(pinfunction "VCC0P9_PCIE")
			(pintype "passive")
		)
		(pad "M16" smd circle
			(at 1.95 0 180)
			(size 0.254 0.254)
			(layers "F.Cu" "F.Mask" "F.Paste")
			(net 403 "Net-(C55-Pad2)")
			(pinfunction "VCC0P9_PCIE")
			(pintype "passive")
		)
		(pad "M18" smd circle
			(at 2.6 0 180)
			(size 0.254 0.254)
			(layers "F.Cu" "F.Mask" "F.Paste")
			(net 403 "Net-(C55-Pad2)")
			(pinfunction "VCC0P9_ANA_PCIE_2")
			(pintype "passive")
		)
		(pad "M19" smd circle
			(at 3.25 0 180)
			(size 0.254 0.254)
			(layers "F.Cu" "F.Mask" "F.Paste")
			(net 23 "GND")
			(pinfunction "VSS_ANA")
			(pintype "passive")
		)
		(pad "M20" smd circle
			(at 3.9 0 180)
			(size 0.254 0.254)
			(layers "F.Cu" "F.Mask" "F.Paste")
			(net 23 "GND")
			(pinfunction "VSS_ANA")
			(pintype "passive")
		)
		(pad "M22" smd circle
			(at 4.6 0 180)
			(size 0.254 0.254)
			(layers "F.Cu" "F.Mask" "F.Paste")
			(net 598 "/TB Controller/PCIex4.TX2-")
			(pinfunction "PCIE_RX2_N")
			(pintype "input")
		)
		(pad "M23" smd oval
			(at 5.06 0 270)
			(size 0.1578 0.3302)
			(layers "F.Cu" "F.Mask" "F.Paste")
			(net 602 "/TB Controller/PCIex4.TX2+")
			(pinfunction "PCIE_RX2_P")
			(pintype "input")
		)
		(pad "N1" smd oval
			(at -5.06 0.46 270)
			(size 0.1578 0.3302)
			(layers "F.Cu" "F.Mask" "F.Paste")
			(net 277 "unconnected-(U4C-DPSRC_ML1_N-PadN1)")
			(pinfunction "DPSRC_ML1_N")
			(pintype "output+no_connect")
		)
		(pad "N2" smd circle
			(at -4.6 0.46 180)
			(size 0.254 0.254)
			(layers "F.Cu" "F.Mask" "F.Paste")
			(net 278 "unconnected-(U4C-DPSRC_ML1_P-PadN2)")
			(pinfunction "DPSRC_ML1_P")
			(pintype "output+no_connect")
		)
		(pad "N4" smd circle
			(at -3.9 0.65 180)
			(size 0.254 0.254)
			(layers "F.Cu" "F.Mask" "F.Paste")
			(net 222 "Net-(U4C-DPSNK1_DDC_DATA)")
			(pinfunction "DPSNK1_DDC_DATA")
			(pintype "passive")
		)
		(pad "N5" smd circle
			(at -3.25 0.65 180)
			(size 0.254 0.254)
			(layers "F.Cu" "F.Mask" "F.Paste")
			(net 23 "GND")
			(pinfunction "VSS_ANA")
			(pintype "passive")
		)
		(pad "N6" smd circle
			(at -2.6 0.65 180)
			(size 0.254 0.254)
			(layers "F.Cu" "F.Mask" "F.Paste")
			(net 185 "Net-(U4C-DPSRC_RBIAS)")
			(pinfunction "DPSRC_RBIAS")
			(pintype "passive")
		)
		(pad "N8" smd circle
			(at -1.95 0.65 180)
			(size 0.254 0.254)
			(layers "F.Cu" "F.Mask" "F.Paste")
			(net 23 "GND")
			(pinfunction "VSS")
			(pintype "passive")
		)
		(pad "N9" smd circle
			(at -1.3 0.65 180)
			(size 0.254 0.254)
			(layers "F.Cu" "F.Mask" "F.Paste")
			(net 23 "GND")
			(pinfunction "VSS")
			(pintype "passive")
		)
		(pad "N11" smd circle
			(at -0.65 0.65 180)
			(size 0.254 0.254)
			(layers "F.Cu" "F.Mask" "F.Paste")
			(net 23 "GND")
			(pinfunction "VSS")
			(pintype "passive")
		)
		(pad "N12" smd circle
			(at 0 0.65 180)
			(size 0.254 0.254)
			(layers "F.Cu" "F.Mask" "F.Paste")
			(net 23 "GND")
			(pinfunction "VSS")
			(pintype "passive")
		)
		(pad "N13" smd circle
			(at 0.65 0.65 180)
			(size 0.254 0.254)
			(layers "F.Cu" "F.Mask" "F.Paste")
			(net 23 "GND")
			(pinfunction "VSS")
			(pintype "passive")
		)
		(pad "N15" smd circle
			(at 1.3 0.65 180)
			(size 0.254 0.254)
			(layers "F.Cu" "F.Mask" "F.Paste")
			(net 23 "GND")
			(pinfunction "FUSE_VQPS_128")
			(pintype "passive")
		)
		(pad "N16" smd circle
			(at 1.95 0.65 180)
			(size 0.254 0.254)
			(layers "F.Cu" "F.Mask" "F.Paste")
			(net 183 "Net-(U4B-PCIE_RBIAS)")
			(pinfunction "PCIE_RBIAS")
			(pintype "input")
		)
		(pad "N18" smd circle
			(at 2.6 0.65 180)
			(size 0.254 0.254)
			(layers "F.Cu" "F.Mask" "F.Paste")
			(net 403 "Net-(C55-Pad2)")
			(pinfunction "VCC0P9_ANA_PCIE_2")
			(pintype "passive")
		)
		(pad "N19" smd circle
			(at 3.25 0.65 180)
			(size 0.254 0.254)
			(layers "F.Cu" "F.Mask" "F.Paste")
			(net 403 "Net-(C55-Pad2)")
			(pinfunction "VCC0P9_ANA_PCIE_1")
			(pintype "passive")
		)
		(pad "N20" smd circle
			(at 3.9 0.65 180)
			(size 0.254 0.254)
			(layers "F.Cu" "F.Mask" "F.Paste")
			(net 23 "GND")
			(pinfunction "VSS_ANA")
			(pintype "passive")
		)
		(pad "N22" smd circle
			(at 4.6 0.46 180)
			(size 0.254 0.254)
			(layers "F.Cu" "F.Mask" "F.Paste")
			(net 23 "GND")
			(pinfunction "VSS_ANA")
			(pintype "passive")
		)
		(pad "N23" smd oval
			(at 5.06 0.46 270)
			(size 0.1578 0.3302)
			(layers "F.Cu" "F.Mask" "F.Paste")
			(net 23 "GND")
			(pinfunction "VSS_ANA")
			(pintype "passive")
		)
		(pad "P1" smd oval
			(at -5.06 0.92 270)
			(size 0.1578 0.3302)
			(layers "F.Cu" "F.Mask" "F.Paste")
			(net 23 "GND")
			(pinfunction "VSS_ANA")
			(pintype "passive")
		)
		(pad "P2" smd circle
			(at -4.6 0.92 180)
			(size 0.254 0.254)
			(layers "F.Cu" "F.Mask" "F.Paste")
			(net 23 "GND")
			(pinfunction "VSS_ANA")
			(pintype "passive")
		)
		(pad "P22" smd circle
			(at 4.6 0.92 180)
			(size 0.254 0.254)
			(layers "F.Cu" "F.Mask" "F.Paste")
			(net 316 "/TB Controller/TB_PCIE_TX1_N")
			(pinfunction "PCIE_TX1_N")
			(pintype "input")
		)
		(pad "P23" smd oval
			(at 5.06 0.92 270)
			(size 0.1578 0.3302)
			(layers "F.Cu" "F.Mask" "F.Paste")
			(net 325 "/TB Controller/TB_PCIE_TX1_P")
			(pinfunction "PCIE_TX1_P")
			(pintype "input")
		)
		(pad "R1" smd oval
			(at -5.06 1.38 270)
			(size 0.1578 0.3302)
			(layers "F.Cu" "F.Mask" "F.Paste")
			(net 279 "unconnected-(U4C-DPSRC_ML0_N-PadR1)")
			(pinfunction "DPSRC_ML0_N")
			(pintype "output+no_connect")
		)
		(pad "R2" smd circle
			(at -4.6 1.38 180)
			(size 0.254 0.254)
			(layers "F.Cu" "F.Mask" "F.Paste")
			(net 280 "unconnected-(U4C-DPSRC_ML0_P-PadR2)")
			(pinfunction "DPSRC_ML0_P")
			(pintype "output+no_connect")
		)
		(pad "R4" smd circle
			(at -3.9 1.3 180)
			(size 0.254 0.254)
			(layers "F.Cu" "F.Mask" "F.Paste")
			(net 219 "Net-(U4C-DPSNK0_DDC_DATA)")
			(pinfunction "DPSNK0_DDC_DATA")
			(pintype "passive")
		)
		(pad "R5" smd circle
			(at -3.25 1.3 180)
			(size 0.254 0.254)
			(layers "F.Cu" "F.Mask" "F.Paste")
			(net 23 "GND")
			(pinfunction "VSS_ANA")
			(pintype "passive")
		)
		(pad "R6" smd circle
			(at -2.6 1.3 180)
			(size 0.254 0.254)
			(layers "F.Cu" "F.Mask" "F.Paste")
			(net 179 "Net-(U4A-VCC3P3_LC)")
			(pinfunction "VCC3P3_LC")
			(pintype "power_in")
		)
		(pad "R8" smd circle
			(at -1.95 1.3 180)
			(size 0.254 0.254)
			(layers "F.Cu" "F.Mask" "F.Paste")
			(net 404 "Net-(C58-Pad2)")
			(pinfunction "VCC0P9_CIO")
			(pintype "passive")
		)
		(pad "R9" smd circle
			(at -1.3 1.3 180)
			(size 0.254 0.254)
			(layers "F.Cu" "F.Mask" "F.Paste")
			(net 404 "Net-(C58-Pad2)")
			(pinfunction "VCC0P9_CIO")
			(pintype "passive")
		)
		(pad "R11" smd circle
			(at -0.65 1.3 180)
			(size 0.254 0.254)
			(layers "F.Cu" "F.Mask" "F.Paste")
			(net 404 "Net-(C58-Pad2)")
			(pinfunction "VCC0P9_CIO")
			(pintype "power_in")
		)
		(pad "R12" smd circle
			(at 0 1.3 180)
			(size 0.254 0.254)
			(layers "F.Cu" "F.Mask" "F.Paste")
			(net 404 "Net-(C58-Pad2)")
			(pinfunction "VCC0P9_CIO")
			(pintype "passive")
		)
		(pad "R13" smd circle
			(at 0.65 1.3 180)
			(size 0.254 0.254)
			(layers "F.Cu" "F.Mask" "F.Paste")
			(net 181 "Net-(U4A-VCC3P3_S0)")
			(pinfunction "VCC3P3_S0")
			(pintype "power_in")
		)
		(pad "R15" smd circle
			(at 1.3 1.3 180)
			(size 0.254 0.254)
			(layers "F.Cu" "F.Mask" "F.Paste")
			(net 405 "Net-(C66-Pad2)")
			(pinfunction "VCC0P9_USB")
			(pintype "power_in")
		)
		(pad "R16" smd circle
			(at 1.95 1.3 180)
			(size 0.254 0.254)
			(layers "F.Cu" "F.Mask" "F.Paste")
			(net 405 "Net-(C66-Pad2)")
			(pinfunction "VCC0P9_USB")
			(pintype "passive")
		)
		(pad "R18" smd circle
			(at 2.6 1.3 180)
			(size 0.254 0.254)
			(layers "F.Cu" "F.Mask" "F.Paste")
			(net 23 "GND")
			(pinfunction "VSS_ANA")
			(pintype "passive")
		)
		(pad "R19" smd circle
			(at 3.25 1.3 180)
			(size 0.254 0.254)
			(layers "F.Cu" "F.Mask" "F.Paste")
			(net 23 "GND")
			(pinfunction "VSS_ANA")
			(pintype "passive")
		)
		(pad "R20" smd circle
			(at 3.9 1.3 180)
			(size 0.254 0.254)
			(layers "F.Cu" "F.Mask" "F.Paste")
			(net 23 "GND")
			(pinfunction "VSS_ANA")
			(pintype "passive")
		)
		(pad "R22" smd circle
			(at 4.6 1.38 180)
			(size 0.254 0.254)
			(layers "F.Cu" "F.Mask" "F.Paste")
			(net 23 "GND")
			(pinfunction "VSS_ANA")
			(pintype "passive")
		)
		(pad "R23" smd oval
			(at 5.06 1.38 270)
			(size 0.1578 0.3302)
			(layers "F.Cu" "F.Mask" "F.Paste")
			(net 23 "GND")
			(pinfunction "VSS_ANA")
			(pintype "passive")
		)
		(pad "T1" smd oval
			(at -5.06 1.84 270)
			(size 0.1578 0.3302)
			(layers "F.Cu" "F.Mask" "F.Paste")
			(net 23 "GND")
			(pinfunction "VSS_ANA")
			(pintype "passive")
		)
		(pad "T2" smd circle
			(at -4.6 1.84 180)
			(size 0.254 0.254)
			(layers "F.Cu" "F.Mask" "F.Paste")
			(net 23 "GND")
			(pinfunction "VSS_ANA")
			(pintype "passive")
		)
		(pad "T4" smd circle
			(at -3.9 1.95 180)
			(size 0.254 0.254)
			(layers "F.Cu" "F.Mask" "F.Paste")
			(net 226 "Net-(U4D-TCK)")
			(pinfunction "TCK")
			(pintype "input")
		)
		(pad "T5" smd circle
			(at -3.25 1.95 180)
			(size 0.254 0.254)
			(layers "F.Cu" "F.Mask" "F.Paste")
			(net 23 "GND")
			(pinfunction "VSS_ANA")
			(pintype "passive")
		)
		(pad "T6" smd circle
			(at -2.6 1.95 180)
			(size 0.254 0.254)
			(layers "F.Cu" "F.Mask" "F.Paste")
			(net 23 "GND")
			(pinfunction "VSS")
			(pintype "passive")
		)
		(pad "T8" smd circle
			(at -1.95 1.95 180)
			(size 0.254 0.254)
			(layers "F.Cu" "F.Mask" "F.Paste")
			(net 23 "GND")
			(pinfunction "VSS")
			(pintype "passive")
		)
		(pad "T9" smd circle
			(at -1.3 1.95 180)
			(size 0.254 0.254)
			(layers "F.Cu" "F.Mask" "F.Paste")
			(net 23 "GND")
			(pinfunction "VSS")
			(pintype "passive")
		)
		(pad "T11" smd circle
			(at -0.65 1.95 180)
			(size 0.254 0.254)
			(layers "F.Cu" "F.Mask" "F.Paste")
			(net 402 "Net-(C52-Pad2)")
			(pinfunction "VCC0P9_DP")
			(pintype "passive")
		)
		(pad "T12" smd circle
			(at 0 1.95 180)
			(size 0.254 0.254)
			(layers "F.Cu" "F.Mask" "F.Paste")
			(net 402 "Net-(C52-Pad2)")
			(pinfunction "VCC0P9_DP")
			(pintype "passive")
		)
		(pad "T13" smd circle
			(at 0.65 1.95 180)
			(size 0.254 0.254)
			(layers "F.Cu" "F.Mask" "F.Paste")
			(net 23 "GND")
			(pinfunction "VSS")
			(pintype "passive")
		)
		(pad "T15" smd circle
			(at 1.3 1.95 180)
			(size 0.254 0.254)
			(layers "F.Cu" "F.Mask" "F.Paste")
			(net 23 "GND")
			(pinfunction "VSS")
			(pintype "passive")
		)
		(pad "T16" smd circle
			(at 1.95 1.95 180)
			(size 0.254 0.254)
			(layers "F.Cu" "F.Mask" "F.Paste")
			(net 23 "GND")
			(pinfunction "VSS")
			(pintype "passive")
		)
		(pad "T18" smd circle
			(at 2.6 1.95 180)
			(size 0.254 0.254)
			(layers "F.Cu" "F.Mask" "F.Paste")
			(net 23 "GND")
			(pinfunction "VSS")
			(pintype "passive")
		)
		(pad "T19" smd circle
			(at 3.25 1.95 180)
			(size 0.254 0.254)
			(layers "F.Cu" "F.Mask" "F.Paste")
			(net 214 "/TB Controller/PCIE_CLK_JHL_N")
			(pinfunction "PCIE_REFCLK_100_IN_N")
			(pintype "input")
		)
		(pad "T20" smd circle
			(at 3.9 1.95 180)
			(size 0.254 0.254)
			(layers "F.Cu" "F.Mask" "F.Paste")
			(net 23 "GND")
			(pinfunction "VSS_ANA")
			(pintype "passive")
		)
		(pad "T22" smd circle
			(at 4.6 1.84 180)
			(size 0.254 0.254)
			(layers "F.Cu" "F.Mask" "F.Paste")
			(net 599 "/TB Controller/PCIex4.TX1-")
			(pinfunction "PCIE_RX1_N")
			(pintype "input")
		)
		(pad "T23" smd oval
			(at 5.06 1.84 270)
			(size 0.1578 0.3302)
			(layers "F.Cu" "F.Mask" "F.Paste")
			(net 600 "/TB Controller/PCIex4.TX1+")
			(pinfunction "PCIE_RX1_P")
			(pintype "input")
		)
		(pad "U1" smd oval
			(at -5.06 2.3 270)
			(size 0.1578 0.3302)
			(layers "F.Cu" "F.Mask" "F.Paste")
			(net 375 "/PD and TB DC-DC/I2C1.SDA")
			(pinfunction "GPIO_0")
			(pintype "bidirectional")
		)
		(pad "U2" smd circle
			(at -4.6 2.3 180)
			(size 0.254 0.254)
			(layers "F.Cu" "F.Mask" "F.Paste")
			(net 373 "/PD and TB DC-DC/I2C1.SCL")
			(pinfunction "GPIO_1")
			(pintype "bidirectional")
		)
		(pad "U22" smd circle
			(at 4.6 2.3 180)
			(size 0.254 0.254)
			(layers "F.Cu" "F.Mask" "F.Paste")
			(net 23 "GND")
			(pinfunction "VSS_ANA")
			(pintype "passive")
		)
		(pad "U23" smd oval
			(at 5.06 2.3 270)
			(size 0.1578 0.3302)
			(layers "F.Cu" "F.Mask" "F.Paste")
			(net 23 "GND")
			(pinfunction "VSS_ANA")
			(pintype "passive")
		)
		(pad "V1" smd oval
			(at -5.06 2.76 270)
			(size 0.1578 0.3302)
			(layers "F.Cu" "F.Mask" "F.Paste")
			(net 358 "/TB flash memory/FLASH_WP")
			(pinfunction "GPIO_2")
			(pintype "bidirectional")
		)
		(pad "V2" smd circle
			(at -4.6 2.76 180)
			(size 0.254 0.254)
			(layers "F.Cu" "F.Mask" "F.Paste")
			(net 186 "Net-(U4C-GPIO_3)")
			(pinfunction "GPIO_3")
			(pintype "bidirectional")
		)
		(pad "V4" smd circle
			(at -3.9 2.6 180)
			(size 0.254 0.254)
			(layers "F.Cu" "F.Mask" "F.Paste")
			(net 225 "Net-(U4D-TMS)")
			(pinfunction "TMS")
			(pintype "input")
		)
		(pad "V5" smd circle
			(at -3.25 2.6 180)
			(size 0.254 0.254)
			(layers "F.Cu" "F.Mask" "F.Paste")
			(net 23 "GND")
			(pinfunction "VSS_ANA")
			(pintype "passive")
		)
		(pad "V6" smd circle
			(at -2.6 2.6 180)
			(size 0.254 0.254)
			(layers "F.Cu" "F.Mask" "F.Paste")
			(net 23 "GND")
			(pinfunction "VSS_ANA")
			(pintype "passive")
		)
		(pad "V8" smd circle
			(at -1.95 2.6 180)
			(size 0.254 0.254)
			(layers "F.Cu" "F.Mask" "F.Paste")
			(net 23 "GND")
			(pinfunction "VSS_ANA")
			(pintype "passive")
		)
		(pad "V9" smd circle
			(at -1.3 2.6 180)
			(size 0.254 0.254)
			(layers "F.Cu" "F.Mask" "F.Paste")
			(net 23 "GND")
			(pinfunction "VSS_ANA")
			(pintype "passive")
		)
		(pad "V11" smd circle
			(at -0.65 2.6 180)
			(size 0.254 0.254)
			(layers "F.Cu" "F.Mask" "F.Paste")
			(net 402 "Net-(C52-Pad2)")
			(pinfunction "VCC0P9_ANA_DPSNK")
			(pintype "power_in")
		)
		(pad "V12" smd circle
			(at 0 2.6 180)
			(size 0.254 0.254)
			(layers "F.Cu" "F.Mask" "F.Paste")
			(net 402 "Net-(C52-Pad2)")
			(pinfunction "VCC0P9_ANA_DPSNK")
			(pintype "passive")
		)
		(pad "V13" smd circle
			(at 0.65 2.6 180)
			(size 0.254 0.254)
			(layers "F.Cu" "F.Mask" "F.Paste")
			(net 402 "Net-(C52-Pad2)")
			(pinfunction "VCC0P9_ANA_DPSNK")
			(pintype "passive")
		)
		(pad "V15" smd circle
			(at 1.3 2.6 180)
			(size 0.254 0.254)
			(layers "F.Cu" "F.Mask" "F.Paste")
			(net 23 "GND")
			(pinfunction "VSS_ANA")
			(pintype "passive")
		)
		(pad "V16" smd circle
			(at 1.95 2.6 180)
			(size 0.254 0.254)
			(layers "F.Cu" "F.Mask" "F.Paste")
			(net 23 "GND")
			(pinfunction "VSS_ANA")
			(pintype "passive")
		)
		(pad "V18" smd circle
			(at 2.6 2.6 180)
			(size 0.254 0.254)
			(layers "F.Cu" "F.Mask" "F.Paste")
			(net 281 "unconnected-(U4F-PCIE_ATEST-PadV18)")
			(pinfunction "PCIE_ATEST")
			(pintype "passive+no_connect")
		)
		(pad "V19" smd circle
			(at 3.25 2.6 180)
			(size 0.254 0.254)
			(layers "F.Cu" "F.Mask" "F.Paste")
			(net 213 "/TB Controller/PCIE_CLK_JHL_P")
			(pinfunction "PCIE_REFCLK_100_IN_P")
			(pintype "input")
		)
		(pad "V20" smd circle
			(at 3.9 2.6 180)
			(size 0.254 0.254)
			(layers "F.Cu" "F.Mask" "F.Paste")
			(net 23 "GND")
			(pinfunction "VSS_ANA")
			(pintype "passive")
		)
		(pad "V22" smd circle
			(at 4.6 2.76 180)
			(size 0.254 0.254)
			(layers "F.Cu" "F.Mask" "F.Paste")
			(net 315 "/TB Controller/TB_PCIE_TX0_N")
			(pinfunction "PCIE_TX0_N")
			(pintype "input")
		)
		(pad "V23" smd oval
			(at 5.06 2.76 270)
			(size 0.1578 0.3302)
			(layers "F.Cu" "F.Mask" "F.Paste")
			(net 323 "/TB Controller/TB_PCIE_TX0_P")
			(pinfunction "PCIE_TX0_P")
			(pintype "input")
		)
		(pad "W1" smd oval
			(at -5.06 3.22 270)
			(size 0.1578 0.3302)
			(layers "F.Cu" "F.Mask" "F.Paste")
			(net 187 "Net-(U4C-GPIO_4)")
			(pinfunction "GPIO_4")
			(pintype "bidirectional")
		)
		(pad "W2" smd circle
			(at -4.6 3.22 180)
			(size 0.254 0.254)
			(layers "F.Cu" "F.Mask" "F.Paste")
			(net 188 "Net-(U4C-GPIO_5)")
			(pinfunction "GPIO_5")
			(pintype "bidirectional")
		)
		(pad "W4" smd circle
			(at -3.9 3.25 180)
			(size 0.254 0.254)
			(layers "F.Cu" "F.Mask" "F.Paste")
			(net 227 "Net-(U4D-TDO)")
			(pinfunction "TDO")
			(pintype "output")
		)
		(pad "W5" smd circle
			(at -3.25 3.25 180)
			(size 0.254 0.254)
			(layers "F.Cu" "F.Mask" "F.Paste")
			(net 23 "GND")
			(pinfunction "VSS_ANA")
			(pintype "passive")
		)
		(pad "W6" smd circle
			(at -2.6 3.25 180)
			(size 0.254 0.254)
			(layers "F.Cu" "F.Mask" "F.Paste")
			(net 23 "GND")
			(pinfunction "VSS_ANA")
			(pintype "passive")
		)
		(pad "W8" smd circle
			(at -1.95 3.25 180)
			(size 0.254 0.254)
			(layers "F.Cu" "F.Mask" "F.Paste")
			(net 23 "GND")
			(pinfunction "VSS_ANA")
			(pintype "passive")
		)
		(pad "W9" smd circle
			(at -1.3 3.25 180)
			(size 0.254 0.254)
			(layers "F.Cu" "F.Mask" "F.Paste")
			(net 23 "GND")
			(pinfunction "VSS_ANA")
			(pintype "passive")
		)
		(pad "W11" smd circle
			(at -0.65 3.25 180)
			(size 0.254 0.254)
			(layers "F.Cu" "F.Mask" "F.Paste")
			(net 282 "unconnected-(U4C-DPSNK0_AUX_N-PadW11)")
			(pinfunction "DPSNK0_AUX_N")
			(pintype "bidirectional+no_connect")
		)
		(pad "W12" smd circle
			(at 0 3.25 180)
			(size 0.254 0.254)
			(layers "F.Cu" "F.Mask" "F.Paste")
			(net 283 "unconnected-(U4C-DPSNK1_AUX_N-PadW12)")
			(pinfunction "DPSNK1_AUX_N")
			(pintype "bidirectional+no_connect")
		)
		(pad "W13" smd circle
			(at 0.65 3.25 180)
			(size 0.254 0.254)
			(layers "F.Cu" "F.Mask" "F.Paste")
			(net 23 "GND")
			(pinfunction "MONDC_DPSNK_0")
			(pintype "passive")
		)
		(pad "W15" smd circle
			(at 1.3 3.25 180)
			(size 0.254 0.254)
			(layers "F.Cu" "F.Mask" "F.Paste")
			(net 240 "/TB Controller/PA_AUX_N")
			(pinfunction "PA_DPSRC_AUX_N")
			(pintype "bidirectional")
		)
		(pad "W16" smd circle
			(at 1.95 3.25 180)
			(size 0.254 0.254)
			(layers "F.Cu" "F.Mask" "F.Paste")
			(net 284 "unconnected-(U4E-PB_DPSRC_AUX_N-PadW16)")
			(pinfunction "PB_DPSRC_AUX_N")
			(pintype "bidirectional+no_connect")
		)
		(pad "W18" smd circle
			(at 2.6 3.25 180)
			(size 0.254 0.254)
			(layers "F.Cu" "F.Mask" "F.Paste")
			(net 23 "GND")
			(pinfunction "MONDC_DPSNK_1")
			(pintype "passive")
		)
		(pad "W19" smd circle
			(at 3.25 3.25 180)
			(size 0.254 0.254)
			(layers "F.Cu" "F.Mask" "F.Paste")
			(net 285 "unconnected-(U4C-DPSRC_AUX_P-PadW19)")
			(pinfunction "DPSRC_AUX_P")
			(pintype "bidirectional+no_connect")
		)
		(pad "W20" smd circle
			(at 3.9 3.25 180)
			(size 0.254 0.254)
			(layers "F.Cu" "F.Mask" "F.Paste")
			(net 23 "GND")
			(pinfunction "VSS_ANA")
			(pintype "passive")
		)
		(pad "W22" smd circle
			(at 4.6 3.22 180)
			(size 0.254 0.254)
			(layers "F.Cu" "F.Mask" "F.Paste")
			(net 23 "GND")
			(pinfunction "VSS_ANA")
			(pintype "passive")
		)
		(pad "W23" smd oval
			(at 5.06 3.22 270)
			(size 0.1578 0.3302)
			(layers "F.Cu" "F.Mask" "F.Paste")
			(net 23 "GND")
			(pinfunction "VSS_ANA")
			(pintype "passive")
		)
		(pad "Y1" smd oval
			(at -5.06 3.68 270)
			(size 0.1578 0.3302)
			(layers "F.Cu" "F.Mask" "F.Paste")
			(net 189 "Net-(U4C-GPIO_6)")
			(pinfunction "GPIO_6")
			(pintype "bidirectional")
		)
		(pad "Y2" smd circle
			(at -4.6 3.68 180)
			(size 0.254 0.254)
			(layers "F.Cu" "F.Mask" "F.Paste")
			(net 190 "Net-(U4C-GPIO_7)")
			(pinfunction "GPIO_7")
			(pintype "bidirectional")
		)
		(pad "Y4" smd circle
			(at -3.9 3.9 180)
			(size 0.254 0.254)
			(layers "F.Cu" "F.Mask" "F.Paste")
			(net 224 "Net-(U4D-TDI)")
			(pinfunction "TDI")
			(pintype "input")
		)
		(pad "Y5" smd circle
			(at -3.25 3.9 180)
			(size 0.254 0.254)
			(layers "F.Cu" "F.Mask" "F.Paste")
			(net 218 "Net-(U4C-DPSNK0_DDC_CLK)")
			(pinfunction "DPSNK0_DDC_CLK")
			(pintype "passive")
		)
		(pad "Y6" smd circle
			(at -2.6 3.9 180)
			(size 0.254 0.254)
			(layers "F.Cu" "F.Mask" "F.Paste")
			(net 220 "Net-(U4C-DPSNK1_HPD)")
			(pinfunction "DPSNK1_HPD")
			(pintype "passive")
		)
		(pad "Y8" smd circle
			(at -1.95 3.9 180)
			(size 0.254 0.254)
			(layers "F.Cu" "F.Mask" "F.Paste")
			(net 221 "Net-(U4C-DPSNK1_DDC_CLK)")
			(pinfunction "DPSNK1_DDC_CLK")
			(pintype "passive")
		)
		(pad "Y9" smd circle
			(at -1.3 3.9 180)
			(size 0.254 0.254)
			(layers "F.Cu" "F.Mask" "F.Paste")
			(net 23 "GND")
			(pinfunction "VSS_ANA")
			(pintype "passive")
		)
		(pad "Y11" smd circle
			(at -0.65 3.9 180)
			(size 0.254 0.254)
			(layers "F.Cu" "F.Mask" "F.Paste")
			(net 286 "unconnected-(U4C-DPSNK0_AUXP-PadY11)")
			(pinfunction "DPSNK0_AUXP")
			(pintype "bidirectional+no_connect")
		)
		(pad "Y12" smd circle
			(at 0 3.9 180)
			(size 0.254 0.254)
			(layers "F.Cu" "F.Mask" "F.Paste")
			(net 287 "unconnected-(U4C-DPSNK1_AUXP-PadY12)")
			(pinfunction "DPSNK1_AUXP")
			(pintype "bidirectional+no_connect")
		)
		(pad "Y13" smd circle
			(at 0.65 3.9 180)
			(size 0.254 0.254)
			(layers "F.Cu" "F.Mask" "F.Paste")
			(net 23 "GND")
			(pinfunction "VSS_ANA")
			(pintype "passive")
		)
		(pad "Y15" smd circle
			(at 1.3 3.9 180)
			(size 0.254 0.254)
			(layers "F.Cu" "F.Mask" "F.Paste")
			(net 239 "/TB Controller/PA_AUX_P")
			(pinfunction "PA_DPSRC_AUX_P")
			(pintype "bidirectional")
		)
		(pad "Y16" smd circle
			(at 1.95 3.9 180)
			(size 0.254 0.254)
			(layers "F.Cu" "F.Mask" "F.Paste")
			(net 288 "unconnected-(U4E-PB_DPSRC_AUX_P-PadY16)")
			(pinfunction "PB_DPSRC_AUX_P")
			(pintype "bidirectional+no_connect")
		)
		(pad "Y18" smd circle
			(at 2.6 3.9 180)
			(size 0.254 0.254)
			(layers "F.Cu" "F.Mask" "F.Paste")
			(net 223 "Net-(U4C-DPSNK_RBIAS)")
			(pinfunction "DPSNK_RBIAS")
			(pintype "passive")
		)
		(pad "Y19" smd circle
			(at 3.25 3.9 180)
			(size 0.254 0.254)
			(layers "F.Cu" "F.Mask" "F.Paste")
			(net 289 "unconnected-(U4C-DPSRC_AUX_N-PadY19)")
			(pinfunction "DPSRC_AUX_N")
			(pintype "bidirectional+no_connect")
		)
		(pad "Y20" smd circle
			(at 3.9 3.9 180)
			(size 0.254 0.254)
			(layers "F.Cu" "F.Mask" "F.Paste")
			(net 23 "GND")
			(pinfunction "VSS_ANA")
			(pintype "passive")
		)
		(pad "Y22" smd circle
			(at 4.6 3.68 180)
			(size 0.254 0.254)
			(layers "F.Cu" "F.Mask" "F.Paste")
			(net 597 "/TB Controller/PCIex4.TX0-")
			(pinfunction "PCIE_RX0_N")
			(pintype "input")
		)
		(pad "Y23" smd oval
			(at 5.06 3.68 270)
			(size 0.1578 0.3302)
			(layers "F.Cu" "F.Mask" "F.Paste")
			(net 596 "/TB Controller/PCIex4.TX0+")
			(pinfunction "PCIE_RX0_P")
			(pintype "input")
		)
	)
	(footprint "antmicro-footprints:C_0402_1005Metric"
		(layer "F.Cu")
		(at 153.8 46.9)
		(descr "Capacitor SMD 0402")
		(tags "capacitor SMD 0402")
		(property "Reference" "C312"
			(at -3.8 0.2 0)
			(layer "F.SilkS")
			(effects
				(font
					(size 0.7 0.7)
					(thickness 0.15)
				)
				(justify left bottom)
			)
		)
		(property "Value" "C_100n_0402"
			(at -1.022927 2.155213 0)
			(layer "F.Fab")
			(effects
				(font
					(size 0.7 0.7)
					(thickness 0.15)
				)
				(justify left bottom)
			)
		)
		(property "Datasheet" "https://www.murata.com/products/productdetail?partno=GRM155R61H104KE14%23"
			(at 0 0 0)
			(layer "F.Fab")
			(hide yes)
			(effects
				(font
					(size 1.27 1.27)
					(thickness 0.15)
				)
			)
		)
		(property "Description" "SMD Multilayer Ceramic Capacitor, 0.1 µF, 50 V, 0402 [1005 Metric], ± 10%, X5R, GRM Series"
			(at 0 0 0)
			(layer "F.Fab")
			(hide yes)
			(effects
				(font
					(size 1.27 1.27)
					(thickness 0.15)
				)
			)
		)
		(property "MPN" "GRM155R61H104KE14D"
			(at 0 0 0)
			(unlocked yes)
			(layer "F.Fab")
			(hide yes)
			(effects
				(font
					(size 1 1)
					(thickness 0.15)
				)
			)
		)
		(property "Manufacturer" "Murata"
			(at 0 0 0)
			(unlocked yes)
			(layer "F.Fab")
			(hide yes)
			(effects
				(font
					(size 1 1)
					(thickness 0.15)
				)
			)
		)
		(property "License" "Apache-2.0"
			(at 0 0 0)
			(unlocked yes)
			(layer "F.Fab")
			(hide yes)
			(effects
				(font
					(size 1 1)
					(thickness 0.15)
				)
			)
		)
		(property "Author" "Antmicro"
			(at 0 0 0)
			(unlocked yes)
			(layer "F.Fab")
			(hide yes)
			(effects
				(font
					(size 1 1)
					(thickness 0.15)
				)
			)
		)
		(property "Val" "100n"
			(at 0 0 0)
			(unlocked yes)
			(layer "F.Fab")
			(hide yes)
			(effects
				(font
					(size 1 1)
					(thickness 0.15)
				)
			)
		)
		(property "Voltage" "50V"
			(at 0 0 0)
			(unlocked yes)
			(layer "F.Fab")
			(hide yes)
			(effects
				(font
					(size 1 1)
					(thickness 0.15)
				)
			)
		)
		(property "Dielectric" "X5R"
			(at 0 0 0)
			(unlocked yes)
			(layer "F.Fab")
			(hide yes)
			(effects
				(font
					(size 1 1)
					(thickness 0.15)
				)
			)
		)
		(sheetname "/Power input/")
		(sheetfile "power_input.kicad_sch")
		(attr smd)
		(fp_rect
			(start -0.925 -0.47)
			(end 0.925 0.47)
			(stroke
				(width 0.05)
				(type default)
			)
			(fill no)
			(layer "F.CrtYd")
		)
		(fp_line
			(start -0.494 -0.25)
			(end 0.504 -0.25)
			(stroke
				(width 0.15)
				(type solid)
			)
			(layer "F.Fab")
		)
		(fp_line
			(start -0.494 0.248)
			(end -0.494 -0.25)
			(stroke
				(width 0.15)
				(type solid)
			)
			(layer "F.Fab")
		)
		(fp_line
			(start 0.504 -0.25)
			(end 0.504 0.248)
			(stroke
				(width 0.15)
				(type solid)
			)
			(layer "F.Fab")
		)
		(fp_line
			(start 0.504 0.248)
			(end -0.494 0.248)
			(stroke
				(width 0.15)
				(type solid)
			)
			(layer "F.Fab")
		)
		(fp_text user "${REFERENCE}"
			(at -0.939 4.599 0)
			(layer "F.Fab")
			(effects
				(font
					(size 0.7 0.7)
					(thickness 0.15)
				)
				(justify left bottom)
			)
		)
		(fp_text user "License: Apache-2.0"
			(at -0.939 5.799 0)
			(layer "F.Fab")
			(effects
				(font
					(size 0.7 0.7)
					(thickness 0.15)
				)
				(justify left bottom)
			)
		)
		(fp_text user "Author: Antmicro"
			(at -0.939 3.399 0)
			(layer "F.Fab")
			(effects
				(font
					(size 0.7 0.7)
					(thickness 0.15)
				)
				(justify left bottom)
			)
		)
		(pad "1" smd roundrect
			(at -0.48 0)
			(size 0.59 0.64)
			(layers "F.Cu" "F.Mask" "F.Paste")
			(roundrect_rratio 0.25)
			(net 23 "GND")
			(pintype "passive")
		)
		(pad "2" smd roundrect
			(at 0.48 0)
			(size 0.59 0.64)
			(layers "F.Cu" "F.Mask" "F.Paste")
			(roundrect_rratio 0.25)
			(net 344 "/Power input/5V_EN")
			(pintype "passive")
		)
	)
	(footprint "antmicro-footprints:C_0603_1608Metric_EIA"
		(layer "F.Cu")
		(at 162.6 114.35)
		(descr "Capacitor SMD 0603, IPC-7351 Density Level A")
		(tags "Capacitor 0603")
		(property "Reference" "C107"
			(at 12.450003 16.600001 0)
			(layer "F.SilkS")
			(effects
				(font
					(size 0.7 0.7)
					(thickness 0.15)
				)
			)
		)
		(property "Value" "C_22u_16V_0603"
			(at -1.42757 1.770288 0)
			(layer "F.Fab")
			(effects
				(font
					(size 0.7 0.7)
					(thickness 0.15)
				)
				(justify left bottom)
			)
		)
		(property "Datasheet" "https://product.samsungsem.com/mlcc/CL10A226MO7JZN.do"
			(at 0 0 0)
			(layer "F.Fab")
			(hide yes)
			(effects
				(font
					(size 1.27 1.27)
					(thickness 0.15)
				)
			)
		)
		(property "Description" "SMD Multilayer Ceramic Capacitor"
			(at 0 0 0)
			(layer "F.Fab")
			(hide yes)
			(effects
				(font
					(size 1.27 1.27)
					(thickness 0.15)
				)
			)
		)
		(property "MPN" "CL10A226MO7JZNC"
			(at 0 0 0)
			(unlocked yes)
			(layer "F.Fab")
			(hide yes)
			(effects
				(font
					(size 1 1)
					(thickness 0.15)
				)
			)
		)
		(property "Manufacturer" "Samsung Electro-Mechanics"
			(at 0 0 0)
			(unlocked yes)
			(layer "F.Fab")
			(hide yes)
			(effects
				(font
					(size 1 1)
					(thickness 0.15)
				)
			)
		)
		(property "License" "Apache-2.0"
			(at 0 0 0)
			(unlocked yes)
			(layer "F.Fab")
			(hide yes)
			(effects
				(font
					(size 1 1)
					(thickness 0.15)
				)
			)
		)
		(property "Author" "Antmicro"
			(at 0 0 0)
			(unlocked yes)
			(layer "F.Fab")
			(hide yes)
			(effects
				(font
					(size 1 1)
					(thickness 0.15)
				)
			)
		)
		(property "Val" "22u"
			(at 0 0 0)
			(unlocked yes)
			(layer "F.Fab")
			(hide yes)
			(effects
				(font
					(size 1 1)
					(thickness 0.15)
				)
			)
		)
		(property "Voltage" "16V"
			(at 0 0 0)
			(unlocked yes)
			(layer "F.Fab")
			(hide yes)
			(effects
				(font
					(size 1 1)
					(thickness 0.15)
				)
			)
		)
		(property "Dielectric" ""
			(at 0 0 0)
			(unlocked yes)
			(layer "F.Fab")
			(hide yes)
			(effects
				(font
					(size 1 1)
					(thickness 0.15)
				)
			)
		)
		(sheetname "/X710 DCDC converters/")
		(sheetfile "DCDC_converters_X710.kicad_sch")
		(attr smd)
		(fp_line
			(start -0.15 -0.55)
			(end 0.15 -0.55)
			(stroke
				(width 0.15)
				(type solid)
			)
			(layer "F.SilkS")
		)
		(fp_line
			(start -0.15 0.55)
			(end 0.15 0.55)
			(stroke
				(width 0.15)
				(type solid)
			)
			(layer "F.SilkS")
		)
		(fp_rect
			(start -1.25 -0.65)
			(end 1.25 0.65)
			(stroke
				(width 0.05)
				(type solid)
			)
			(fill no)
			(layer "F.CrtYd")
		)
		(fp_rect
			(start -0.8 -0.45)
			(end 0.8 0.45)
			(stroke
				(width 0.15)
				(type solid)
			)
			(fill no)
			(layer "F.Fab")
		)
		(fp_text user "License: Apache-2.0"
			(at -1.682 5.895 0)
			(layer "F.Fab")
			(effects
				(font
					(size 0.7 0.7)
					(thickness 0.15)
				)
				(justify left bottom)
			)
		)
		(fp_text user "${REFERENCE}"
			(at -1.682 3.895 0)
			(layer "F.Fab")
			(effects
				(font
					(size 0.7 0.7)
					(thickness 0.15)
				)
				(justify left bottom)
			)
		)
		(fp_text user "Author: Antmicro"
			(at -1.682 4.894 0)
			(layer "F.Fab")
			(effects
				(font
					(size 0.7 0.7)
					(thickness 0.15)
				)
				(justify left bottom)
			)
		)
		(pad "1" smd roundrect
			(at -0.7 0)
			(size 0.8 1.1)
			(layers "F.Cu" "F.Mask" "F.Paste")
			(roundrect_rratio 0.2)
			(net 23 "GND")
			(pintype "passive")
		)
		(pad "2" smd roundrect
			(at 0.7 0)
			(size 0.8 1.1)
			(layers "F.Cu" "F.Mask" "F.Paste")
			(roundrect_rratio 0.2)
			(net 40 "+5V")
			(pintype "passive")
		)
	)
	(footprint "antmicro-footprints:R_0402_1005Metric"
		(layer "F.Cu")
		(at 155.255 67.124999 -90)
		(descr "Resistor SMD 0402")
		(tags "resistor SMD 0402")
		(property "Reference" "R144"
			(at -12.324999 -20.295 270)
			(layer "F.SilkS")
			(effects
				(font
					(size 0.7 0.7)
					(thickness 0.15)
				)
			)
		)
		(property "Value" "R_100k_0402"
			(at -1.011843 1.772047 270)
			(layer "F.Fab")
			(effects
				(font
					(size 0.7 0.7)
					(thickness 0.15)
				)
				(justify left bottom)
			)
		)
		(property "Datasheet" "https://www.bourns.com/docs/product-datasheets/cr.pdf"
			(at 0 0 270)
			(layer "F.Fab")
			(hide yes)
			(effects
				(font
					(size 1.27 1.27)
					(thickness 0.15)
				)
			)
		)
		(property "Description" "SMD Chip Resistor, 100 kohm, ± 1%, 62.5 mW, 0402 [1005 Metric], Thick Film, General Purpose"
			(at 0 0 270)
			(layer "F.Fab")
			(hide yes)
			(effects
				(font
					(size 1.27 1.27)
					(thickness 0.15)
				)
			)
		)
		(property "MPN" "CR0402-FX-1003GLF"
			(at 0 0 270)
			(unlocked yes)
			(layer "F.Fab")
			(hide yes)
			(effects
				(font
					(size 1 1)
					(thickness 0.15)
				)
			)
		)
		(property "Manufacturer" "Bourns"
			(at 0 0 270)
			(unlocked yes)
			(layer "F.Fab")
			(hide yes)
			(effects
				(font
					(size 1 1)
					(thickness 0.15)
				)
			)
		)
		(property "License" "Apache-2.0"
			(at 0 0 270)
			(unlocked yes)
			(layer "F.Fab")
			(hide yes)
			(effects
				(font
					(size 1 1)
					(thickness 0.15)
				)
			)
		)
		(property "Author" "Antmicro"
			(at 0 0 270)
			(unlocked yes)
			(layer "F.Fab")
			(hide yes)
			(effects
				(font
					(size 1 1)
					(thickness 0.15)
				)
			)
		)
		(property "Val" "100k"
			(at 0 0 270)
			(unlocked yes)
			(layer "F.Fab")
			(hide yes)
			(effects
				(font
					(size 1 1)
					(thickness 0.15)
				)
			)
		)
		(property "Tolerance" "1%"
			(at 0 0 270)
			(unlocked yes)
			(layer "F.Fab")
			(hide yes)
			(effects
				(font
					(size 1 1)
					(thickness 0.15)
				)
			)
		)
		(sheetname "/X710-AT2 Misc/")
		(sheetfile "x710-at2-mics.kicad_sch")
		(attr smd)
		(fp_rect
			(start -0.925 -0.47)
			(end 0.925 0.47)
			(stroke
				(width 0.05)
				(type default)
			)
			(fill no)
			(layer "F.CrtYd")
		)
		(fp_rect
			(start -0.5 -0.25)
			(end 0.5 0.25)
			(stroke
				(width 0.15)
				(type solid)
			)
			(fill no)
			(layer "F.Fab")
		)
		(fp_text user "Author: Antmicro"
			(at -0.95 4.169 270)
			(layer "F.Fab")
			(effects
				(font
					(size 0.7 0.7)
					(thickness 0.15)
				)
				(justify left bottom)
			)
		)
		(fp_text user "${REFERENCE}"
			(at -0.95 3.168 270)
			(layer "F.Fab")
			(effects
				(font
					(size 0.7 0.7)
					(thickness 0.15)
				)
				(justify left bottom)
			)
		)
		(fp_text user "License: Apache-2.0"
			(at -0.95 5.169 270)
			(layer "F.Fab")
			(effects
				(font
					(size 0.7 0.7)
					(thickness 0.15)
				)
				(justify left bottom)
			)
		)
		(pad "1" smd roundrect
			(at -0.48 0 270)
			(size 0.59 0.64)
			(layers "F.Cu" "F.Mask" "F.Paste")
			(roundrect_rratio 0.25)
			(net 137 "/X710-AT2 Misc/NCSI.RXD_1")
			(pintype "passive")
		)
		(pad "2" smd roundrect
			(at 0.48 0 270)
			(size 0.59 0.64)
			(layers "F.Cu" "F.Mask" "F.Paste")
			(roundrect_rratio 0.25)
			(net 7 "+3V3")
			(pintype "passive")
		)
	)
	(footprint "antmicro-footprints:C_0603_1608Metric_EIA"
		(layer "F.Cu")
		(at 138.705 89.274999 -90)
		(descr "Capacitor SMD 0603, IPC-7351 Density Level A")
		(tags "Capacitor 0603")
		(property "Reference" "C239"
			(at 4.225001 17.455 270)
			(layer "F.SilkS")
			(effects
				(font
					(size 0.7 0.7)
					(thickness 0.15)
				)
				(justify left bottom)
			)
		)
		(property "Value" "C_22u_16V_0603"
			(at -1.42757 1.770288 270)
			(layer "F.Fab")
			(effects
				(font
					(size 0.7 0.7)
					(thickness 0.15)
				)
				(justify left bottom)
			)
		)
		(property "Datasheet" "https://product.samsungsem.com/mlcc/CL10A226MO7JZN.do"
			(at 0 0 270)
			(layer "F.Fab")
			(hide yes)
			(effects
				(font
					(size 1.27 1.27)
					(thickness 0.15)
				)
			)
		)
		(property "Description" "SMD Multilayer Ceramic Capacitor"
			(at 0 0 270)
			(layer "F.Fab")
			(hide yes)
			(effects
				(font
					(size 1.27 1.27)
					(thickness 0.15)
				)
			)
		)
		(property "MPN" "CL10A226MO7JZNC"
			(at 0 0 270)
			(unlocked yes)
			(layer "F.Fab")
			(hide yes)
			(effects
				(font
					(size 1 1)
					(thickness 0.15)
				)
			)
		)
		(property "Manufacturer" "Samsung Electro-Mechanics"
			(at 0 0 270)
			(unlocked yes)
			(layer "F.Fab")
			(hide yes)
			(effects
				(font
					(size 1 1)
					(thickness 0.15)
				)
			)
		)
		(property "License" "Apache-2.0"
			(at 0 0 270)
			(unlocked yes)
			(layer "F.Fab")
			(hide yes)
			(effects
				(font
					(size 1 1)
					(thickness 0.15)
				)
			)
		)
		(property "Author" "Antmicro"
			(at 0 0 270)
			(unlocked yes)
			(layer "F.Fab")
			(hide yes)
			(effects
				(font
					(size 1 1)
					(thickness 0.15)
				)
			)
		)
		(property "Val" "22u"
			(at 0 0 270)
			(unlocked yes)
			(layer "F.Fab")
			(hide yes)
			(effects
				(font
					(size 1 1)
					(thickness 0.15)
				)
			)
		)
		(property "Voltage" "16V"
			(at 0 0 270)
			(unlocked yes)
			(layer "F.Fab")
			(hide yes)
			(effects
				(font
					(size 1 1)
					(thickness 0.15)
				)
			)
		)
		(property "Dielectric" ""
			(at 0 0 270)
			(unlocked yes)
			(layer "F.Fab")
			(hide yes)
			(effects
				(font
					(size 1 1)
					(thickness 0.15)
				)
			)
		)
		(sheetname "/X710-AT2 power/")
		(sheetfile "x710-at2-power.kicad_sch")
		(attr smd)
		(fp_line
			(start -0.15 0.55)
			(end 0.15 0.55)
			(stroke
				(width 0.15)
				(type solid)
			)
			(layer "F.SilkS")
		)
		(fp_line
			(start -0.15 -0.55)
			(end 0.15 -0.55)
			(stroke
				(width 0.15)
				(type solid)
			)
			(layer "F.SilkS")
		)
		(fp_rect
			(start -1.25 -0.65)
			(end 1.25 0.65)
			(stroke
				(width 0.05)
				(type solid)
			)
			(fill no)
			(layer "F.CrtYd")
		)
		(fp_rect
			(start -0.8 -0.45)
			(end 0.8 0.45)
			(stroke
				(width 0.15)
				(type solid)
			)
			(fill no)
			(layer "F.Fab")
		)
		(fp_text user "${REFERENCE}"
			(at -1.682 3.895 270)
			(layer "F.Fab")
			(effects
				(font
					(size 0.7 0.7)
					(thickness 0.15)
				)
				(justify left bottom)
			)
		)
		(fp_text user "License: Apache-2.0"
			(at -1.682 5.895 270)
			(layer "F.Fab")
			(effects
				(font
					(size 0.7 0.7)
					(thickness 0.15)
				)
				(justify left bottom)
			)
		)
		(fp_text user "Author: Antmicro"
			(at -1.682 4.894 270)
			(layer "F.Fab")
			(effects
				(font
					(size 0.7 0.7)
					(thickness 0.15)
				)
				(justify left bottom)
			)
		)
		(pad "1" smd roundrect
			(at -0.7 0 270)
			(size 0.8 1.1)
			(layers "F.Cu" "F.Mask" "F.Paste")
			(roundrect_rratio 0.2)
			(net 23 "GND")
			(pintype "passive")
		)
		(pad "2" smd roundrect
			(at 0.7 0 270)
			(size 0.8 1.1)
			(layers "F.Cu" "F.Mask" "F.Paste")
			(roundrect_rratio 0.2)
			(net 7 "+3V3")
			(pintype "passive")
		)
	)
	(footprint "antmicro-footprints:L_Vishay-IHLP1616BZ"
		(layer "F.Cu")
		(at 138.5 124.7 90)
		(property "Reference" "L2"
			(at 1.3 -2.5 90)
			(layer "F.SilkS")
			(effects
				(font
					(size 0.7 0.7)
					(thickness 0.15)
				)
				(justify left bottom)
			)
		)
		(property "Value" "L_680n_7.6A_IHLP1616BZ"
			(at -0.016 3.253 90)
			(layer "F.Fab")
			(effects
				(font
					(size 0.7 0.7)
					(thickness 0.15)
				)
				(justify left bottom)
			)
		)
		(property "Datasheet" "https://www.mouser.com/datasheet/2/427/ihlp1616bz5a-1763007.pdf"
			(at 0 0 90)
			(layer "F.Fab")
			(hide yes)
			(effects
				(font
					(size 1.27 1.27)
					(thickness 0.15)
				)
			)
		)
		(property "Description" "Power Inductor (SMT), 680 nH, 7.6 A, Shielded, 6.8 A, IHLP-1616BZ-5A"
			(at 0 0 90)
			(layer "F.Fab")
			(hide yes)
			(effects
				(font
					(size 1.27 1.27)
					(thickness 0.15)
				)
			)
		)
		(property "Val" "680n/7.6A"
			(at 0 0 90)
			(unlocked yes)
			(layer "F.Fab")
			(hide yes)
			(effects
				(font
					(size 1 1)
					(thickness 0.15)
				)
			)
		)
		(property "Manufacturer" "Vishay"
			(at 0 0 90)
			(unlocked yes)
			(layer "F.Fab")
			(hide yes)
			(effects
				(font
					(size 1 1)
					(thickness 0.15)
				)
			)
		)
		(property "MPN" "IHLP1616BZERR68M5A"
			(at 0 0 90)
			(unlocked yes)
			(layer "F.Fab")
			(hide yes)
			(effects
				(font
					(size 1 1)
					(thickness 0.15)
				)
			)
		)
		(property "ISat" "6.8 A"
			(at 0 0 90)
			(unlocked yes)
			(layer "F.Fab")
			(hide yes)
			(effects
				(font
					(size 1 1)
					(thickness 0.15)
				)
			)
		)
		(property "IMax" "7.6 A"
			(at 0 0 90)
			(unlocked yes)
			(layer "F.Fab")
			(hide yes)
			(effects
				(font
					(size 1 1)
					(thickness 0.15)
				)
			)
		)
		(property "Size" "4.06x4.06"
			(at 0 0 90)
			(unlocked yes)
			(layer "F.Fab")
			(hide yes)
			(effects
				(font
					(size 1 1)
					(thickness 0.15)
				)
			)
		)
		(property "Author" "Antmicro"
			(at 0 0 90)
			(unlocked yes)
			(layer "F.Fab")
			(hide yes)
			(effects
				(font
					(size 1 1)
					(thickness 0.15)
				)
			)
		)
		(property "License" "Apache-2.0"
			(at 0 0 90)
			(unlocked yes)
			(layer "F.Fab")
			(hide yes)
			(effects
				(font
					(size 1 1)
					(thickness 0.15)
				)
			)
		)
		(sheetname "/TB Controller - Power/")
		(sheetfile "tb-power.kicad_sch")
		(attr smd)
		(fp_line
			(start 2.012 -2.024)
			(end -2.044 -2.024)
			(stroke
				(width 0.15)
				(type solid)
			)
			(layer "F.SilkS")
		)
		(fp_line
			(start 2.012 -2.024)
			(end 2.012 -1.45)
			(stroke
				(width 0.15)
				(type solid)
			)
			(layer "F.SilkS")
		)
		(fp_line
			(start -2.044 -2.024)
			(end -2.044 -1.45)
			(stroke
				(width 0.15)
				(type solid)
			)
			(layer "F.SilkS")
		)
		(fp_line
			(start 2.012 2.031)
			(end 2.012 1.45)
			(stroke
				(width 0.15)
				(type solid)
			)
			(layer "F.SilkS")
		)
		(fp_line
			(start -2.044 2.031)
			(end -2.044 1.45)
			(stroke
				(width 0.15)
				(type solid)
			)
			(layer "F.SilkS")
		)
		(fp_line
			(start -2.044 2.031)
			(end 2.012 2.031)
			(stroke
				(width 0.15)
				(type solid)
			)
			(layer "F.SilkS")
		)
		(fp_line
			(start -2.475 -2.31)
			(end 2.475 -2.31)
			(stroke
				(width 0.05)
				(type solid)
			)
			(layer "F.CrtYd")
		)
		(fp_line
			(start 2.475 -1.4)
			(end 2.475 -2.31)
			(stroke
				(width 0.05)
				(type solid)
			)
			(layer "F.CrtYd")
		)
		(fp_line
			(start 2.475 -1.4)
			(end 3.07 -1.4)
			(stroke
				(width 0.05)
				(type solid)
			)
			(layer "F.CrtYd")
		)
		(fp_line
			(start -2.475 -1.4)
			(end -2.475 -2.31)
			(stroke
				(width 0.05)
				(type solid)
			)
			(layer "F.CrtYd")
		)
		(fp_line
			(start -2.475 -1.4)
			(end -3.07 -1.4)
			(stroke
				(width 0.05)
				(type solid)
			)
			(layer "F.CrtYd")
		)
		(fp_line
			(start 3.07 1.4)
			(end 3.07 -1.4)
			(stroke
				(width 0.05)
				(type solid)
			)
			(layer "F.CrtYd")
		)
		(fp_line
			(start 2.475 1.4)
			(end 3.07 1.4)
			(stroke
				(width 0.05)
				(type solid)
			)
			(layer "F.CrtYd")
		)
		(fp_line
			(start 2.475 1.4)
			(end 2.475 2.32)
			(stroke
				(width 0.05)
				(type solid)
			)
			(layer "F.CrtYd")
		)
		(fp_line
			(start -2.475 1.4)
			(end -3.07 1.4)
			(stroke
				(width 0.05)
				(type solid)
			)
			(layer "F.CrtYd")
		)
		(fp_line
			(start -2.475 1.4)
			(end -2.475 2.32)
			(stroke
				(width 0.05)
				(type solid)
			)
			(layer "F.CrtYd")
		)
		(fp_line
			(start -3.07 1.4)
			(end -3.07 -1.4)
			(stroke
				(width 0.05)
				(type solid)
			)
			(layer "F.CrtYd")
		)
		(fp_line
			(start -2.475 2.32)
			(end 2.475 2.32)
			(stroke
				(width 0.05)
				(type solid)
			)
			(layer "F.CrtYd")
		)
		(fp_rect
			(start -2.217 -2.065)
			(end 2.217 2.064)
			(stroke
				(width 0.15)
				(type solid)
			)
			(fill no)
			(layer "F.Fab")
		)
		(fp_text user "Author: Antmicro"
			(at -3.07 5.253 90)
			(layer "F.Fab")
			(effects
				(font
					(size 0.7 0.7)
					(thickness 0.15)
				)
				(justify left bottom)
			)
		)
		(fp_text user "${REFERENCE}"
			(at -3.07 7.653 90)
			(layer "F.Fab")
			(effects
				(font
					(size 0.7 0.7)
					(thickness 0.15)
				)
				(justify left bottom)
			)
		)
		(fp_text user "License: Apache-2.0"
			(at -3.07 6.453 90)
			(layer "F.Fab")
			(effects
				(font
					(size 0.7 0.7)
					(thickness 0.15)
				)
				(justify left bottom)
			)
		)
		(pad "1" smd roundrect
			(at -1.89225 0 180)
			(size 2.286 1.8545)
			(layers "F.Cu" "F.Mask" "F.Paste")
			(roundrect_rratio 0.1)
			(net 426 "Net-(L2-Pad1)")
			(pintype "passive")
		)
		(pad "2" smd roundrect
			(at 1.89225 0 180)
			(size 2.286 1.8545)
			(layers "F.Cu" "F.Mask" "F.Paste")
			(roundrect_rratio 0.1)
			(net 68 "/TB Controller - Power/VCC_0P9")
			(pintype "passive")
		)
	)
	(footprint "antmicro-footprints:L_Bourns-SRP4021HMT"
		(layer "F.Cu")
		(at 162.549999 106.000001 -90)
		(property "Reference" "L7"
			(at 17.549996 -12.450003 270)
			(layer "F.SilkS")
			(effects
				(font
					(size 0.7 0.7)
					(thickness 0.15)
				)
			)
		)
		(property "Value" "L_1u_10A_Bourns-SRP4021HMT"
			(at -2.85 3.4 270)
			(layer "F.Fab")
			(effects
				(font
					(size 0.7 0.7)
					(thickness 0.15)
				)
				(justify left bottom)
			)
		)
		(property "Datasheet" "https://www.mouser.com/datasheet/2/54/Bourns_04_01_2025_SRP4021HMT_Datasheet-3580094.pdf"
			(at 0 0 270)
			(layer "F.Fab")
			(effects
				(font
					(size 0.7 0.7)
					(thickness 0.15)
				)
				(justify left bottom)
			)
		)
		(property "Description" "Power Inductors - SMD Ind,4.1x4.2x1.9mm,1uH+/-20%,10A, Shielded"
			(at 0 0 270)
			(layer "F.Fab")
			(effects
				(font
					(size 0.7 0.7)
					(thickness 0.15)
				)
				(justify left bottom)
			)
		)
		(property "Val" "1u/10A"
			(at 0 0 270)
			(unlocked yes)
			(layer "F.Fab")
			(hide yes)
			(effects
				(font
					(size 1 1)
					(thickness 0.15)
				)
			)
		)
		(property "Manufacturer" "Bourns"
			(at 0 0 270)
			(unlocked yes)
			(layer "F.Fab")
			(hide yes)
			(effects
				(font
					(size 1 1)
					(thickness 0.15)
				)
			)
		)
		(property "MPN" "SRP4021HMT-1R0M"
			(at 0 0 270)
			(unlocked yes)
			(layer "F.Fab")
			(hide yes)
			(effects
				(font
					(size 1 1)
					(thickness 0.15)
				)
			)
		)
		(property "ISat" ""
			(at 0 0 270)
			(unlocked yes)
			(layer "F.Fab")
			(hide yes)
			(effects
				(font
					(size 1 1)
					(thickness 0.15)
				)
			)
		)
		(property "Isat" "8A"
			(at 0 0 270)
			(unlocked yes)
			(layer "F.Fab")
			(hide yes)
			(effects
				(font
					(size 1 1)
					(thickness 0.15)
				)
			)
		)
		(property "IMax" ""
			(at 0 0 270)
			(unlocked yes)
			(layer "F.Fab")
			(hide yes)
			(effects
				(font
					(size 1 1)
					(thickness 0.15)
				)
			)
		)
		(property "Imax" "10A"
			(at 0 0 270)
			(unlocked yes)
			(layer "F.Fab")
			(hide yes)
			(effects
				(font
					(size 1 1)
					(thickness 0.15)
				)
			)
		)
		(property "Size" "4.2x4.1"
			(at 0 0 270)
			(unlocked yes)
			(layer "F.Fab")
			(hide yes)
			(effects
				(font
					(size 1 1)
					(thickness 0.15)
				)
			)
		)
		(property "Author" "Antmicro"
			(at 0 0 270)
			(unlocked yes)
			(layer "F.Fab")
			(hide yes)
			(effects
				(font
					(size 1 1)
					(thickness 0.15)
				)
			)
		)
		(property "License" "Apache-2.0"
			(at 0 0 270)
			(unlocked yes)
			(layer "F.Fab")
			(hide yes)
			(effects
				(font
					(size 1 1)
					(thickness 0.15)
				)
			)
		)
		(sheetname "/X710 DCDC converters/")
		(sheetfile "DCDC_converters_X710.kicad_sch")
		(attr smd)
		(fp_line
			(start -0.8 2.05)
			(end 0.8 2.05)
			(stroke
				(width 0.15)
				(type solid)
			)
			(layer "F.SilkS")
		)
		(fp_line
			(start -0.8 -2.05)
			(end 0.8 -2.05)
			(stroke
				(width 0.15)
				(type solid)
			)
			(layer "F.SilkS")
		)
		(fp_rect
			(start -2.85 -2.3)
			(end 2.85 2.3)
			(stroke
				(width 0.05)
				(type solid)
			)
			(fill no)
			(layer "F.CrtYd")
		)
		(fp_rect
			(start -2 -2.05)
			(end 2 2.05)
			(stroke
				(width 0.15)
				(type solid)
			)
			(fill no)
			(layer "F.Fab")
		)
		(fp_text user "Author: Antmicro"
			(at -2.85 4.6 270)
			(layer "F.Fab")
			(effects
				(font
					(size 0.7 0.7)
					(thickness 0.15)
				)
				(justify left bottom)
			)
		)
		(fp_text user "License: Apache-2.0"
			(at -2.85 7 270)
			(layer "F.Fab")
			(effects
				(font
					(size 0.7 0.7)
					(thickness 0.15)
				)
				(justify left bottom)
			)
		)
		(fp_text user "${REFERENCE}"
			(at -2.85 5.8 270)
			(layer "F.Fab")
			(effects
				(font
					(size 0.7 0.7)
					(thickness 0.15)
				)
				(justify left bottom)
			)
		)
		(pad "1" smd rect
			(at 1.85 0 90)
			(size 1.5 3.5)
			(layers "F.Cu" "F.Mask" "F.Paste")
			(net 310 "/X710 DCDC converters/1V0_SW")
			(pintype "passive")
		)
		(pad "2" smd rect
			(at -1.85 0 90)
			(size 1.5 3.5)
			(layers "F.Cu" "F.Mask" "F.Paste")
			(net 339 "/X710 DCDC converters/+1V0_OUT")
			(pintype "passive")
		)
	)
	(footprint "antmicro-footprints:R_0402_1005Metric"
		(layer "F.Cu")
		(at 124 71 180)
		(descr "Resistor SMD 0402")
		(tags "resistor SMD 0402")
		(property "Reference" "R221"
			(at -1 0.2 180)
			(layer "F.SilkS")
			(effects
				(font
					(size 0.7 0.7)
					(thickness 0.15)
				)
				(justify left bottom)
			)
		)
		(property "Value" "R_0R_0402"
			(at -1.011843 1.772047 180)
			(layer "F.Fab")
			(effects
				(font
					(size 0.7 0.7)
					(thickness 0.15)
				)
				(justify left bottom)
			)
		)
		(property "Datasheet" "https://industrial.panasonic.com/cdbs/www-data/pdf/RDA0000/AOA0000C301.pdf"
			(at 0 0 180)
			(layer "F.Fab")
			(hide yes)
			(effects
				(font
					(size 1.27 1.27)
					(thickness 0.15)
				)
			)
		)
		(property "Description" "SMD Chip Resistor, Jumper, 0 ohm, 100 mW, 0402 [1005 Metric], Thick Film, General Purpose"
			(at 0 0 180)
			(layer "F.Fab")
			(hide yes)
			(effects
				(font
					(size 1.27 1.27)
					(thickness 0.15)
				)
			)
		)
		(property "MPN" "ERJ2GE0R00X"
			(at 0 0 180)
			(unlocked yes)
			(layer "F.Fab")
			(hide yes)
			(effects
				(font
					(size 1 1)
					(thickness 0.15)
				)
			)
		)
		(property "Manufacturer" "Panasonic"
			(at 0 0 180)
			(unlocked yes)
			(layer "F.Fab")
			(hide yes)
			(effects
				(font
					(size 1 1)
					(thickness 0.15)
				)
			)
		)
		(property "License" "Apache-2.0"
			(at 0 0 180)
			(unlocked yes)
			(layer "F.Fab")
			(hide yes)
			(effects
				(font
					(size 1 1)
					(thickness 0.15)
				)
			)
		)
		(property "Author" "Antmicro"
			(at 0 0 180)
			(unlocked yes)
			(layer "F.Fab")
			(hide yes)
			(effects
				(font
					(size 1 1)
					(thickness 0.15)
				)
			)
		)
		(property "Val" "0R"
			(at 0 0 180)
			(unlocked yes)
			(layer "F.Fab")
			(hide yes)
			(effects
				(font
					(size 1 1)
					(thickness 0.15)
				)
			)
		)
		(property "Tolerance" "~"
			(at 0 0 180)
			(unlocked yes)
			(layer "F.Fab")
			(hide yes)
			(effects
				(font
					(size 1 1)
					(thickness 0.15)
				)
			)
		)
		(property "Current" "1A"
			(at 0 0 180)
			(unlocked yes)
			(layer "F.Fab")
			(hide yes)
			(effects
				(font
					(size 1 1)
					(thickness 0.15)
				)
			)
		)
		(sheetname "/Fan controller/")
		(sheetfile "fan-controller.kicad_sch")
		(attr smd)
		(fp_rect
			(start -0.925 -0.47)
			(end 0.925 0.47)
			(stroke
				(width 0.05)
				(type default)
			)
			(fill no)
			(layer "F.CrtYd")
		)
		(fp_rect
			(start -0.5 -0.25)
			(end 0.5 0.25)
			(stroke
				(width 0.15)
				(type solid)
			)
			(fill no)
			(layer "F.Fab")
		)
		(fp_text user "Author: Antmicro"
			(at -0.95 4.169 180)
			(layer "F.Fab")
			(effects
				(font
					(size 0.7 0.7)
					(thickness 0.15)
				)
				(justify left bottom)
			)
		)
		(fp_text user "License: Apache-2.0"
			(at -0.95 5.169 180)
			(layer "F.Fab")
			(effects
				(font
					(size 0.7 0.7)
					(thickness 0.15)
				)
				(justify left bottom)
			)
		)
		(fp_text user "${REFERENCE}"
			(at -0.95 3.168 180)
			(layer "F.Fab")
			(effects
				(font
					(size 0.7 0.7)
					(thickness 0.15)
				)
				(justify left bottom)
			)
		)
		(pad "1" smd roundrect
			(at -0.48 0 180)
			(size 0.59 0.64)
			(layers "F.Cu" "F.Mask" "F.Paste")
			(roundrect_rratio 0.25)
			(net 23 "GND")
			(pintype "passive")
		)
		(pad "2" smd roundrect
			(at 0.48 0 180)
			(size 0.59 0.64)
			(layers "F.Cu" "F.Mask" "F.Paste")
			(roundrect_rratio 0.25)
			(net 156 "/Fan controller/D0")
			(pintype "passive")
		)
	)
	(footprint "antmicro-footprints:R_0402_1005Metric"
		(layer "F.Cu")
		(at 157.355 94.055 90)
		(descr "Resistor SMD 0402")
		(tags "resistor SMD 0402")
		(property "Reference" "R165"
			(at -19.145001 23.294999 90)
			(layer "F.SilkS")
			(effects
				(font
					(size 0.7 0.7)
					(thickness 0.15)
				)
			)
		)
		(property "Value" "R_10R_0402"
			(at -1.011843 1.772047 90)
			(layer "F.Fab")
			(effects
				(font
					(size 0.7 0.7)
					(thickness 0.15)
				)
				(justify left bottom)
			)
		)
		(property "Datasheet" "https://www.bourns.com/docs/product-datasheets/cr.pdf"
			(at 0 0 90)
			(layer "F.Fab")
			(hide yes)
			(effects
				(font
					(size 1.27 1.27)
					(thickness 0.15)
				)
			)
		)
		(property "Description" "SMD Chip Resistor, 10 ohm, ± 1%, 62.5 mW, 0402 [1005 Metric], Thick Film, General Purpose"
			(at 0 0 90)
			(layer "F.Fab")
			(hide yes)
			(effects
				(font
					(size 1.27 1.27)
					(thickness 0.15)
				)
			)
		)
		(property "MPN" "CR0402-FX-10R0GLF"
			(at 0 0 90)
			(unlocked yes)
			(layer "F.Fab")
			(hide yes)
			(effects
				(font
					(size 1 1)
					(thickness 0.15)
				)
			)
		)
		(property "Manufacturer" "Bourns"
			(at 0 0 90)
			(unlocked yes)
			(layer "F.Fab")
			(hide yes)
			(effects
				(font
					(size 1 1)
					(thickness 0.15)
				)
			)
		)
		(property "License" "Apache-2.0"
			(at 0 0 90)
			(unlocked yes)
			(layer "F.Fab")
			(hide yes)
			(effects
				(font
					(size 1 1)
					(thickness 0.15)
				)
			)
		)
		(property "Author" "Antmicro"
			(at 0 0 90)
			(unlocked yes)
			(layer "F.Fab")
			(hide yes)
			(effects
				(font
					(size 1 1)
					(thickness 0.15)
				)
			)
		)
		(property "Val" "10R"
			(at 0 0 90)
			(unlocked yes)
			(layer "F.Fab")
			(hide yes)
			(effects
				(font
					(size 1 1)
					(thickness 0.15)
				)
			)
		)
		(property "Tolerance" "1%"
			(at 0 0 90)
			(unlocked yes)
			(layer "F.Fab")
			(hide yes)
			(effects
				(font
					(size 1 1)
					(thickness 0.15)
				)
			)
		)
		(sheetname "/X710-AT2 Misc/")
		(sheetfile "x710-at2-mics.kicad_sch")
		(attr smd)
		(fp_rect
			(start -0.925 -0.47)
			(end 0.925 0.47)
			(stroke
				(width 0.05)
				(type default)
			)
			(fill no)
			(layer "F.CrtYd")
		)
		(fp_rect
			(start -0.5 -0.25)
			(end 0.5 0.25)
			(stroke
				(width 0.15)
				(type solid)
			)
			(fill no)
			(layer "F.Fab")
		)
		(fp_text user "Author: Antmicro"
			(at -0.95 4.169 90)
			(layer "F.Fab")
			(effects
				(font
					(size 0.7 0.7)
					(thickness 0.15)
				)
				(justify left bottom)
			)
		)
		(fp_text user "License: Apache-2.0"
			(at -0.95 5.169 90)
			(layer "F.Fab")
			(effects
				(font
					(size 0.7 0.7)
					(thickness 0.15)
				)
				(justify left bottom)
			)
		)
		(fp_text user "${REFERENCE}"
			(at -0.95 3.168 90)
			(layer "F.Fab")
			(effects
				(font
					(size 0.7 0.7)
					(thickness 0.15)
				)
				(justify left bottom)
			)
		)
		(pad "1" smd roundrect
			(at -0.48 0 90)
			(size 0.59 0.64)
			(layers "F.Cu" "F.Mask" "F.Paste")
			(roundrect_rratio 0.25)
			(net 59 "/X710-AT2 Misc/50MHZ_XTAL_R.-")
			(pintype "passive")
		)
		(pad "2" smd roundrect
			(at 0.48 0 90)
			(size 0.59 0.64)
			(layers "F.Cu" "F.Mask" "F.Paste")
			(roundrect_rratio 0.25)
			(net 120 "/X710-AT2 Misc/50MHZ_XTAL.-")
			(pintype "passive")
		)
	)
	(footprint "antmicro-footprints:C_0402_1005Metric"
		(layer "F.Cu")
		(at 141.1 109.850002 90)
		(descr "Capacitor SMD 0402")
		(tags "capacitor SMD 0402")
		(property "Reference" "C125"
			(at -17.049998 16 90)
			(layer "F.SilkS")
			(effects
				(font
					(size 0.7 0.7)
					(thickness 0.15)
				)
			)
		)
		(property "Value" "C_100n_0402"
			(at -1.022927 2.155213 90)
			(layer "F.Fab")
			(effects
				(font
					(size 0.7 0.7)
					(thickness 0.15)
				)
				(justify left bottom)
			)
		)
		(property "Datasheet" "https://www.murata.com/products/productdetail?partno=GRM155R61H104KE14%23"
			(at 0 0 90)
			(layer "F.Fab")
			(hide yes)
			(effects
				(font
					(size 1.27 1.27)
					(thickness 0.15)
				)
			)
		)
		(property "Description" "SMD Multilayer Ceramic Capacitor, 0.1 µF, 50 V, 0402 [1005 Metric], ± 10%, X5R, GRM Series"
			(at 0 0 90)
			(layer "F.Fab")
			(hide yes)
			(effects
				(font
					(size 1.27 1.27)
					(thickness 0.15)
				)
			)
		)
		(property "MPN" "GRM155R61H104KE14D"
			(at 0 0 90)
			(unlocked yes)
			(layer "F.Fab")
			(hide yes)
			(effects
				(font
					(size 1 1)
					(thickness 0.15)
				)
			)
		)
		(property "Manufacturer" "Murata"
			(at 0 0 90)
			(unlocked yes)
			(layer "F.Fab")
			(hide yes)
			(effects
				(font
					(size 1 1)
					(thickness 0.15)
				)
			)
		)
		(property "License" "Apache-2.0"
			(at 0 0 90)
			(unlocked yes)
			(layer "F.Fab")
			(hide yes)
			(effects
				(font
					(size 1 1)
					(thickness 0.15)
				)
			)
		)
		(property "Author" "Antmicro"
			(at 0 0 90)
			(unlocked yes)
			(layer "F.Fab")
			(hide yes)
			(effects
				(font
					(size 1 1)
					(thickness 0.15)
				)
			)
		)
		(property "Val" "100n"
			(at 0 0 90)
			(unlocked yes)
			(layer "F.Fab")
			(hide yes)
			(effects
				(font
					(size 1 1)
					(thickness 0.15)
				)
			)
		)
		(property "Voltage" "50V"
			(at 0 0 90)
			(unlocked yes)
			(layer "F.Fab")
			(hide yes)
			(effects
				(font
					(size 1 1)
					(thickness 0.15)
				)
			)
		)
		(property "Dielectric" "X5R"
			(at 0 0 90)
			(unlocked yes)
			(layer "F.Fab")
			(hide yes)
			(effects
				(font
					(size 1 1)
					(thickness 0.15)
				)
			)
		)
		(sheetname "/X710 DCDC converters/")
		(sheetfile "DCDC_converters_X710.kicad_sch")
		(attr smd)
		(fp_rect
			(start -0.925 -0.47)
			(end 0.925 0.47)
			(stroke
				(width 0.05)
				(type default)
			)
			(fill no)
			(layer "F.CrtYd")
		)
		(fp_line
			(start 0.504 -0.25)
			(end 0.504 0.248)
			(stroke
				(width 0.15)
				(type solid)
			)
			(layer "F.Fab")
		)
		(fp_line
			(start -0.494 -0.25)
			(end 0.504 -0.25)
			(stroke
				(width 0.15)
				(type solid)
			)
			(layer "F.Fab")
		)
		(fp_line
			(start 0.504 0.248)
			(end -0.494 0.248)
			(stroke
				(width 0.15)
				(type solid)
			)
			(layer "F.Fab")
		)
		(fp_line
			(start -0.494 0.248)
			(end -0.494 -0.25)
			(stroke
				(width 0.15)
				(type solid)
			)
			(layer "F.Fab")
		)
		(fp_text user "License: Apache-2.0"
			(at -0.939 5.799 90)
			(layer "F.Fab")
			(effects
				(font
					(size 0.7 0.7)
					(thickness 0.15)
				)
				(justify left bottom)
			)
		)
		(fp_text user "${REFERENCE}"
			(at -0.939 4.599 90)
			(layer "F.Fab")
			(effects
				(font
					(size 0.7 0.7)
					(thickness 0.15)
				)
				(justify left bottom)
			)
		)
		(fp_text user "Author: Antmicro"
			(at -0.939 3.399 90)
			(layer "F.Fab")
			(effects
				(font
					(size 0.7 0.7)
					(thickness 0.15)
				)
				(justify left bottom)
			)
		)
		(pad "1" smd roundrect
			(at -0.48 0 90)
			(size 0.59 0.64)
			(layers "F.Cu" "F.Mask" "F.Paste")
			(roundrect_rratio 0.25)
			(net 119 "/X710 DCDC converters/VCCD_BST")
			(pintype "passive")
		)
		(pad "2" smd roundrect
			(at 0.48 0 90)
			(size 0.59 0.64)
			(layers "F.Cu" "F.Mask" "F.Paste")
			(roundrect_rratio 0.25)
			(net 153 "/X710 DCDC converters/VCCD_SW")
			(pintype "passive")
		)
	)
	(footprint "antmicro-footprints:C_0603_1608Metric"
		(layer "F.Cu")
		(at 122.15 103.3)
		(descr "Capacitor SMD 0603")
		(tags "capacitor 0603")
		(property "Reference" "C24"
			(at 2.35 -0.3 0)
			(layer "F.SilkS")
			(effects
				(font
					(size 0.7 0.7)
					(thickness 0.15)
				)
			)
		)
		(property "Value" "C_22u_0603"
			(at -1.42757 1.770288 0)
			(layer "F.Fab")
			(effects
				(font
					(size 0.7 0.7)
					(thickness 0.15)
				)
				(justify left bottom)
			)
		)
		(property "Datasheet" "https://www.murata.com/products/productdetail?partno=GRM188R60J226MEA0%23"
			(at 0 0 0)
			(layer "F.Fab")
			(hide yes)
			(effects
				(font
					(size 1.27 1.27)
					(thickness 0.15)
				)
			)
		)
		(property "Description" "SMD Multilayer Ceramic Capacitor, 22 µF, 6.3 V, 0603 [1608 Metric], ± 20%, X5R, GRM Series"
			(at 0 0 0)
			(layer "F.Fab")
			(hide yes)
			(effects
				(font
					(size 1.27 1.27)
					(thickness 0.15)
				)
			)
		)
		(property "MPN" "GRM188R60J226MEA0D"
			(at 0 0 0)
			(unlocked yes)
			(layer "F.Fab")
			(hide yes)
			(effects
				(font
					(size 1 1)
					(thickness 0.15)
				)
			)
		)
		(property "Manufacturer" "Murata"
			(at 0 0 0)
			(unlocked yes)
			(layer "F.Fab")
			(hide yes)
			(effects
				(font
					(size 1 1)
					(thickness 0.15)
				)
			)
		)
		(property "License" "Apache-2.0"
			(at 0 0 0)
			(unlocked yes)
			(layer "F.Fab")
			(hide yes)
			(effects
				(font
					(size 1 1)
					(thickness 0.15)
				)
			)
		)
		(property "Val" "22u"
			(at 0 0 0)
			(unlocked yes)
			(layer "F.Fab")
			(hide yes)
			(effects
				(font
					(size 1 1)
					(thickness 0.15)
				)
			)
		)
		(property "Voltage" ""
			(at 0 0 0)
			(unlocked yes)
			(layer "F.Fab")
			(hide yes)
			(effects
				(font
					(size 1 1)
					(thickness 0.15)
				)
			)
		)
		(property "Dielectric" ""
			(at 0 0 0)
			(unlocked yes)
			(layer "F.Fab")
			(hide yes)
			(effects
				(font
					(size 1 1)
					(thickness 0.15)
				)
			)
		)
		(property "Author" "Antmicro"
			(at 0 0 0)
			(unlocked yes)
			(layer "F.Fab")
			(hide yes)
			(effects
				(font
					(size 1 1)
					(thickness 0.15)
				)
			)
		)
		(sheetname "/PD and TB DC-DC/")
		(sheetfile "PD_and_TB_DC_DC.kicad_sch")
		(attr smd)
		(fp_line
			(start -0.15 -0.4)
			(end 0.15 -0.4)
			(stroke
				(width 0.15)
				(type solid)
			)
			(layer "F.SilkS")
		)
		(fp_line
			(start -0.15 0.4)
			(end 0.15 0.4)
			(stroke
				(width 0.15)
				(type solid)
			)
			(layer "F.SilkS")
		)
		(fp_rect
			(start -1.25 -0.65)
			(end 1.25 0.65)
			(stroke
				(width 0.05)
				(type solid)
			)
			(fill no)
			(layer "F.CrtYd")
		)
		(fp_rect
			(start -0.8 -0.4)
			(end 0.8 0.4)
			(stroke
				(width 0.15)
				(type solid)
			)
			(fill no)
			(layer "F.Fab")
		)
		(fp_text user "${REFERENCE}"
			(at -1.682 3.895 0)
			(layer "F.Fab")
			(effects
				(font
					(size 0.7 0.7)
					(thickness 0.15)
				)
				(justify left bottom)
			)
		)
		(fp_text user "License: Apache-2.0"
			(at -1.682 5.895 0)
			(layer "F.Fab")
			(effects
				(font
					(size 0.7 0.7)
					(thickness 0.15)
				)
				(justify left bottom)
			)
		)
		(fp_text user "Author: Antmicro"
			(at -1.682 4.894 0)
			(layer "F.Fab")
			(effects
				(font
					(size 0.7 0.7)
					(thickness 0.15)
				)
				(justify left bottom)
			)
		)
		(pad "1" smd roundrect
			(at -0.7 0)
			(size 0.8 1)
			(layers "F.Cu" "F.Mask" "F.Paste")
			(roundrect_rratio 0.2)
			(net 23 "GND")
			(pintype "passive")
		)
		(pad "2" smd roundrect
			(at 0.7 0)
			(size 0.8 1)
			(layers "F.Cu" "F.Mask" "F.Paste")
			(roundrect_rratio 0.2)
			(net 399 "Net-(D4-A)")
			(pintype "passive")
		)
	)
	(footprint "antmicro-footprints:C_0402_1005Metric"
		(layer "F.Cu")
		(at 129.52 92.2)
		(descr "Capacitor SMD 0402")
		(tags "capacitor SMD 0402")
		(property "Reference" "C129"
			(at 38.914999 -9.199999 0)
			(layer "F.SilkS")
			(effects
				(font
					(size 0.7 0.7)
					(thickness 0.15)
				)
			)
		)
		(property "Value" "C_33p_0402"
			(at -1.022927 2.155213 0)
			(layer "F.Fab")
			(effects
				(font
					(size 0.7 0.7)
					(thickness 0.15)
				)
				(justify left bottom)
			)
		)
		(property "Datasheet" "https://spicat.kyocera-avx.com/product/mlcc/chartview/04025A330FAT2A/"
			(at 0 0 0)
			(layer "F.Fab")
			(hide yes)
			(effects
				(font
					(size 1.27 1.27)
					(thickness 0.15)
				)
			)
		)
		(property "Description" "SMD Multilayer Ceramic Capacitor, 33 pF, 50 V, 0402 [1005 Metric], ± 5%, C0G / NP0, MC"
			(at 0 0 0)
			(layer "F.Fab")
			(hide yes)
			(effects
				(font
					(size 1.27 1.27)
					(thickness 0.15)
				)
			)
		)
		(property "MPN" "04025A330FAT2A"
			(at 0 0 0)
			(unlocked yes)
			(layer "F.Fab")
			(hide yes)
			(effects
				(font
					(size 1 1)
					(thickness 0.15)
				)
			)
		)
		(property "Manufacturer" "KYOCERA AVX"
			(at 0 0 0)
			(unlocked yes)
			(layer "F.Fab")
			(hide yes)
			(effects
				(font
					(size 1 1)
					(thickness 0.15)
				)
			)
		)
		(property "License" "Apache-2.0"
			(at 0 0 0)
			(unlocked yes)
			(layer "F.Fab")
			(hide yes)
			(effects
				(font
					(size 1 1)
					(thickness 0.15)
				)
			)
		)
		(property "Author" "Antmicro"
			(at 0 0 0)
			(unlocked yes)
			(layer "F.Fab")
			(hide yes)
			(effects
				(font
					(size 1 1)
					(thickness 0.15)
				)
			)
		)
		(property "Val" "33p"
			(at 0 0 0)
			(unlocked yes)
			(layer "F.Fab")
			(hide yes)
			(effects
				(font
					(size 1 1)
					(thickness 0.15)
				)
			)
		)
		(property "Voltage" ""
			(at 0 0 0)
			(unlocked yes)
			(layer "F.Fab")
			(hide yes)
			(effects
				(font
					(size 1 1)
					(thickness 0.15)
				)
			)
		)
		(property "Dielectric" ""
			(at 0 0 0)
			(unlocked yes)
			(layer "F.Fab")
			(hide yes)
			(effects
				(font
					(size 1 1)
					(thickness 0.15)
				)
			)
		)
		(sheetname "/X710 DCDC converters/")
		(sheetfile "DCDC_converters_X710.kicad_sch")
		(attr smd)
		(fp_rect
			(start -0.925 -0.47)
			(end 0.925 0.47)
			(stroke
				(width 0.05)
				(type default)
			)
			(fill no)
			(layer "F.CrtYd")
		)
		(fp_line
			(start -0.494 -0.25)
			(end 0.504 -0.25)
			(stroke
				(width 0.15)
				(type solid)
			)
			(layer "F.Fab")
		)
		(fp_line
			(start -0.494 0.248)
			(end -0.494 -0.25)
			(stroke
				(width 0.15)
				(type solid)
			)
			(layer "F.Fab")
		)
		(fp_line
			(start 0.504 -0.25)
			(end 0.504 0.248)
			(stroke
				(width 0.15)
				(type solid)
			)
			(layer "F.Fab")
		)
		(fp_line
			(start 0.504 0.248)
			(end -0.494 0.248)
			(stroke
				(width 0.15)
				(type solid)
			)
			(layer "F.Fab")
		)
		(fp_text user "License: Apache-2.0"
			(at -0.939 5.799 0)
			(layer "F.Fab")
			(effects
				(font
					(size 0.7 0.7)
					(thickness 0.15)
				)
				(justify left bottom)
			)
		)
		(fp_text user "Author: Antmicro"
			(at -0.939 3.399 0)
			(layer "F.Fab")
			(effects
				(font
					(size 0.7 0.7)
					(thickness 0.15)
				)
				(justify left bottom)
			)
		)
		(fp_text user "${REFERENCE}"
			(at -0.939 4.599 0)
			(layer "F.Fab")
			(effects
				(font
					(size 0.7 0.7)
					(thickness 0.15)
				)
				(justify left bottom)
			)
		)
		(pad "1" smd roundrect
			(at -0.48 0)
			(size 0.59 0.64)
			(layers "F.Cu" "F.Mask" "F.Paste")
			(roundrect_rratio 0.25)
			(net 333 "/X710 DCDC converters/3V3_FB")
			(pintype "passive")
		)
		(pad "2" smd roundrect
			(at 0.48 0)
			(size 0.59 0.64)
			(layers "F.Cu" "F.Mask" "F.Paste")
			(roundrect_rratio 0.25)
			(net 334 "/X710 DCDC converters/+3V3_OUT")
			(pintype "passive")
		)
	)
	(footprint "antmicro-footprints:R_0402_1005Metric"
		(layer "F.Cu")
		(at 135 145.5)
		(descr "Resistor SMD 0402")
		(tags "resistor SMD 0402")
		(property "Reference" "R97"
			(at 1 0.5 0)
			(layer "F.SilkS")
			(effects
				(font
					(size 0.7 0.7)
					(thickness 0.15)
				)
				(justify left bottom)
			)
		)
		(property "Value" "R_330R_0402"
			(at -1.011843 1.772047 0)
			(layer "F.Fab")
			(effects
				(font
					(size 0.7 0.7)
					(thickness 0.15)
				)
				(justify left bottom)
			)
		)
		(property "Datasheet" "https://www.bourns.com/docs/product-datasheets/cr.pdf"
			(at 0 0 0)
			(layer "F.Fab")
			(hide yes)
			(effects
				(font
					(size 1.27 1.27)
					(thickness 0.15)
				)
			)
		)
		(property "Description" "SMD Chip Resistor, 330 ohm, ± 1%, 62.5 mW, 0402 [1005 Metric], Thick Film, General Purpose"
			(at 0 0 0)
			(layer "F.Fab")
			(hide yes)
			(effects
				(font
					(size 1.27 1.27)
					(thickness 0.15)
				)
			)
		)
		(property "MPN" "CR0402-FX-3300GLF"
			(at 0 0 0)
			(unlocked yes)
			(layer "F.Fab")
			(hide yes)
			(effects
				(font
					(size 1 1)
					(thickness 0.15)
				)
			)
		)
		(property "Manufacturer" "Bourns"
			(at 0 0 0)
			(unlocked yes)
			(layer "F.Fab")
			(hide yes)
			(effects
				(font
					(size 1 1)
					(thickness 0.15)
				)
			)
		)
		(property "License" "Apache-2.0"
			(at 0 0 0)
			(unlocked yes)
			(layer "F.Fab")
			(hide yes)
			(effects
				(font
					(size 1 1)
					(thickness 0.15)
				)
			)
		)
		(property "Author" "Antmicro"
			(at 0 0 0)
			(unlocked yes)
			(layer "F.Fab")
			(hide yes)
			(effects
				(font
					(size 1 1)
					(thickness 0.15)
				)
			)
		)
		(property "Val" "330R"
			(at 0 0 0)
			(unlocked yes)
			(layer "F.Fab")
			(hide yes)
			(effects
				(font
					(size 1 1)
					(thickness 0.15)
				)
			)
		)
		(property "Tolerance" "1%"
			(at 0 0 0)
			(unlocked yes)
			(layer "F.Fab")
			(hide yes)
			(effects
				(font
					(size 1 1)
					(thickness 0.15)
				)
			)
		)
		(sheetname "/X710 DCDC converters/")
		(sheetfile "DCDC_converters_X710.kicad_sch")
		(attr smd)
		(fp_rect
			(start -0.925 -0.47)
			(end 0.925 0.47)
			(stroke
				(width 0.05)
				(type default)
			)
			(fill no)
			(layer "F.CrtYd")
		)
		(fp_rect
			(start -0.5 -0.25)
			(end 0.5 0.25)
			(stroke
				(width 0.15)
				(type solid)
			)
			(fill no)
			(layer "F.Fab")
		)
		(fp_text user "${REFERENCE}"
			(at -0.95 3.168 0)
			(layer "F.Fab")
			(effects
				(font
					(size 0.7 0.7)
					(thickness 0.15)
				)
				(justify left bottom)
			)
		)
		(fp_text user "Author: Antmicro"
			(at -0.95 4.169 0)
			(layer "F.Fab")
			(effects
				(font
					(size 0.7 0.7)
					(thickness 0.15)
				)
				(justify left bottom)
			)
		)
		(fp_text user "License: Apache-2.0"
			(at -0.95 5.169 0)
			(layer "F.Fab")
			(effects
				(font
					(size 0.7 0.7)
					(thickness 0.15)
				)
				(justify left bottom)
			)
		)
		(pad "1" smd roundrect
			(at -0.48 0)
			(size 0.59 0.64)
			(layers "F.Cu" "F.Mask" "F.Paste")
			(roundrect_rratio 0.25)
			(net 419 "Net-(D11-A)")
			(pintype "passive")
		)
		(pad "2" smd roundrect
			(at 0.48 0)
			(size 0.59 0.64)
			(layers "F.Cu" "F.Mask" "F.Paste")
			(roundrect_rratio 0.25)
			(net 334 "/X710 DCDC converters/+3V3_OUT")
			(pintype "passive")
		)
	)
	(footprint "antmicro-footprints:R_0402_1005Metric"
		(layer "F.Cu")
		(at 139 67.549999)
		(descr "Resistor SMD 0402")
		(tags "resistor SMD 0402")
		(property "Reference" "R113"
			(at 1 0.450001 0)
			(layer "F.SilkS")
			(effects
				(font
					(size 0.7 0.7)
					(thickness 0.15)
				)
				(justify left bottom)
			)
		)
		(property "Value" "R_0R_0402"
			(at -1.011843 1.772047 0)
			(layer "F.Fab")
			(effects
				(font
					(size 0.7 0.7)
					(thickness 0.15)
				)
				(justify left bottom)
			)
		)
		(property "Datasheet" "https://industrial.panasonic.com/cdbs/www-data/pdf/RDA0000/AOA0000C301.pdf"
			(at 0 0 0)
			(layer "F.Fab")
			(hide yes)
			(effects
				(font
					(size 1.27 1.27)
					(thickness 0.15)
				)
			)
		)
		(property "Description" "SMD Chip Resistor, Jumper, 0 ohm, 100 mW, 0402 [1005 Metric], Thick Film, General Purpose"
			(at 0 0 0)
			(layer "F.Fab")
			(hide yes)
			(effects
				(font
					(size 1.27 1.27)
					(thickness 0.15)
				)
			)
		)
		(property "MPN" "ERJ2GE0R00X"
			(at 0 0 0)
			(unlocked yes)
			(layer "F.Fab")
			(hide yes)
			(effects
				(font
					(size 1 1)
					(thickness 0.15)
				)
			)
		)
		(property "Manufacturer" "Panasonic"
			(at 0 0 0)
			(unlocked yes)
			(layer "F.Fab")
			(hide yes)
			(effects
				(font
					(size 1 1)
					(thickness 0.15)
				)
			)
		)
		(property "License" "Apache-2.0"
			(at 0 0 0)
			(unlocked yes)
			(layer "F.Fab")
			(hide yes)
			(effects
				(font
					(size 1 1)
					(thickness 0.15)
				)
			)
		)
		(property "Author" "Antmicro"
			(at 0 0 0)
			(unlocked yes)
			(layer "F.Fab")
			(hide yes)
			(effects
				(font
					(size 1 1)
					(thickness 0.15)
				)
			)
		)
		(property "Val" "0R"
			(at 0 0 0)
			(unlocked yes)
			(layer "F.Fab")
			(hide yes)
			(effects
				(font
					(size 1 1)
					(thickness 0.15)
				)
			)
		)
		(property "Tolerance" "~"
			(at 0 0 0)
			(unlocked yes)
			(layer "F.Fab")
			(hide yes)
			(effects
				(font
					(size 1 1)
					(thickness 0.15)
				)
			)
		)
		(property "Current" "1A"
			(at 0 0 0)
			(unlocked yes)
			(layer "F.Fab")
			(hide yes)
			(effects
				(font
					(size 1 1)
					(thickness 0.15)
				)
			)
		)
		(sheetname "/X710-AT2 PCIe/")
		(sheetfile "x710-at2-pcie.kicad_sch")
		(attr smd)
		(fp_rect
			(start -0.925 -0.47)
			(end 0.925 0.47)
			(stroke
				(width 0.05)
				(type default)
			)
			(fill no)
			(layer "F.CrtYd")
		)
		(fp_rect
			(start -0.5 -0.25)
			(end 0.5 0.25)
			(stroke
				(width 0.15)
				(type solid)
			)
			(fill no)
			(layer "F.Fab")
		)
		(fp_text user "Author: Antmicro"
			(at -0.95 4.169 0)
			(layer "F.Fab")
			(effects
				(font
					(size 0.7 0.7)
					(thickness 0.15)
				)
				(justify left bottom)
			)
		)
		(fp_text user "License: Apache-2.0"
			(at -0.95 5.169 0)
			(layer "F.Fab")
			(effects
				(font
					(size 0.7 0.7)
					(thickness 0.15)
				)
				(justify left bottom)
			)
		)
		(fp_text user "${REFERENCE}"
			(at -0.95 3.168 0)
			(layer "F.Fab")
			(effects
				(font
					(size 0.7 0.7)
					(thickness 0.15)
				)
				(justify left bottom)
			)
		)
		(pad "1" smd roundrect
			(at -0.48 0)
			(size 0.59 0.64)
			(layers "F.Cu" "F.Mask" "F.Paste")
			(roundrect_rratio 0.25)
			(net 393 "/TB Controller/REFCLK.+")
			(pintype "passive")
		)
		(pad "2" smd roundrect
			(at 0.48 0)
			(size 0.59 0.64)
			(layers "F.Cu" "F.Mask" "F.Paste")
			(roundrect_rratio 0.25)
			(net 159 "/X710-AT2 PCIe/CLK+")
			(pintype "passive")
		)
	)
	(footprint "antmicro-footprints:C_0402_1005Metric"
		(layer "F.Cu")
		(at 158.944999 96.954999 90)
		(descr "Capacitor SMD 0402")
		(tags "capacitor SMD 0402")
		(property "Reference" "C280"
			(at -19.625001 23.294999 90)
			(layer "F.SilkS")
			(effects
				(font
					(size 0.7 0.7)
					(thickness 0.15)
				)
			)
		)
		(property "Value" "C_5p6_0402"
			(at -1.022927 2.155213 90)
			(layer "F.Fab")
			(effects
				(font
					(size 0.7 0.7)
					(thickness 0.15)
				)
				(justify left bottom)
			)
		)
		(property "Datasheet" "https://www.mouser.com/datasheet/3/76/2/GCM1555C1H5R6BA16_01A.pdf"
			(at 0 0 90)
			(layer "F.Fab")
			(hide yes)
			(effects
				(font
					(size 1.27 1.27)
					(thickness 0.15)
				)
			)
		)
		(property "Description" "Multilayer Ceramic Capacitors MLCC - SMD/SMT 5.6 pF 50 VDC 0.1 pF 0402 C0G (NP0) AEC-Q200"
			(at 0 0 90)
			(layer "F.Fab")
			(hide yes)
			(effects
				(font
					(size 1.27 1.27)
					(thickness 0.15)
				)
			)
		)
		(property "MPN" "GCM1555C1H5R6BA16D"
			(at 0 0 90)
			(unlocked yes)
			(layer "F.Fab")
			(hide yes)
			(effects
				(font
					(size 1 1)
					(thickness 0.15)
				)
			)
		)
		(property "Manufacturer" "Murata"
			(at 0 0 90)
			(unlocked yes)
			(layer "F.Fab")
			(hide yes)
			(effects
				(font
					(size 1 1)
					(thickness 0.15)
				)
			)
		)
		(property "License" "Apache-2.0"
			(at 0 0 90)
			(unlocked yes)
			(layer "F.Fab")
			(hide yes)
			(effects
				(font
					(size 1 1)
					(thickness 0.15)
				)
			)
		)
		(property "Author" "Antmicro"
			(at 0 0 90)
			(unlocked yes)
			(layer "F.Fab")
			(hide yes)
			(effects
				(font
					(size 1 1)
					(thickness 0.15)
				)
			)
		)
		(property "Val" "5p6"
			(at 0 0 90)
			(unlocked yes)
			(layer "F.Fab")
			(hide yes)
			(effects
				(font
					(size 1 1)
					(thickness 0.15)
				)
			)
		)
		(property "Voltage" "50V"
			(at 0 0 90)
			(unlocked yes)
			(layer "F.Fab")
			(hide yes)
			(effects
				(font
					(size 1 1)
					(thickness 0.15)
				)
			)
		)
		(property "Dielectric" "C0G"
			(at 0 0 90)
			(unlocked yes)
			(layer "F.Fab")
			(hide yes)
			(effects
				(font
					(size 1 1)
					(thickness 0.15)
				)
			)
		)
		(sheetname "/X710-AT2 Misc/")
		(sheetfile "x710-at2-mics.kicad_sch")
		(attr smd)
		(fp_rect
			(start -0.925 -0.47)
			(end 0.925 0.47)
			(stroke
				(width 0.05)
				(type default)
			)
			(fill no)
			(layer "F.CrtYd")
		)
		(fp_line
			(start 0.504 -0.25)
			(end 0.504 0.248)
			(stroke
				(width 0.15)
				(type solid)
			)
			(layer "F.Fab")
		)
		(fp_line
			(start -0.494 -0.25)
			(end 0.504 -0.25)
			(stroke
				(width 0.15)
				(type solid)
			)
			(layer "F.Fab")
		)
		(fp_line
			(start 0.504 0.248)
			(end -0.494 0.248)
			(stroke
				(width 0.15)
				(type solid)
			)
			(layer "F.Fab")
		)
		(fp_line
			(start -0.494 0.248)
			(end -0.494 -0.25)
			(stroke
				(width 0.15)
				(type solid)
			)
			(layer "F.Fab")
		)
		(fp_text user "Author: Antmicro"
			(at -0.939 3.399 90)
			(layer "F.Fab")
			(effects
				(font
					(size 0.7 0.7)
					(thickness 0.15)
				)
				(justify left bottom)
			)
		)
		(fp_text user "${REFERENCE}"
			(at -0.939 4.599 90)
			(layer "F.Fab")
			(effects
				(font
					(size 0.7 0.7)
					(thickness 0.15)
				)
				(justify left bottom)
			)
		)
		(fp_text user "License: Apache-2.0"
			(at -0.939 5.799 90)
			(layer "F.Fab")
			(effects
				(font
					(size 0.7 0.7)
					(thickness 0.15)
				)
				(justify left bottom)
			)
		)
		(pad "1" smd roundrect
			(at -0.48 0 90)
			(size 0.59 0.64)
			(layers "F.Cu" "F.Mask" "F.Paste")
			(roundrect_rratio 0.25)
			(net 23 "GND")
			(pintype "passive")
		)
		(pad "2" smd roundrect
			(at 0.48 0 90)
			(size 0.59 0.64)
			(layers "F.Cu" "F.Mask" "F.Paste")
			(roundrect_rratio 0.25)
			(net 58 "/X710-AT2 Misc/50MHZ_XTAL_R.+")
			(pintype "passive")
		)
	)
	(footprint "antmicro-footprints:C_0603_1608Metric_EIA"
		(layer "F.Cu")
		(at 147.199999 113)
		(descr "Capacitor SMD 0603, IPC-7351 Density Level A")
		(tags "Capacitor 0603")
		(property "Reference" "C108"
			(at 14.850002 16.75 0)
			(layer "F.SilkS")
			(effects
				(font
					(size 0.7 0.7)
					(thickness 0.15)
				)
			)
		)
		(property "Value" "C_22u_16V_0603"
			(at -1.42757 1.770288 0)
			(layer "F.Fab")
			(effects
				(font
					(size 0.7 0.7)
					(thickness 0.15)
				)
				(justify left bottom)
			)
		)
		(property "Datasheet" "https://product.samsungsem.com/mlcc/CL10A226MO7JZN.do"
			(at 0 0 0)
			(layer "F.Fab")
			(hide yes)
			(effects
				(font
					(size 1.27 1.27)
					(thickness 0.15)
				)
			)
		)
		(property "Description" "SMD Multilayer Ceramic Capacitor"
			(at 0 0 0)
			(layer "F.Fab")
			(hide yes)
			(effects
				(font
					(size 1.27 1.27)
					(thickness 0.15)
				)
			)
		)
		(property "MPN" "CL10A226MO7JZNC"
			(at 0 0 0)
			(unlocked yes)
			(layer "F.Fab")
			(hide yes)
			(effects
				(font
					(size 1 1)
					(thickness 0.15)
				)
			)
		)
		(property "Manufacturer" "Samsung Electro-Mechanics"
			(at 0 0 0)
			(unlocked yes)
			(layer "F.Fab")
			(hide yes)
			(effects
				(font
					(size 1 1)
					(thickness 0.15)
				)
			)
		)
		(property "License" "Apache-2.0"
			(at 0 0 0)
			(unlocked yes)
			(layer "F.Fab")
			(hide yes)
			(effects
				(font
					(size 1 1)
					(thickness 0.15)
				)
			)
		)
		(property "Author" "Antmicro"
			(at 0 0 0)
			(unlocked yes)
			(layer "F.Fab")
			(hide yes)
			(effects
				(font
					(size 1 1)
					(thickness 0.15)
				)
			)
		)
		(property "Val" "22u"
			(at 0 0 0)
			(unlocked yes)
			(layer "F.Fab")
			(hide yes)
			(effects
				(font
					(size 1 1)
					(thickness 0.15)
				)
			)
		)
		(property "Voltage" "16V"
			(at 0 0 0)
			(unlocked yes)
			(layer "F.Fab")
			(hide yes)
			(effects
				(font
					(size 1 1)
					(thickness 0.15)
				)
			)
		)
		(property "Dielectric" ""
			(at 0 0 0)
			(unlocked yes)
			(layer "F.Fab")
			(hide yes)
			(effects
				(font
					(size 1 1)
					(thickness 0.15)
				)
			)
		)
		(sheetname "/X710 DCDC converters/")
		(sheetfile "DCDC_converters_X710.kicad_sch")
		(attr smd)
		(fp_line
			(start -0.15 -0.55)
			(end 0.15 -0.55)
			(stroke
				(width 0.15)
				(type solid)
			)
			(layer "F.SilkS")
		)
		(fp_line
			(start -0.15 0.55)
			(end 0.15 0.55)
			(stroke
				(width 0.15)
				(type solid)
			)
			(layer "F.SilkS")
		)
		(fp_rect
			(start -1.25 -0.65)
			(end 1.25 0.65)
			(stroke
				(width 0.05)
				(type solid)
			)
			(fill no)
			(layer "F.CrtYd")
		)
		(fp_rect
			(start -0.8 -0.45)
			(end 0.8 0.45)
			(stroke
				(width 0.15)
				(type solid)
			)
			(fill no)
			(layer "F.Fab")
		)
		(fp_text user "License: Apache-2.0"
			(at -1.682 5.895 0)
			(layer "F.Fab")
			(effects
				(font
					(size 0.7 0.7)
					(thickness 0.15)
				)
				(justify left bottom)
			)
		)
		(fp_text user "${REFERENCE}"
			(at -1.682 3.895 0)
			(layer "F.Fab")
			(effects
				(font
					(size 0.7 0.7)
					(thickness 0.15)
				)
				(justify left bottom)
			)
		)
		(fp_text user "Author: Antmicro"
			(at -1.682 4.894 0)
			(layer "F.Fab")
			(effects
				(font
					(size 0.7 0.7)
					(thickness 0.15)
				)
				(justify left bottom)
			)
		)
		(pad "1" smd roundrect
			(at -0.7 0)
			(size 0.8 1.1)
			(layers "F.Cu" "F.Mask" "F.Paste")
			(roundrect_rratio 0.2)
			(net 23 "GND")
			(pintype "passive")
		)
		(pad "2" smd roundrect
			(at 0.7 0)
			(size 0.8 1.1)
			(layers "F.Cu" "F.Mask" "F.Paste")
			(roundrect_rratio 0.2)
			(net 40 "+5V")
			(pintype "passive")
		)
	)
	(footprint "antmicro-footprints:C_0402_1005Metric"
		(layer "F.Cu")
		(at 122.2 102.1)
		(descr "Capacitor SMD 0402")
		(tags "capacitor SMD 0402")
		(property "Reference" "C18"
			(at -2 0 0)
			(layer "F.SilkS")
			(effects
				(font
					(size 0.7 0.7)
					(thickness 0.15)
				)
			)
		)
		(property "Value" "C_1u_25V_0402"
			(at -1.022927 2.155213 0)
			(layer "F.Fab")
			(effects
				(font
					(size 0.7 0.7)
					(thickness 0.15)
				)
				(justify left bottom)
			)
		)
		(property "Datasheet" "https://www.murata.com/products/productdetail?partno=GRM155R61E105KE11%23"
			(at 0 0 0)
			(layer "F.Fab")
			(hide yes)
			(effects
				(font
					(size 1.27 1.27)
					(thickness 0.15)
				)
			)
		)
		(property "Description" "SMD Multilayer Ceramic Capacitor, 1 µF, 25 V, 0402 [1005 Metric], ± 10%, X5R, GRM Series"
			(at 0 0 0)
			(layer "F.Fab")
			(hide yes)
			(effects
				(font
					(size 1.27 1.27)
					(thickness 0.15)
				)
			)
		)
		(property "MPN" "GRM155R61E105KE11J"
			(at 0 0 0)
			(unlocked yes)
			(layer "F.Fab")
			(hide yes)
			(effects
				(font
					(size 1 1)
					(thickness 0.15)
				)
			)
		)
		(property "Manufacturer" "Murata"
			(at 0 0 0)
			(unlocked yes)
			(layer "F.Fab")
			(hide yes)
			(effects
				(font
					(size 1 1)
					(thickness 0.15)
				)
			)
		)
		(property "License" "Apache-2.0"
			(at 0 0 0)
			(unlocked yes)
			(layer "F.Fab")
			(hide yes)
			(effects
				(font
					(size 1 1)
					(thickness 0.15)
				)
			)
		)
		(property "Author" "Antmicro"
			(at 0 0 0)
			(unlocked yes)
			(layer "F.Fab")
			(hide yes)
			(effects
				(font
					(size 1 1)
					(thickness 0.15)
				)
			)
		)
		(property "Val" "1u"
			(at 0 0 0)
			(unlocked yes)
			(layer "F.Fab")
			(hide yes)
			(effects
				(font
					(size 1 1)
					(thickness 0.15)
				)
			)
		)
		(property "Voltage" "25V"
			(at 0 0 0)
			(unlocked yes)
			(layer "F.Fab")
			(hide yes)
			(effects
				(font
					(size 1 1)
					(thickness 0.15)
				)
			)
		)
		(property "Dielectric" "X5R"
			(at 0 0 0)
			(unlocked yes)
			(layer "F.Fab")
			(hide yes)
			(effects
				(font
					(size 1 1)
					(thickness 0.15)
				)
			)
		)
		(sheetname "/PD and TB DC-DC/")
		(sheetfile "PD_and_TB_DC_DC.kicad_sch")
		(attr smd)
		(fp_rect
			(start -0.925 -0.47)
			(end 0.925 0.47)
			(stroke
				(width 0.05)
				(type default)
			)
			(fill no)
			(layer "F.CrtYd")
		)
		(fp_line
			(start -0.494 -0.25)
			(end 0.504 -0.25)
			(stroke
				(width 0.15)
				(type solid)
			)
			(layer "F.Fab")
		)
		(fp_line
			(start -0.494 0.248)
			(end -0.494 -0.25)
			(stroke
				(width 0.15)
				(type solid)
			)
			(layer "F.Fab")
		)
		(fp_line
			(start 0.504 -0.25)
			(end 0.504 0.248)
			(stroke
				(width 0.15)
				(type solid)
			)
			(layer "F.Fab")
		)
		(fp_line
			(start 0.504 0.248)
			(end -0.494 0.248)
			(stroke
				(width 0.15)
				(type solid)
			)
			(layer "F.Fab")
		)
		(fp_text user "${REFERENCE}"
			(at -0.939 4.599 0)
			(layer "F.Fab")
			(effects
				(font
					(size 0.7 0.7)
					(thickness 0.15)
				)
				(justify left bottom)
			)
		)
		(fp_text user "License: Apache-2.0"
			(at -0.939 5.799 0)
			(layer "F.Fab")
			(effects
				(font
					(size 0.7 0.7)
					(thickness 0.15)
				)
				(justify left bottom)
			)
		)
		(fp_text user "Author: Antmicro"
			(at -0.939 3.399 0)
			(layer "F.Fab")
			(effects
				(font
					(size 0.7 0.7)
					(thickness 0.15)
				)
				(justify left bottom)
			)
		)
		(pad "1" smd roundrect
			(at -0.48 0)
			(size 0.59 0.64)
			(layers "F.Cu" "F.Mask" "F.Paste")
			(roundrect_rratio 0.25)
			(net 23 "GND")
			(pintype "passive")
		)
		(pad "2" smd roundrect
			(at 0.48 0)
			(size 0.59 0.64)
			(layers "F.Cu" "F.Mask" "F.Paste")
			(roundrect_rratio 0.25)
			(net 399 "Net-(D4-A)")
			(pintype "passive")
		)
	)
	(footprint "antmicro-footprints:C_0402_1005Metric"
		(layer "F.Cu")
		(at 134.85 131.1 90)
		(descr "Capacitor SMD 0402")
		(tags "capacitor SMD 0402")
		(property "Reference" "C91"
			(at -0.170996 7.15 90)
			(layer "F.SilkS")
			(effects
				(font
					(size 0.7 0.7)
					(thickness 0.15)
				)
				(justify left bottom)
			)
		)
		(property "Value" "C_100n_0402"
			(at -1.022927 2.155213 90)
			(layer "F.Fab")
			(effects
				(font
					(size 0.7 0.7)
					(thickness 0.15)
				)
				(justify left bottom)
			)
		)
		(property "Datasheet" "https://www.murata.com/products/productdetail?partno=GRM155R61H104KE14%23"
			(at 0 0 90)
			(layer "F.Fab")
			(hide yes)
			(effects
				(font
					(size 1.27 1.27)
					(thickness 0.15)
				)
			)
		)
		(property "Description" "SMD Multilayer Ceramic Capacitor, 0.1 µF, 50 V, 0402 [1005 Metric], ± 10%, X5R, GRM Series"
			(at 0 0 90)
			(layer "F.Fab")
			(hide yes)
			(effects
				(font
					(size 1.27 1.27)
					(thickness 0.15)
				)
			)
		)
		(property "MPN" "GRM155R61H104KE14D"
			(at 0 0 90)
			(unlocked yes)
			(layer "F.Fab")
			(hide yes)
			(effects
				(font
					(size 1 1)
					(thickness 0.15)
				)
			)
		)
		(property "Manufacturer" "Murata"
			(at 0 0 90)
			(unlocked yes)
			(layer "F.Fab")
			(hide yes)
			(effects
				(font
					(size 1 1)
					(thickness 0.15)
				)
			)
		)
		(property "License" "Apache-2.0"
			(at 0 0 90)
			(unlocked yes)
			(layer "F.Fab")
			(hide yes)
			(effects
				(font
					(size 1 1)
					(thickness 0.15)
				)
			)
		)
		(property "Val" "100n"
			(at 0 0 90)
			(unlocked yes)
			(layer "F.Fab")
			(hide yes)
			(effects
				(font
					(size 1 1)
					(thickness 0.15)
				)
			)
		)
		(property "Voltage" "50V"
			(at 0 0 90)
			(unlocked yes)
			(layer "F.Fab")
			(hide yes)
			(effects
				(font
					(size 1 1)
					(thickness 0.15)
				)
			)
		)
		(property "Dielectric" "X5R"
			(at 0 0 90)
			(unlocked yes)
			(layer "F.Fab")
			(hide yes)
			(effects
				(font
					(size 1 1)
					(thickness 0.15)
				)
			)
		)
		(property "Author" "Antmicro"
			(at 0 0 90)
			(unlocked yes)
			(layer "F.Fab")
			(hide yes)
			(effects
				(font
					(size 1 1)
					(thickness 0.15)
				)
			)
		)
		(sheetname "/TB Controller - Power/")
		(sheetfile "tb-power.kicad_sch")
		(attr smd)
		(fp_rect
			(start -0.925 -0.47)
			(end 0.925 0.47)
			(stroke
				(width 0.05)
				(type default)
			)
			(fill no)
			(layer "F.CrtYd")
		)
		(fp_line
			(start 0.504 -0.25)
			(end 0.504 0.248)
			(stroke
				(width 0.15)
				(type solid)
			)
			(layer "F.Fab")
		)
		(fp_line
			(start -0.494 -0.25)
			(end 0.504 -0.25)
			(stroke
				(width 0.15)
				(type solid)
			)
			(layer "F.Fab")
		)
		(fp_line
			(start 0.504 0.248)
			(end -0.494 0.248)
			(stroke
				(width 0.15)
				(type solid)
			)
			(layer "F.Fab")
		)
		(fp_line
			(start -0.494 0.248)
			(end -0.494 -0.25)
			(stroke
				(width 0.15)
				(type solid)
			)
			(layer "F.Fab")
		)
		(fp_text user "${REFERENCE}"
			(at -0.939 4.599 90)
			(layer "F.Fab")
			(effects
				(font
					(size 0.7 0.7)
					(thickness 0.15)
				)
				(justify left bottom)
			)
		)
		(fp_text user "License: Apache-2.0"
			(at -0.939 5.799 90)
			(layer "F.Fab")
			(effects
				(font
					(size 0.7 0.7)
					(thickness 0.15)
				)
				(justify left bottom)
			)
		)
		(fp_text user "Author: Antmicro"
			(at -0.939 3.399 90)
			(layer "F.Fab")
			(effects
				(font
					(size 0.7 0.7)
					(thickness 0.15)
				)
				(justify left bottom)
			)
		)
		(pad "1" smd roundrect
			(at -0.48 0 90)
			(size 0.59 0.64)
			(layers "F.Cu" "F.Mask" "F.Paste")
			(roundrect_rratio 0.25)
			(net 23 "GND")
			(pintype "passive")
		)
		(pad "2" smd roundrect
			(at 0.48 0 90)
			(size 0.59 0.64)
			(layers "F.Cu" "F.Mask" "F.Paste")
			(roundrect_rratio 0.25)
			(net 57 "+3V3_TB")
			(pintype "passive")
		)
	)
	(footprint "antmicro-footprints:FB_0603_1608Metric"
		(layer "F.Cu")
		(at 164.105 99.224999 90)
		(property "Reference" "FB7"
			(at 0 7.695 90)
			(layer "F.SilkS")
			(effects
				(font
					(size 0.7 0.7)
					(thickness 0.15)
				)
			)
		)
		(property "Value" "FB_33Z_3A_Murata-BLM18PG_0603"
			(at 0 1.5 90)
			(layer "F.Fab")
			(effects
				(font
					(size 0.7 0.7)
					(thickness 0.15)
				)
				(justify left bottom)
			)
		)
		(property "Datasheet" "https://www.murata.com/products/productdata/8796737273886/QNFA9101.pdf?1649080818000"
			(at 0 0 90)
			(layer "F.Fab")
			(hide yes)
			(effects
				(font
					(size 1.27 1.27)
					(thickness 0.15)
				)
			)
		)
		(property "Description" "Ferrite Bead, 0603 [1608 Metric], 33 ohm, 3 A, BLM18PG, 0.025 ohm, ± 25%, DC power line"
			(at 0 0 90)
			(layer "F.Fab")
			(hide yes)
			(effects
				(font
					(size 1.27 1.27)
					(thickness 0.15)
				)
			)
		)
		(property "Val" "33Z/3A"
			(at 0 0 90)
			(unlocked yes)
			(layer "F.Fab")
			(hide yes)
			(effects
				(font
					(size 1 1)
					(thickness 0.15)
				)
			)
		)
		(property "MPN" "BLM18PG330SH1D"
			(at 0 0 90)
			(unlocked yes)
			(layer "F.Fab")
			(hide yes)
			(effects
				(font
					(size 1 1)
					(thickness 0.15)
				)
			)
		)
		(property "Manufacturer" "Murata"
			(at 0 0 90)
			(unlocked yes)
			(layer "F.Fab")
			(hide yes)
			(effects
				(font
					(size 1 1)
					(thickness 0.15)
				)
			)
		)
		(property "Current" ""
			(at 0 0 90)
			(unlocked yes)
			(layer "F.Fab")
			(hide yes)
			(effects
				(font
					(size 1 1)
					(thickness 0.15)
				)
			)
		)
		(property "Author" "Antmicro"
			(at 0 0 90)
			(unlocked yes)
			(layer "F.Fab")
			(hide yes)
			(effects
				(font
					(size 1 1)
					(thickness 0.15)
				)
			)
		)
		(property "License" "Apache-2.0"
			(at 0 0 90)
			(unlocked yes)
			(layer "F.Fab")
			(hide yes)
			(effects
				(font
					(size 1 1)
					(thickness 0.15)
				)
			)
		)
		(sheetname "/X710-AT2 power/")
		(sheetfile "x710-at2-power.kicad_sch")
		(attr smd)
		(fp_line
			(start -0.15 -0.4)
			(end 0.15 -0.4)
			(stroke
				(width 0.15)
				(type solid)
			)
			(layer "F.SilkS")
		)
		(fp_line
			(start -0.15 0.4)
			(end 0.15 0.4)
			(stroke
				(width 0.15)
				(type solid)
			)
			(layer "F.SilkS")
		)
		(fp_rect
			(start -1.25 -0.65)
			(end 1.25 0.65)
			(stroke
				(width 0.05)
				(type solid)
			)
			(fill no)
			(layer "F.CrtYd")
		)
		(fp_line
			(start 0.8 -0.408)
			(end -0.803 -0.408)
			(stroke
				(width 0.15)
				(type solid)
			)
			(layer "F.Fab")
		)
		(fp_line
			(start 0.8 -0.408)
			(end 0.8 0.406)
			(stroke
				(width 0.15)
				(type solid)
			)
			(layer "F.Fab")
		)
		(fp_line
			(start 0.8 0.406)
			(end -0.803 0.406)
			(stroke
				(width 0.15)
				(type solid)
			)
			(layer "F.Fab")
		)
		(fp_line
			(start -0.803 0.406)
			(end -0.803 -0.408)
			(stroke
				(width 0.15)
				(type solid)
			)
			(layer "F.Fab")
		)
		(fp_text user "Author: Antmicro"
			(at -1.653 3.162 90)
			(layer "F.Fab")
			(effects
				(font
					(size 0.7 0.7)
					(thickness 0.15)
				)
				(justify left bottom)
			)
		)
		(fp_text user "${REFERENCE}"
			(at -1.653 4.6 90)
			(layer "F.Fab")
			(effects
				(font
					(size 0.7 0.7)
					(thickness 0.15)
				)
				(justify left bottom)
			)
		)
		(fp_text user "License: Apache-2.0"
			(at -1.653 5.9 90)
			(layer "F.Fab")
			(effects
				(font
					(size 0.7 0.7)
					(thickness 0.15)
				)
				(justify left bottom)
			)
		)
		(pad "1" smd roundrect
			(at -0.7 0 90)
			(size 0.8 1)
			(layers "F.Cu" "F.Mask" "F.Paste")
			(roundrect_rratio 0.2)
			(net 136 "+1V0")
			(pintype "passive")
		)
		(pad "2" smd roundrect
			(at 0.7 0 90)
			(size 0.8 1)
			(layers "F.Cu" "F.Mask" "F.Paste")
			(roundrect_rratio 0.2)
			(net 14 "P1_AVDDL")
			(pintype "passive")
		)
	)
	(footprint "antmicro-footprints:TDFN-8-1EP_2x3x0.75mm_P0.5mm_EP1.75x1.63mm"
		(layer "F.Cu")
		(at 120.5 71)
		(descr "8-Lead Plastic Dual Flat, 2x3mm Body")
		(tags "DFN 0.5")
		(property "Reference" "U18"
			(at -2.2 2.3 0)
			(layer "F.SilkS")
			(effects
				(font
					(size 0.7 0.7)
					(thickness 0.15)
				)
				(justify left bottom)
			)
		)
		(property "Value" "MAX31740ATA+T"
			(at -2.1 3 0)
			(layer "F.Fab")
			(effects
				(font
					(size 0.7 0.7)
					(thickness 0.15)
				)
				(justify left bottom)
			)
		)
		(property "Datasheet" "https://www.analog.com/media/en/technical-documentation/data-sheets/max31740.pdf"
			(at 0 0 0)
			(layer "F.Fab")
			(hide yes)
			(effects
				(font
					(size 1.27 1.27)
					(thickness 0.15)
				)
			)
		)
		(property "Description" "Pwm fan speed controller, temperature measurement, Control speed of 2-, 3-, 4- Wire Fans"
			(at 0 0 0)
			(layer "F.Fab")
			(hide yes)
			(effects
				(font
					(size 1.27 1.27)
					(thickness 0.15)
				)
			)
		)
		(property "MPN" "MAX31740ATA+T"
			(at 0 0 0)
			(unlocked yes)
			(layer "F.Fab")
			(hide yes)
			(effects
				(font
					(size 1 1)
					(thickness 0.15)
				)
			)
		)
		(property "Manufacturer" "Analog Devices"
			(at 0 0 0)
			(unlocked yes)
			(layer "F.Fab")
			(hide yes)
			(effects
				(font
					(size 1 1)
					(thickness 0.15)
				)
			)
		)
		(property "Author" "Antmicro"
			(at 0 0 0)
			(unlocked yes)
			(layer "F.Fab")
			(hide yes)
			(effects
				(font
					(size 1 1)
					(thickness 0.15)
				)
			)
		)
		(property "License" "Apache-2.0"
			(at 0 0 0)
			(unlocked yes)
			(layer "F.Fab")
			(hide yes)
			(effects
				(font
					(size 1 1)
					(thickness 0.15)
				)
			)
		)
		(sheetname "/Fan controller/")
		(sheetfile "fan-controller.kicad_sch")
		(attr smd)
		(fp_circle
			(center -1.8 -1.1)
			(end -1.75 -1.1)
			(stroke
				(width 0.15)
				(type solid)
			)
			(fill yes)
			(layer "F.SilkS")
		)
		(fp_rect
			(start -2.05 -1.25)
			(end 2.05 1.25)
			(stroke
				(width 0.05)
				(type default)
			)
			(fill no)
			(layer "F.CrtYd")
		)
		(fp_text user "${REFERENCE}"
			(at -2.12 6.2 0)
			(layer "F.Fab")
			(effects
				(font
					(size 0.7 0.7)
					(thickness 0.15)
				)
				(justify left bottom)
			)
		)
		(fp_text user "License: Apache-2.0"
			(at -2.12 5 0)
			(layer "F.Fab")
			(effects
				(font
					(size 0.7 0.7)
					(thickness 0.15)
				)
				(justify left bottom)
			)
		)
		(fp_text user "Author: Antmicro"
			(at -2.12 7.4 0)
			(layer "F.Fab")
			(effects
				(font
					(size 0.7 0.7)
					(thickness 0.15)
				)
				(justify left bottom)
			)
		)
		(pad "1" smd rect
			(at -1.5 -0.75 90)
			(size 0.3 0.75)
			(layers "F.Cu" "F.Mask" "F.Paste")
			(net 157 "/Fan controller/DMIN")
			(pinfunction "DMIN")
			(pintype "passive")
		)
		(pad "2" smd rect
			(at -1.5 -0.25 90)
			(size 0.3 0.75)
			(layers "F.Cu" "F.Mask" "F.Paste")
			(net 158 "/Fan controller/SLOPE")
			(pinfunction "SLOPE")
			(pintype "passive")
		)
		(pad "3" smd rect
			(at -1.5 0.25 90)
			(size 0.3 0.75)
			(layers "F.Cu" "F.Mask" "F.Paste")
			(net 151 "/Fan controller/SENSE")
			(pinfunction "SENSE")
			(pintype "passive")
		)
		(pad "4" smd rect
			(at -1.5 0.75 90)
			(size 0.3 0.75)
			(layers "F.Cu" "F.Mask" "F.Paste")
			(net 23 "GND")
			(pinfunction "GND")
			(pintype "power_in")
		)
		(pad "5" smd rect
			(at 1.5 0.75 90)
			(size 0.3 0.75)
			(layers "F.Cu" "F.Mask" "F.Paste")
			(net 152 "/Fan controller/FREQ")
			(pinfunction "FREQ")
			(pintype "passive")
		)
		(pad "6" smd rect
			(at 1.5 0.25 90)
			(size 0.3 0.75)
			(layers "F.Cu" "F.Mask" "F.Paste")
			(net 156 "/Fan controller/D0")
			(pinfunction "D0")
			(pintype "passive")
		)
		(pad "7" smd rect
			(at 1.5 -0.25 90)
			(size 0.3 0.75)
			(layers "F.Cu" "F.Mask" "F.Paste")
			(net 154 "/Fan controller/PWM")
			(pinfunction "PWM_OUT")
			(pintype "output")
		)
		(pad "8" smd rect
			(at 1.5 -0.75 90)
			(size 0.3 0.75)
			(layers "F.Cu" "F.Mask" "F.Paste")
			(net 40 "+5V")
			(pinfunction "VDD")
			(pintype "power_in")
		)
		(pad "9" smd rect
			(at 0 0 90)
			(size 1.63 1.75)
			(layers "F.Cu" "F.Mask" "F.Paste")
			(net 23 "GND")
			(pinfunction "EP")
			(pintype "power_in")
		)
	)
	(footprint "antmicro-footprints:C_0805_2012Metric"
		(layer "F.Cu")
		(at 161.394999 97.024998 180)
		(descr "Capacitor SMD 0805")
		(tags "capacitor SMD 0805")
		(property "Reference" "C170"
			(at -7.695 0 180)
			(layer "F.SilkS")
			(effects
				(font
					(size 0.7 0.7)
					(thickness 0.15)
				)
			)
		)
		(property "Value" "C_100u_0805"
			(at -2.055717 1.963152 180)
			(layer "F.Fab")
			(effects
				(font
					(size 0.7 0.7)
					(thickness 0.15)
				)
				(justify left bottom)
			)
		)
		(property "Datasheet" "https://www.murata.com/products/productdetail?partno=GRM21BR60J107ME15%23"
			(at 0 0 180)
			(layer "F.Fab")
			(hide yes)
			(effects
				(font
					(size 1.27 1.27)
					(thickness 0.15)
				)
			)
		)
		(property "Description" "SMD Multilayer Ceramic Capacitor, 100 µF, 6.3 V, 0805 [2012 Metric], ± 20%, X5R, GRM Series"
			(at 0 0 180)
			(layer "F.Fab")
			(hide yes)
			(effects
				(font
					(size 1.27 1.27)
					(thickness 0.15)
				)
			)
		)
		(property "MPN" "GRM21BR60J107ME15L"
			(at 0 0 180)
			(unlocked yes)
			(layer "F.Fab")
			(hide yes)
			(effects
				(font
					(size 1 1)
					(thickness 0.15)
				)
			)
		)
		(property "Manufacturer" "Murata"
			(at 0 0 180)
			(unlocked yes)
			(layer "F.Fab")
			(hide yes)
			(effects
				(font
					(size 1 1)
					(thickness 0.15)
				)
			)
		)
		(property "License" "Apache-2.0"
			(at 0 0 180)
			(unlocked yes)
			(layer "F.Fab")
			(hide yes)
			(effects
				(font
					(size 1 1)
					(thickness 0.15)
				)
			)
		)
		(property "Author" "Antmicro"
			(at 0 0 180)
			(unlocked yes)
			(layer "F.Fab")
			(hide yes)
			(effects
				(font
					(size 1 1)
					(thickness 0.15)
				)
			)
		)
		(property "Val" "100u"
			(at 0 0 180)
			(unlocked yes)
			(layer "F.Fab")
			(hide yes)
			(effects
				(font
					(size 1 1)
					(thickness 0.15)
				)
			)
		)
		(property "Voltage" ""
			(at 0 0 180)
			(unlocked yes)
			(layer "F.Fab")
			(hide yes)
			(effects
				(font
					(size 1 1)
					(thickness 0.15)
				)
			)
		)
		(property "Dielectric" ""
			(at 0 0 180)
			(unlocked yes)
			(layer "F.Fab")
			(hide yes)
			(effects
				(font
					(size 1 1)
					(thickness 0.15)
				)
			)
		)
		(property "Public" "False"
			(at 0 0 180)
			(unlocked yes)
			(layer "F.Fab")
			(hide yes)
			(effects
				(font
					(size 1 1)
					(thickness 0.15)
				)
			)
		)
		(sheetname "/X710-AT2 power/")
		(sheetfile "x710-at2-power.kicad_sch")
		(attr smd)
		(fp_line
			(start -0.3 0.7)
			(end 0.3 0.7)
			(stroke
				(width 0.15)
				(type solid)
			)
			(layer "F.SilkS")
		)
		(fp_line
			(start -0.3 -0.7)
			(end 0.3 -0.7)
			(stroke
				(width 0.15)
				(type solid)
			)
			(layer "F.SilkS")
		)
		(fp_rect
			(start 1.95 -0.9)
			(end -1.95 0.9)
			(stroke
				(width 0.05)
				(type default)
			)
			(fill no)
			(layer "F.CrtYd")
		)
		(fp_rect
			(start -0.95 -0.675)
			(end 0.95 0.675)
			(stroke
				(width 0.15)
				(type solid)
			)
			(fill no)
			(layer "F.Fab")
		)
		(fp_text user "${REFERENCE}"
			(at -1.9 3.947 180)
			(layer "F.Fab")
			(effects
				(font
					(size 0.7 0.7)
					(thickness 0.15)
				)
				(justify left bottom)
			)
		)
		(fp_text user "License: Apache-2.0"
			(at -1.9 4.947 180)
			(layer "F.Fab")
			(effects
				(font
					(size 0.7 0.7)
					(thickness 0.15)
				)
				(justify left bottom)
			)
		)
		(fp_text user "Author: Antmicro"
			(at -1.9 5.947 180)
			(layer "F.Fab")
			(effects
				(font
					(size 0.7 0.7)
					(thickness 0.15)
				)
				(justify left bottom)
			)
		)
		(pad "1" smd roundrect
			(at -1.1 0 180)
			(size 1.2 1.3)
			(layers "F.Cu" "F.Mask" "F.Paste")
			(roundrect_rratio 0.25)
			(net 23 "GND")
			(pintype "passive")
		)
		(pad "2" smd roundrect
			(at 1.1 0 180)
			(size 1.2 1.3)
			(layers "F.Cu" "F.Mask" "F.Paste")
			(roundrect_rratio 0.25)
			(net 5 "P0_AVDDL")
			(pintype "passive")
		)
	)
	(footprint "antmicro-footprints:R_0402_1005Metric"
		(layer "F.Cu")
		(at 117.6 114.42 -90)
		(descr "Resistor SMD 0402")
		(tags "resistor SMD 0402")
		(property "Reference" "R32"
			(at 1.98 -0.65 270)
			(layer "F.SilkS")
			(effects
				(font
					(size 0.7 0.7)
					(thickness 0.15)
				)
			)
		)
		(property "Value" "R_330R_0402"
			(at -1.011843 1.772047 270)
			(layer "F.Fab")
			(effects
				(font
					(size 0.7 0.7)
					(thickness 0.15)
				)
				(justify left bottom)
			)
		)
		(property "Datasheet" "https://www.bourns.com/docs/product-datasheets/cr.pdf"
			(at 0 0 270)
			(layer "F.Fab")
			(hide yes)
			(effects
				(font
					(size 1.27 1.27)
					(thickness 0.15)
				)
			)
		)
		(property "Description" "SMD Chip Resistor, 330 ohm, ± 1%, 62.5 mW, 0402 [1005 Metric], Thick Film, General Purpose"
			(at 0 0 270)
			(layer "F.Fab")
			(hide yes)
			(effects
				(font
					(size 1.27 1.27)
					(thickness 0.15)
				)
			)
		)
		(property "MPN" "CR0402-FX-3300GLF"
			(at 0 0 270)
			(unlocked yes)
			(layer "F.Fab")
			(hide yes)
			(effects
				(font
					(size 1 1)
					(thickness 0.15)
				)
			)
		)
		(property "Manufacturer" "Bourns"
			(at 0 0 270)
			(unlocked yes)
			(layer "F.Fab")
			(hide yes)
			(effects
				(font
					(size 1 1)
					(thickness 0.15)
				)
			)
		)
		(property "License" "Apache-2.0"
			(at 0 0 270)
			(unlocked yes)
			(layer "F.Fab")
			(hide yes)
			(effects
				(font
					(size 1 1)
					(thickness 0.15)
				)
			)
		)
		(property "Val" "330R"
			(at 0 0 270)
			(unlocked yes)
			(layer "F.Fab")
			(hide yes)
			(effects
				(font
					(size 1 1)
					(thickness 0.15)
				)
			)
		)
		(property "Tolerance" "1%"
			(at 0 0 270)
			(unlocked yes)
			(layer "F.Fab")
			(hide yes)
			(effects
				(font
					(size 1 1)
					(thickness 0.15)
				)
			)
		)
		(property "Author" "Antmicro"
			(at 0 0 270)
			(unlocked yes)
			(layer "F.Fab")
			(hide yes)
			(effects
				(font
					(size 1 1)
					(thickness 0.15)
				)
			)
		)
		(sheetname "/PD and TB DC-DC/")
		(sheetfile "PD_and_TB_DC_DC.kicad_sch")
		(attr smd)
		(fp_rect
			(start -0.925 -0.47)
			(end 0.925 0.47)
			(stroke
				(width 0.05)
				(type default)
			)
			(fill no)
			(layer "F.CrtYd")
		)
		(fp_rect
			(start -0.5 -0.25)
			(end 0.5 0.25)
			(stroke
				(width 0.15)
				(type solid)
			)
			(fill no)
			(layer "F.Fab")
		)
		(fp_text user "Author: Antmicro"
			(at -0.95 4.169 270)
			(layer "F.Fab")
			(effects
				(font
					(size 0.7 0.7)
					(thickness 0.15)
				)
				(justify left bottom)
			)
		)
		(fp_text user "${REFERENCE}"
			(at -0.95 3.168 270)
			(layer "F.Fab")
			(effects
				(font
					(size 0.7 0.7)
					(thickness 0.15)
				)
				(justify left bottom)
			)
		)
		(fp_text user "License: Apache-2.0"
			(at -0.95 5.169 270)
			(layer "F.Fab")
			(effects
				(font
					(size 0.7 0.7)
					(thickness 0.15)
				)
				(justify left bottom)
			)
		)
		(pad "1" smd roundrect
			(at -0.48 0 270)
			(size 0.59 0.64)
			(layers "F.Cu" "F.Mask" "F.Paste")
			(roundrect_rratio 0.25)
			(net 23 "GND")
			(pintype "passive")
		)
		(pad "2" smd roundrect
			(at 0.48 0 270)
			(size 0.59 0.64)
			(layers "F.Cu" "F.Mask" "F.Paste")
			(roundrect_rratio 0.25)
			(net 195 "Net-(D4-C)")
			(pintype "passive")
		)
	)
	(footprint "antmicro-footprints:C_0805_2012Metric"
		(layer "F.Cu")
		(at 161.395 95.174999 180)
		(descr "Capacitor SMD 0805")
		(tags "capacitor SMD 0805")
		(property "Reference" "C178"
			(at -7.695 0 180)
			(layer "F.SilkS")
			(effects
				(font
					(size 0.7 0.7)
					(thickness 0.15)
				)
			)
		)
		(property "Value" "C_100u_0805"
			(at -2.055717 1.963152 180)
			(layer "F.Fab")
			(effects
				(font
					(size 0.7 0.7)
					(thickness 0.15)
				)
				(justify left bottom)
			)
		)
		(property "Datasheet" "https://www.murata.com/products/productdetail?partno=GRM21BR60J107ME15%23"
			(at 0 0 180)
			(layer "F.Fab")
			(hide yes)
			(effects
				(font
					(size 1.27 1.27)
					(thickness 0.15)
				)
			)
		)
		(property "Description" "SMD Multilayer Ceramic Capacitor, 100 µF, 6.3 V, 0805 [2012 Metric], ± 20%, X5R, GRM Series"
			(at 0 0 180)
			(layer "F.Fab")
			(hide yes)
			(effects
				(font
					(size 1.27 1.27)
					(thickness 0.15)
				)
			)
		)
		(property "MPN" "GRM21BR60J107ME15L"
			(at 0 0 180)
			(unlocked yes)
			(layer "F.Fab")
			(hide yes)
			(effects
				(font
					(size 1 1)
					(thickness 0.15)
				)
			)
		)
		(property "Manufacturer" "Murata"
			(at 0 0 180)
			(unlocked yes)
			(layer "F.Fab")
			(hide yes)
			(effects
				(font
					(size 1 1)
					(thickness 0.15)
				)
			)
		)
		(property "License" "Apache-2.0"
			(at 0 0 180)
			(unlocked yes)
			(layer "F.Fab")
			(hide yes)
			(effects
				(font
					(size 1 1)
					(thickness 0.15)
				)
			)
		)
		(property "Author" "Antmicro"
			(at 0 0 180)
			(unlocked yes)
			(layer "F.Fab")
			(hide yes)
			(effects
				(font
					(size 1 1)
					(thickness 0.15)
				)
			)
		)
		(property "Val" "100u"
			(at 0 0 180)
			(unlocked yes)
			(layer "F.Fab")
			(hide yes)
			(effects
				(font
					(size 1 1)
					(thickness 0.15)
				)
			)
		)
		(property "Voltage" ""
			(at 0 0 180)
			(unlocked yes)
			(layer "F.Fab")
			(hide yes)
			(effects
				(font
					(size 1 1)
					(thickness 0.15)
				)
			)
		)
		(property "Dielectric" ""
			(at 0 0 180)
			(unlocked yes)
			(layer "F.Fab")
			(hide yes)
			(effects
				(font
					(size 1 1)
					(thickness 0.15)
				)
			)
		)
		(property "Public" "False"
			(at 0 0 180)
			(unlocked yes)
			(layer "F.Fab")
			(hide yes)
			(effects
				(font
					(size 1 1)
					(thickness 0.15)
				)
			)
		)
		(sheetname "/X710-AT2 power/")
		(sheetfile "x710-at2-power.kicad_sch")
		(attr smd)
		(fp_line
			(start -0.3 0.7)
			(end 0.3 0.7)
			(stroke
				(width 0.15)
				(type solid)
			)
			(layer "F.SilkS")
		)
		(fp_line
			(start -0.3 -0.7)
			(end 0.3 -0.7)
			(stroke
				(width 0.15)
				(type solid)
			)
			(layer "F.SilkS")
		)
		(fp_rect
			(start 1.95 -0.9)
			(end -1.95 0.9)
			(stroke
				(width 0.05)
				(type default)
			)
			(fill no)
			(layer "F.CrtYd")
		)
		(fp_rect
			(start -0.95 -0.675)
			(end 0.95 0.675)
			(stroke
				(width 0.15)
				(type solid)
			)
			(fill no)
			(layer "F.Fab")
		)
		(fp_text user "${REFERENCE}"
			(at -1.9 3.947 180)
			(layer "F.Fab")
			(effects
				(font
					(size 0.7 0.7)
					(thickness 0.15)
				)
				(justify left bottom)
			)
		)
		(fp_text user "License: Apache-2.0"
			(at -1.9 4.947 180)
			(layer "F.Fab")
			(effects
				(font
					(size 0.7 0.7)
					(thickness 0.15)
				)
				(justify left bottom)
			)
		)
		(fp_text user "Author: Antmicro"
			(at -1.9 5.947 180)
			(layer "F.Fab")
			(effects
				(font
					(size 0.7 0.7)
					(thickness 0.15)
				)
				(justify left bottom)
			)
		)
		(pad "1" smd roundrect
			(at -1.1 0 180)
			(size 1.2 1.3)
			(layers "F.Cu" "F.Mask" "F.Paste")
			(roundrect_rratio 0.25)
			(net 23 "GND")
			(pintype "passive")
		)
		(pad "2" smd roundrect
			(at 1.1 0 180)
			(size 1.2 1.3)
			(layers "F.Cu" "F.Mask" "F.Paste")
			(roundrect_rratio 0.25)
			(net 5 "P0_AVDDL")
			(pintype "passive")
		)
	)
	(footprint "antmicro-footprints:R_0402_1005Metric"
		(layer "F.Cu")
		(at 132.4 82.8 -90)
		(descr "Resistor SMD 0402")
		(tags "resistor SMD 0402")
		(property "Reference" "R225"
			(at 1.6 0.6 270)
			(layer "F.SilkS")
			(effects
				(font
					(size 0.7 0.7)
					(thickness 0.15)
				)
				(justify left bottom)
			)
		)
		(property "Value" "R_10k_0402"
			(at -1.011843 1.772047 270)
			(layer "F.Fab")
			(effects
				(font
					(size 0.7 0.7)
					(thickness 0.15)
				)
				(justify left bottom)
			)
		)
		(property "Datasheet" "https://www.bourns.com/docs/product-datasheets/cr.pdf"
			(at 0 0 270)
			(layer "F.Fab")
			(hide yes)
			(effects
				(font
					(size 1.27 1.27)
					(thickness 0.15)
				)
			)
		)
		(property "Description" "SMD Chip Resistor, 10 kohm, ± 1%, 62.5 mW, 0402 [1005 Metric], Thick Film, General Purpose"
			(at 0 0 270)
			(layer "F.Fab")
			(hide yes)
			(effects
				(font
					(size 1.27 1.27)
					(thickness 0.15)
				)
			)
		)
		(property "MPN" "CR0402-FX-1002GLF"
			(at 0 0 270)
			(unlocked yes)
			(layer "F.Fab")
			(hide yes)
			(effects
				(font
					(size 1 1)
					(thickness 0.15)
				)
			)
		)
		(property "Manufacturer" "Bourns"
			(at 0 0 270)
			(unlocked yes)
			(layer "F.Fab")
			(hide yes)
			(effects
				(font
					(size 1 1)
					(thickness 0.15)
				)
			)
		)
		(property "License" "Apache-2.0"
			(at 0 0 270)
			(unlocked yes)
			(layer "F.Fab")
			(hide yes)
			(effects
				(font
					(size 1 1)
					(thickness 0.15)
				)
			)
		)
		(property "Author" "Antmicro"
			(at 0 0 270)
			(unlocked yes)
			(layer "F.Fab")
			(hide yes)
			(effects
				(font
					(size 1 1)
					(thickness 0.15)
				)
			)
		)
		(property "Val" "10k"
			(at 0 0 270)
			(unlocked yes)
			(layer "F.Fab")
			(hide yes)
			(effects
				(font
					(size 1 1)
					(thickness 0.15)
				)
			)
		)
		(property "Tolerance" "1%"
			(at 0 0 270)
			(unlocked yes)
			(layer "F.Fab")
			(hide yes)
			(effects
				(font
					(size 1 1)
					(thickness 0.15)
				)
			)
		)
		(sheetname "/X710 flash memory/")
		(sheetfile "flash_x710.kicad_sch")
		(attr smd)
		(fp_rect
			(start -0.925 -0.47)
			(end 0.925 0.47)
			(stroke
				(width 0.05)
				(type default)
			)
			(fill no)
			(layer "F.CrtYd")
		)
		(fp_rect
			(start -0.5 -0.25)
			(end 0.5 0.25)
			(stroke
				(width 0.15)
				(type solid)
			)
			(fill no)
			(layer "F.Fab")
		)
		(fp_text user "${REFERENCE}"
			(at -0.95 3.168 270)
			(layer "F.Fab")
			(effects
				(font
					(size 0.7 0.7)
					(thickness 0.15)
				)
				(justify left bottom)
			)
		)
		(fp_text user "Author: Antmicro"
			(at -0.95 4.169 270)
			(layer "F.Fab")
			(effects
				(font
					(size 0.7 0.7)
					(thickness 0.15)
				)
				(justify left bottom)
			)
		)
		(fp_text user "License: Apache-2.0"
			(at -0.95 5.169 270)
			(layer "F.Fab")
			(effects
				(font
					(size 0.7 0.7)
					(thickness 0.15)
				)
				(justify left bottom)
			)
		)
		(pad "1" smd roundrect
			(at -0.48 0 270)
			(size 0.59 0.64)
			(layers "F.Cu" "F.Mask" "F.Paste")
			(roundrect_rratio 0.25)
			(net 388 "/X710 flash memory/~{WP}")
			(pintype "passive")
		)
		(pad "2" smd roundrect
			(at 0.48 0 270)
			(size 0.59 0.64)
			(layers "F.Cu" "F.Mask" "F.Paste")
			(roundrect_rratio 0.25)
			(net 343 "/X710 flash memory/+3V3_FLASH")
			(pintype "passive")
		)
	)
	(footprint "antmicro-footprints:R_0402_1005Metric"
		(layer "F.Cu")
		(at 151.550002 113.150002)
		(descr "Resistor SMD 0402")
		(tags "resistor SMD 0402")
		(property "Reference" "R93"
			(at 14.149998 17.25 0)
			(layer "F.SilkS")
			(effects
				(font
					(size 0.7 0.7)
					(thickness 0.15)
				)
			)
		)
		(property "Value" "R_0R_0402"
			(at -1.011843 1.772047 0)
			(layer "F.Fab")
			(effects
				(font
					(size 0.7 0.7)
					(thickness 0.15)
				)
				(justify left bottom)
			)
		)
		(property "Datasheet" "https://industrial.panasonic.com/cdbs/www-data/pdf/RDA0000/AOA0000C301.pdf"
			(at 0 0 0)
			(layer "F.Fab")
			(hide yes)
			(effects
				(font
					(size 1.27 1.27)
					(thickness 0.15)
				)
			)
		)
		(property "Description" "SMD Chip Resistor, Jumper, 0 ohm, 100 mW, 0402 [1005 Metric], Thick Film, General Purpose"
			(at 0 0 0)
			(layer "F.Fab")
			(hide yes)
			(effects
				(font
					(size 1.27 1.27)
					(thickness 0.15)
				)
			)
		)
		(property "MPN" "ERJ2GE0R00X"
			(at 0 0 0)
			(unlocked yes)
			(layer "F.Fab")
			(hide yes)
			(effects
				(font
					(size 1 1)
					(thickness 0.15)
				)
			)
		)
		(property "Manufacturer" "Panasonic"
			(at 0 0 0)
			(unlocked yes)
			(layer "F.Fab")
			(hide yes)
			(effects
				(font
					(size 1 1)
					(thickness 0.15)
				)
			)
		)
		(property "License" "Apache-2.0"
			(at 0 0 0)
			(unlocked yes)
			(layer "F.Fab")
			(hide yes)
			(effects
				(font
					(size 1 1)
					(thickness 0.15)
				)
			)
		)
		(property "Author" "Antmicro"
			(at 0 0 0)
			(unlocked yes)
			(layer "F.Fab")
			(hide yes)
			(effects
				(font
					(size 1 1)
					(thickness 0.15)
				)
			)
		)
		(property "Val" "0R"
			(at 0 0 0)
			(unlocked yes)
			(layer "F.Fab")
			(hide yes)
			(effects
				(font
					(size 1 1)
					(thickness 0.15)
				)
			)
		)
		(property "Tolerance" "~"
			(at 0 0 0)
			(unlocked yes)
			(layer "F.Fab")
			(hide yes)
			(effects
				(font
					(size 1 1)
					(thickness 0.15)
				)
			)
		)
		(property "Current" "1A"
			(at 0 0 0)
			(unlocked yes)
			(layer "F.Fab")
			(hide yes)
			(effects
				(font
					(size 1 1)
					(thickness 0.15)
				)
			)
		)
		(sheetname "/X710 DCDC converters/")
		(sheetfile "DCDC_converters_X710.kicad_sch")
		(attr smd)
		(fp_rect
			(start -0.925 -0.47)
			(end 0.925 0.47)
			(stroke
				(width 0.05)
				(type default)
			)
			(fill no)
			(layer "F.CrtYd")
		)
		(fp_rect
			(start -0.5 -0.25)
			(end 0.5 0.25)
			(stroke
				(width 0.15)
				(type solid)
			)
			(fill no)
			(layer "F.Fab")
		)
		(fp_text user "License: Apache-2.0"
			(at -0.95 5.169 0)
			(layer "F.Fab")
			(effects
				(font
					(size 0.7 0.7)
					(thickness 0.15)
				)
				(justify left bottom)
			)
		)
		(fp_text user "Author: Antmicro"
			(at -0.95 4.169 0)
			(layer "F.Fab")
			(effects
				(font
					(size 0.7 0.7)
					(thickness 0.15)
				)
				(justify left bottom)
			)
		)
		(fp_text user "${REFERENCE}"
			(at -0.95 3.168 0)
			(layer "F.Fab")
			(effects
				(font
					(size 0.7 0.7)
					(thickness 0.15)
				)
				(justify left bottom)
			)
		)
		(pad "1" smd roundrect
			(at -0.48 0)
			(size 0.59 0.64)
			(layers "F.Cu" "F.Mask" "F.Paste")
			(roundrect_rratio 0.25)
			(net 379 "/X710 DCDC converters/VCCD_PG")
			(pintype "passive")
		)
		(pad "2" smd roundrect
			(at 0.48 0)
			(size 0.59 0.64)
			(layers "F.Cu" "F.Mask" "F.Paste")
			(roundrect_rratio 0.25)
			(net 384 "/X710 DCDC converters/1V88_EN")
			(pintype "passive")
		)
	)
	(footprint "antmicro-footprints:R_0603_1608Metric"
		(layer "F.Cu")
		(at 137.870002 91.25)
		(descr "Resistor SMD 0603")
		(tags "resistor SMD 0603")
		(property "Reference" "R108"
			(at 37.144997 -9.199999 0)
			(layer "F.SilkS")
			(effects
				(font
					(size 0.7 0.7)
					(thickness 0.15)
				)
			)
		)
		(property "Value" "R_0R_22.4A_0603"
			(at 0 1.6 0)
			(layer "F.Fab")
			(effects
				(font
					(size 0.7 0.7)
					(thickness 0.15)
				)
				(justify left bottom)
			)
		)
		(property "Datasheet" "https://fscdn.rohm.com/en/products/databook/datasheet/passive/resistor/chip_resistor/pmr-jpw-e.pdf"
			(at 0 0 0)
			(layer "F.Fab")
			(hide yes)
			(effects
				(font
					(size 1.27 1.27)
					(thickness 0.15)
				)
			)
		)
		(property "Description" "SMD Chip Resistor"
			(at 0 0 0)
			(layer "F.Fab")
			(hide yes)
			(effects
				(font
					(size 1.27 1.27)
					(thickness 0.15)
				)
			)
		)
		(property "MPN" "PMR03EZPJ000"
			(at 0 0 0)
			(unlocked yes)
			(layer "F.Fab")
			(hide yes)
			(effects
				(font
					(size 1 1)
					(thickness 0.15)
				)
			)
		)
		(property "Manufacturer" "ROHM Semiconductor"
			(at 0 0 0)
			(unlocked yes)
			(layer "F.Fab")
			(hide yes)
			(effects
				(font
					(size 1 1)
					(thickness 0.15)
				)
			)
		)
		(property "Val" "0R"
			(at 0 0 0)
			(unlocked yes)
			(layer "F.Fab")
			(hide yes)
			(effects
				(font
					(size 1 1)
					(thickness 0.15)
				)
			)
		)
		(property "Max. Curr." "22.4A"
			(at 0 0 0)
			(unlocked yes)
			(layer "F.Fab")
			(hide yes)
			(effects
				(font
					(size 1 1)
					(thickness 0.15)
				)
			)
		)
		(property "Author" "Antmicro"
			(at 0 0 0)
			(unlocked yes)
			(layer "F.Fab")
			(hide yes)
			(effects
				(font
					(size 1 1)
					(thickness 0.15)
				)
			)
		)
		(property "License" "Apache-2.0"
			(at 0 0 0)
			(unlocked yes)
			(layer "F.Fab")
			(hide yes)
			(effects
				(font
					(size 1 1)
					(thickness 0.15)
				)
			)
		)
		(property "Tolerance" "template_tolerance"
			(at 0 0 0)
			(unlocked yes)
			(layer "F.Fab")
			(hide yes)
			(effects
				(font
					(size 1 1)
					(thickness 0.15)
				)
			)
		)
		(sheetname "/X710 DCDC converters/")
		(sheetfile "DCDC_converters_X710.kicad_sch")
		(attr smd)
		(fp_line
			(start -0.15 -0.4)
			(end 0.15 -0.4)
			(stroke
				(width 0.15)
				(type solid)
			)
			(layer "F.SilkS")
		)
		(fp_line
			(start -0.15 0.4)
			(end 0.15 0.4)
			(stroke
				(width 0.15)
				(type solid)
			)
			(layer "F.SilkS")
		)
		(fp_rect
			(start -1.25 -0.65)
			(end 1.25 0.65)
			(stroke
				(width 0.05)
				(type solid)
			)
			(fill no)
			(layer "F.CrtYd")
		)
		(fp_rect
			(start -0.8 -0.4)
			(end 0.8 0.4)
			(stroke
				(width 0.15)
				(type solid)
			)
			(fill no)
			(layer "F.Fab")
		)
		(fp_text user "Author: Antmicro"
			(at -1.25 4.9 0)
			(layer "F.Fab")
			(effects
				(font
					(size 0.7 0.7)
					(thickness 0.15)
				)
				(justify left bottom)
			)
		)
		(fp_text user "License: Apache-2.0"
			(at -1.25 5.9 0)
			(layer "F.Fab")
			(effects
				(font
					(size 0.7 0.7)
					(thickness 0.15)
				)
				(justify left bottom)
			)
		)
		(fp_text user "${REFERENCE}"
			(at -1.25 3.898 0)
			(layer "F.Fab")
			(effects
				(font
					(size 0.7 0.7)
					(thickness 0.15)
				)
				(justify left bottom)
			)
		)
		(pad "1" smd roundrect
			(at -0.7 0)
			(size 0.8 1)
			(layers "F.Cu" "F.Mask" "F.Paste")
			(roundrect_rratio 0.2)
			(net 334 "/X710 DCDC converters/+3V3_OUT")
			(pintype "passive")
		)
		(pad "2" smd roundrect
			(at 0.7 0)
			(size 0.8 1)
			(layers "F.Cu" "F.Mask" "F.Paste")
			(roundrect_rratio 0.2)
			(net 7 "+3V3")
			(pintype "passive")
		)
	)
	(footprint "antmicro-footprints:SOIC-8_5.3x5.3x2mm_P1.27mm"
		(layer "F.Cu")
		(at 147.8 122.2 90)
		(descr "8-Pin SOIC 208-mil")
		(property "Reference" "U8"
			(at 3.3 4 90)
			(layer "F.SilkS")
			(effects
				(font
					(size 0.7 0.7)
					(thickness 0.15)
				)
				(justify left bottom)
			)
		)
		(property "Value" "MX25L8006EM2I-12G"
			(at 0 3.8 90)
			(layer "F.Fab")
			(effects
				(font
					(size 0.7 0.7)
					(thickness 0.15)
				)
				(justify left bottom)
			)
		)
		(property "Datasheet" "https://www.macronix.com/Lists/Datasheet/Attachments/8680/MX25L8006E,%203V,%208Mb,%20v1.6.pdf"
			(at 0 0 90)
			(layer "F.Fab")
			(hide yes)
			(effects
				(font
					(size 1.27 1.27)
					(thickness 0.15)
				)
			)
		)
		(property "Description" "FLASH - NOR Memory IC 8Mbit SPI 86 MHz 8-SOP"
			(at 0 0 90)
			(layer "F.Fab")
			(hide yes)
			(effects
				(font
					(size 1.27 1.27)
					(thickness 0.15)
				)
			)
		)
		(property "MPN" "MX25L8006EM2I-12G"
			(at 0 0 90)
			(unlocked yes)
			(layer "F.Fab")
			(hide yes)
			(effects
				(font
					(size 1 1)
					(thickness 0.15)
				)
			)
		)
		(property "Manufacturer" "Macronix"
			(at 0 0 90)
			(unlocked yes)
			(layer "F.Fab")
			(hide yes)
			(effects
				(font
					(size 1 1)
					(thickness 0.15)
				)
			)
		)
		(property "Author" "Antmicro"
			(at 0 0 90)
			(unlocked yes)
			(layer "F.Fab")
			(hide yes)
			(effects
				(font
					(size 1 1)
					(thickness 0.15)
				)
			)
		)
		(property "License" "Apache-2.0"
			(at 0 0 90)
			(unlocked yes)
			(layer "F.Fab")
			(hide yes)
			(effects
				(font
					(size 1 1)
					(thickness 0.15)
				)
			)
		)
		(sheetname "/TB flash memory/")
		(sheetfile "flash-memory.kicad_sch")
		(attr smd dnp)
		(fp_line
			(start -2.8 -2.641)
			(end -4.4 -2.641)
			(stroke
				(width 0.15)
				(type solid)
			)
			(layer "F.SilkS")
		)
		(fp_circle
			(center -4.85 -1.905)
			(end -4.8 -1.855)
			(stroke
				(width 0.15)
				(type solid)
			)
			(fill yes)
			(layer "F.SilkS")
		)
		(fp_rect
			(start 4.675 -3)
			(end -4.675 3)
			(stroke
				(width 0.05)
				(type solid)
			)
			(fill no)
			(layer "F.CrtYd")
		)
		(fp_line
			(start 2.64 -2.641)
			(end 2.64 2.64)
			(stroke
				(width 0.15)
				(type solid)
			)
			(layer "F.Fab")
		)
		(fp_line
			(start -2.641 -2.641)
			(end 2.64 -2.641)
			(stroke
				(width 0.15)
				(type solid)
			)
			(layer "F.Fab")
		)
		(fp_line
			(start -2.641 -1.371)
			(end -1.371 -2.641)
			(stroke
				(width 0.15)
				(type solid)
			)
			(layer "F.Fab")
		)
		(fp_line
			(start 2.64 2.64)
			(end -2.641 2.64)
			(stroke
				(width 0.15)
				(type solid)
			)
			(layer "F.Fab")
		)
		(fp_line
			(start -2.641 2.64)
			(end -2.641 -2.641)
			(stroke
				(width 0.15)
				(type solid)
			)
			(layer "F.Fab")
		)
		(fp_text user "${REFERENCE}"
			(at -4.675 4.938 90)
			(layer "F.Fab")
			(effects
				(font
					(size 0.7 0.7)
					(thickness 0.15)
				)
				(justify left bottom)
			)
		)
		(fp_text user "Author: Antmicro"
			(at -4.675 5.938 90)
			(layer "F.Fab")
			(effects
				(font
					(size 0.7 0.7)
					(thickness 0.15)
				)
				(justify left bottom)
			)
		)
		(fp_text user "License: Apache-2.0"
			(at -4.675 6.938 90)
			(layer "F.Fab")
			(effects
				(font
					(size 0.7 0.7)
					(thickness 0.15)
				)
				(justify left bottom)
			)
		)
		(pad "1" smd roundrect
			(at -3.601 -1.905 180)
			(size 0.65 1.65)
			(layers "F.Cu" "F.Mask" "F.Paste")
			(roundrect_rratio 0.25)
			(net 359 "/PD and TB DC-DC/TB_FLASH.~{CE}")
			(pinfunction "~{CS}")
			(pintype "input")
		)
		(pad "2" smd roundrect
			(at -3.601 -0.635 180)
			(size 0.65 1.65)
			(layers "F.Cu" "F.Mask" "F.Paste")
			(roundrect_rratio 0.25)
			(net 357 "/PD and TB DC-DC/TB_FLASH.MISO")
			(pinfunction "SO/IO1")
			(pintype "input")
		)
		(pad "3" smd roundrect
			(at -3.601 0.633 180)
			(size 0.65 1.65)
			(layers "F.Cu" "F.Mask" "F.Paste")
			(roundrect_rratio 0.25)
			(net 358 "/TB flash memory/FLASH_WP")
			(pinfunction "~{WP}")
			(pintype "input")
		)
		(pad "4" smd roundrect
			(at -3.601 1.904 180)
			(size 0.65 1.65)
			(layers "F.Cu" "F.Mask" "F.Paste")
			(roundrect_rratio 0.25)
			(net 23 "GND")
			(pinfunction "GND")
			(pintype "power_in")
		)
		(pad "5" smd roundrect
			(at 3.6 1.904 180)
			(size 0.65 1.65)
			(layers "F.Cu" "F.Mask" "F.Paste")
			(roundrect_rratio 0.25)
			(net 398 "/PD and TB DC-DC/TB_FLASH.MOSI")
			(pinfunction "SI/IO0")
			(pintype "input")
		)
		(pad "6" smd roundrect
			(at 3.6 0.633 180)
			(size 0.65 1.65)
			(layers "F.Cu" "F.Mask" "F.Paste")
			(roundrect_rratio 0.25)
			(net 397 "/PD and TB DC-DC/TB_FLASH.CLK")
			(pinfunction "SCLK")
			(pintype "input")
		)
		(pad "7" smd roundrect
			(at 3.6 -0.635 180)
			(size 0.65 1.65)
			(layers "F.Cu" "F.Mask" "F.Paste")
			(roundrect_rratio 0.25)
			(net 370 "/TB flash memory/FLASH_HOLD")
			(pinfunction "~{HOLD}")
			(pintype "input")
		)
		(pad "8" smd roundrect
			(at 3.6 -1.905 180)
			(size 0.65 1.65)
			(layers "F.Cu" "F.Mask" "F.Paste")
			(roundrect_rratio 0.25)
			(net 57 "+3V3_TB")
			(pinfunction "VCC")
			(pintype "power_in")
		)
	)
	(footprint "antmicro-footprints:C_0402_1005Metric"
		(layer "F.Cu")
		(at 133 131.2)
		(descr "Capacitor SMD 0402")
		(tags "capacitor SMD 0402")
		(property "Reference" "C82"
			(at -3.2 0.4 0)
			(layer "F.SilkS")
			(effects
				(font
					(size 0.7 0.7)
					(thickness 0.15)
				)
				(justify left bottom)
			)
		)
		(property "Value" "C_100n_0402"
			(at -1.022927 2.155213 0)
			(layer "F.Fab")
			(effects
				(font
					(size 0.7 0.7)
					(thickness 0.15)
				)
				(justify left bottom)
			)
		)
		(property "Datasheet" "https://www.murata.com/products/productdetail?partno=GRM155R61H104KE14%23"
			(at 0 0 0)
			(layer "F.Fab")
			(hide yes)
			(effects
				(font
					(size 1.27 1.27)
					(thickness 0.15)
				)
			)
		)
		(property "Description" "SMD Multilayer Ceramic Capacitor, 0.1 µF, 50 V, 0402 [1005 Metric], ± 10%, X5R, GRM Series"
			(at 0 0 0)
			(layer "F.Fab")
			(hide yes)
			(effects
				(font
					(size 1.27 1.27)
					(thickness 0.15)
				)
			)
		)
		(property "MPN" "GRM155R61H104KE14D"
			(at 0 0 0)
			(unlocked yes)
			(layer "F.Fab")
			(hide yes)
			(effects
				(font
					(size 1 1)
					(thickness 0.15)
				)
			)
		)
		(property "Manufacturer" "Murata"
			(at 0 0 0)
			(unlocked yes)
			(layer "F.Fab")
			(hide yes)
			(effects
				(font
					(size 1 1)
					(thickness 0.15)
				)
			)
		)
		(property "License" "Apache-2.0"
			(at 0 0 0)
			(unlocked yes)
			(layer "F.Fab")
			(hide yes)
			(effects
				(font
					(size 1 1)
					(thickness 0.15)
				)
			)
		)
		(property "Val" "100n"
			(at 0 0 0)
			(unlocked yes)
			(layer "F.Fab")
			(hide yes)
			(effects
				(font
					(size 1 1)
					(thickness 0.15)
				)
			)
		)
		(property "Voltage" "50V"
			(at 0 0 0)
			(unlocked yes)
			(layer "F.Fab")
			(hide yes)
			(effects
				(font
					(size 1 1)
					(thickness 0.15)
				)
			)
		)
		(property "Dielectric" "X5R"
			(at 0 0 0)
			(unlocked yes)
			(layer "F.Fab")
			(hide yes)
			(effects
				(font
					(size 1 1)
					(thickness 0.15)
				)
			)
		)
		(property "Author" "Antmicro"
			(at 0 0 0)
			(unlocked yes)
			(layer "F.Fab")
			(hide yes)
			(effects
				(font
					(size 1 1)
					(thickness 0.15)
				)
			)
		)
		(sheetname "/TB Controller - Power/")
		(sheetfile "tb-power.kicad_sch")
		(attr smd)
		(fp_rect
			(start -0.925 -0.47)
			(end 0.925 0.47)
			(stroke
				(width 0.05)
				(type default)
			)
			(fill no)
			(layer "F.CrtYd")
		)
		(fp_line
			(start -0.494 -0.25)
			(end 0.504 -0.25)
			(stroke
				(width 0.15)
				(type solid)
			)
			(layer "F.Fab")
		)
		(fp_line
			(start -0.494 0.248)
			(end -0.494 -0.25)
			(stroke
				(width 0.15)
				(type solid)
			)
			(layer "F.Fab")
		)
		(fp_line
			(start 0.504 -0.25)
			(end 0.504 0.248)
			(stroke
				(width 0.15)
				(type solid)
			)
			(layer "F.Fab")
		)
		(fp_line
			(start 0.504 0.248)
			(end -0.494 0.248)
			(stroke
				(width 0.15)
				(type solid)
			)
			(layer "F.Fab")
		)
		(fp_text user "License: Apache-2.0"
			(at -0.939 5.799 0)
			(layer "F.Fab")
			(effects
				(font
					(size 0.7 0.7)
					(thickness 0.15)
				)
				(justify left bottom)
			)
		)
		(fp_text user "Author: Antmicro"
			(at -0.939 3.399 0)
			(layer "F.Fab")
			(effects
				(font
					(size 0.7 0.7)
					(thickness 0.15)
				)
				(justify left bottom)
			)
		)
		(fp_text user "${REFERENCE}"
			(at -0.939 4.599 0)
			(layer "F.Fab")
			(effects
				(font
					(size 0.7 0.7)
					(thickness 0.15)
				)
				(justify left bottom)
			)
		)
		(pad "1" smd roundrect
			(at -0.48 0)
			(size 0.59 0.64)
			(layers "F.Cu" "F.Mask" "F.Paste")
			(roundrect_rratio 0.25)
			(net 23 "GND")
			(pintype "passive")
		)
		(pad "2" smd roundrect
			(at 0.48 0)
			(size 0.59 0.64)
			(layers "F.Cu" "F.Mask" "F.Paste")
			(roundrect_rratio 0.25)
			(net 57 "+3V3_TB")
			(pintype "passive")
		)
	)
	(footprint "antmicro-footprints:C_0603_1608Metric_EIA"
		(layer "F.Cu")
		(at 159.55 103.050001 -90)
		(descr "Capacitor SMD 0603, IPC-7351 Density Level A")
		(tags "Capacitor 0603")
		(property "Reference" "C147"
			(at 17.649996 -13.250002 270)
			(layer "F.SilkS")
			(effects
				(font
					(size 0.7 0.7)
					(thickness 0.15)
				)
			)
		)
		(property "Value" "C_22u_16V_0603"
			(at -1.42757 1.770288 270)
			(layer "F.Fab")
			(effects
				(font
					(size 0.7 0.7)
					(thickness 0.15)
				)
				(justify left bottom)
			)
		)
		(property "Datasheet" "https://product.samsungsem.com/mlcc/CL10A226MO7JZN.do"
			(at 0 0 270)
			(layer "F.Fab")
			(hide yes)
			(effects
				(font
					(size 1.27 1.27)
					(thickness 0.15)
				)
			)
		)
		(property "Description" "SMD Multilayer Ceramic Capacitor"
			(at 0 0 270)
			(layer "F.Fab")
			(hide yes)
			(effects
				(font
					(size 1.27 1.27)
					(thickness 0.15)
				)
			)
		)
		(property "MPN" "CL10A226MO7JZNC"
			(at 0 0 270)
			(unlocked yes)
			(layer "F.Fab")
			(hide yes)
			(effects
				(font
					(size 1 1)
					(thickness 0.15)
				)
			)
		)
		(property "Manufacturer" "Samsung Electro-Mechanics"
			(at 0 0 270)
			(unlocked yes)
			(layer "F.Fab")
			(hide yes)
			(effects
				(font
					(size 1 1)
					(thickness 0.15)
				)
			)
		)
		(property "License" "Apache-2.0"
			(at 0 0 270)
			(unlocked yes)
			(layer "F.Fab")
			(hide yes)
			(effects
				(font
					(size 1 1)
					(thickness 0.15)
				)
			)
		)
		(property "Author" "Antmicro"
			(at 0 0 270)
			(unlocked yes)
			(layer "F.Fab")
			(hide yes)
			(effects
				(font
					(size 1 1)
					(thickness 0.15)
				)
			)
		)
		(property "Val" "22u"
			(at 0 0 270)
			(unlocked yes)
			(layer "F.Fab")
			(hide yes)
			(effects
				(font
					(size 1 1)
					(thickness 0.15)
				)
			)
		)
		(property "Voltage" "16V"
			(at 0 0 270)
			(unlocked yes)
			(layer "F.Fab")
			(hide yes)
			(effects
				(font
					(size 1 1)
					(thickness 0.15)
				)
			)
		)
		(property "Dielectric" ""
			(at 0 0 270)
			(unlocked yes)
			(layer "F.Fab")
			(hide yes)
			(effects
				(font
					(size 1 1)
					(thickness 0.15)
				)
			)
		)
		(sheetname "/X710 DCDC converters/")
		(sheetfile "DCDC_converters_X710.kicad_sch")
		(attr smd)
		(fp_line
			(start -0.15 0.55)
			(end 0.15 0.55)
			(stroke
				(width 0.15)
				(type solid)
			)
			(layer "F.SilkS")
		)
		(fp_line
			(start -0.15 -0.55)
			(end 0.15 -0.55)
			(stroke
				(width 0.15)
				(type solid)
			)
			(layer "F.SilkS")
		)
		(fp_rect
			(start -1.25 -0.65)
			(end 1.25 0.65)
			(stroke
				(width 0.05)
				(type solid)
			)
			(fill no)
			(layer "F.CrtYd")
		)
		(fp_rect
			(start -0.8 -0.45)
			(end 0.8 0.45)
			(stroke
				(width 0.15)
				(type solid)
			)
			(fill no)
			(layer "F.Fab")
		)
		(fp_text user "Author: Antmicro"
			(at -1.682 4.894 270)
			(layer "F.Fab")
			(effects
				(font
					(size 0.7 0.7)
					(thickness 0.15)
				)
				(justify left bottom)
			)
		)
		(fp_text user "${REFERENCE}"
			(at -1.682 3.895 270)
			(layer "F.Fab")
			(effects
				(font
					(size 0.7 0.7)
					(thickness 0.15)
				)
				(justify left bottom)
			)
		)
		(fp_text user "License: Apache-2.0"
			(at -1.682 5.895 270)
			(layer "F.Fab")
			(effects
				(font
					(size 0.7 0.7)
					(thickness 0.15)
				)
				(justify left bottom)
			)
		)
		(pad "1" smd roundrect
			(at -0.7 0 270)
			(size 0.8 1.1)
			(layers "F.Cu" "F.Mask" "F.Paste")
			(roundrect_rratio 0.2)
			(net 23 "GND")
			(pintype "passive")
		)
		(pad "2" smd roundrect
			(at 0.7 0 270)
			(size 0.8 1.1)
			(layers "F.Cu" "F.Mask" "F.Paste")
			(roundrect_rratio 0.2)
			(net 339 "/X710 DCDC converters/+1V0_OUT")
			(pintype "passive")
		)
	)
	(footprint "antmicro-footprints:FB_0805_2012Metric"
		(layer "F.Cu")
		(at 166.665 63 -90)
		(descr "FERRITE BEAD 0805")
		(tags "FERRITE BEAD 0805")
		(property "Reference" "FB8"
			(at -1.1 -1.935 270)
			(layer "F.SilkS")
			(effects
				(font
					(size 0.7 0.7)
					(thickness 0.15)
				)
				(justify left bottom)
			)
		)
		(property "Value" "FB_330Z_1.5A_Murata-BLM21PG_0805"
			(at 0.001 1.801 270)
			(layer "F.Fab")
			(effects
				(font
					(size 0.7 0.7)
					(thickness 0.15)
				)
				(justify left bottom)
			)
		)
		(property "Datasheet" "https://www.murata.com/products/productdata/8796738977822/ENFA0005.pdf?1653276712000"
			(at 0 0 270)
			(layer "F.Fab")
			(hide yes)
			(effects
				(font
					(size 1.27 1.27)
					(thickness 0.15)
				)
			)
		)
		(property "Description" "Ferrite Bead, 0805 [2012 Metric], 330 ohm, 1.5 A, BLM21P, 0.07 ohm, ± 25%, DC power line"
			(at 0 0 270)
			(layer "F.Fab")
			(hide yes)
			(effects
				(font
					(size 1.27 1.27)
					(thickness 0.15)
				)
			)
		)
		(property "Val" "330Z/1.5A"
			(at 0 0 270)
			(unlocked yes)
			(layer "F.Fab")
			(hide yes)
			(effects
				(font
					(size 1 1)
					(thickness 0.15)
				)
			)
		)
		(property "MPN" "BLM21PG331SN1D"
			(at 0 0 270)
			(unlocked yes)
			(layer "F.Fab")
			(hide yes)
			(effects
				(font
					(size 1 1)
					(thickness 0.15)
				)
			)
		)
		(property "Manufacturer" "Murata"
			(at 0 0 270)
			(unlocked yes)
			(layer "F.Fab")
			(hide yes)
			(effects
				(font
					(size 1 1)
					(thickness 0.15)
				)
			)
		)
		(property "Current" ""
			(at 0 0 270)
			(unlocked yes)
			(layer "F.Fab")
			(hide yes)
			(effects
				(font
					(size 1 1)
					(thickness 0.15)
				)
			)
		)
		(property "Author" "Antmicro"
			(at 0 0 270)
			(unlocked yes)
			(layer "F.Fab")
			(hide yes)
			(effects
				(font
					(size 1 1)
					(thickness 0.15)
				)
			)
		)
		(property "License" "Apache-2.0"
			(at 0 0 270)
			(unlocked yes)
			(layer "F.Fab")
			(hide yes)
			(effects
				(font
					(size 1 1)
					(thickness 0.15)
				)
			)
		)
		(sheetname "/X710-AT2 10GbE/")
		(sheetfile "x710-at2-10gbe.kicad_sch")
		(attr smd)
		(fp_line
			(start -0.319 0.698)
			(end 0.281 0.698)
			(stroke
				(width 0.15)
				(type solid)
			)
			(layer "F.SilkS")
		)
		(fp_line
			(start -0.299 -0.698)
			(end 0.299 -0.698)
			(stroke
				(width 0.15)
				(type solid)
			)
			(layer "F.SilkS")
		)
		(fp_rect
			(start 1.95 -0.9)
			(end -1.95 0.9)
			(stroke
				(width 0.05)
				(type default)
			)
			(fill no)
			(layer "F.CrtYd")
		)
		(fp_line
			(start -0.948 0.681)
			(end 0.948 0.681)
			(stroke
				(width 0.15)
				(type solid)
			)
			(layer "F.Fab")
		)
		(fp_line
			(start -0.948 -0.676)
			(end -0.948 0.676)
			(stroke
				(width 0.15)
				(type solid)
			)
			(layer "F.Fab")
		)
		(fp_line
			(start 0.948 -0.676)
			(end 0.948 0.676)
			(stroke
				(width 0.15)
				(type solid)
			)
			(layer "F.Fab")
		)
		(fp_line
			(start -0.948 -0.681)
			(end 0.948 -0.681)
			(stroke
				(width 0.15)
				(type solid)
			)
			(layer "F.Fab")
		)
		(fp_text user "Author: Antmicro"
			(at -1.44 5.001 270)
			(layer "F.Fab")
			(effects
				(font
					(size 0.7 0.7)
					(thickness 0.15)
				)
				(justify left bottom)
			)
		)
		(fp_text user "${REFERENCE}"
			(at -1.44 3.801 270)
			(layer "F.Fab")
			(effects
				(font
					(size 0.7 0.7)
					(thickness 0.15)
				)
				(justify left bottom)
			)
		)
		(fp_text user "License: Apache-2.0"
			(at -1.44 6.201 270)
			(layer "F.Fab")
			(effects
				(font
					(size 0.7 0.7)
					(thickness 0.15)
				)
				(justify left bottom)
			)
		)
		(pad "1" smd roundrect
			(at -1.1 0 270)
			(size 1.2 1.3)
			(layers "F.Cu" "F.Mask" "F.Paste")
			(roundrect_rratio 0.25)
			(net 7 "+3V3")
			(pintype "passive")
		)
		(pad "2" smd roundrect
			(at 1.1 0 270)
			(size 1.2 1.3)
			(layers "F.Cu" "F.Mask" "F.Paste")
			(roundrect_rratio 0.25)
			(net 56 "/X710-AT2 10GbE/3V3_OSC")
			(pintype "passive")
		)
	)
	(footprint "antmicro-footprints:R_0402_1005Metric"
		(layer "F.Cu")
		(at 151.55 110.15 180)
		(descr "Resistor SMD 0402")
		(tags "resistor SMD 0402")
		(property "Reference" "R102"
			(at -14.149998 -17.25 180)
			(layer "F.SilkS")
			(effects
				(font
					(size 0.7 0.7)
					(thickness 0.15)
				)
			)
		)
		(property "Value" "R_63k4_0402"
			(at -1.011843 1.772047 180)
			(layer "F.Fab")
			(effects
				(font
					(size 0.7 0.7)
					(thickness 0.15)
				)
				(justify left bottom)
			)
		)
		(property "Datasheet" "https://industrial.panasonic.com/cdbs/www-data/pdf/RDM0000/AOA0000C307.pdf"
			(at 0 0 180)
			(layer "F.Fab")
			(hide yes)
			(effects
				(font
					(size 1.27 1.27)
					(thickness 0.15)
				)
			)
		)
		(property "Description" "SMD Chip Resistor, 63.4 kohm, ± 0.1%, 63 mW, 0402 [1005 Metric], Thin Film,  Precision"
			(at 0 0 180)
			(layer "F.Fab")
			(hide yes)
			(effects
				(font
					(size 1.27 1.27)
					(thickness 0.15)
				)
			)
		)
		(property "MPN" "ERA-2AEB6342X"
			(at 0 0 180)
			(unlocked yes)
			(layer "F.Fab")
			(hide yes)
			(effects
				(font
					(size 1 1)
					(thickness 0.15)
				)
			)
		)
		(property "Manufacturer" "Panasonic"
			(at 0 0 180)
			(unlocked yes)
			(layer "F.Fab")
			(hide yes)
			(effects
				(font
					(size 1 1)
					(thickness 0.15)
				)
			)
		)
		(property "License" "Apache-2.0"
			(at 0 0 180)
			(unlocked yes)
			(layer "F.Fab")
			(hide yes)
			(effects
				(font
					(size 1 1)
					(thickness 0.15)
				)
			)
		)
		(property "Author" "Antmicro"
			(at 0 0 180)
			(unlocked yes)
			(layer "F.Fab")
			(hide yes)
			(effects
				(font
					(size 1 1)
					(thickness 0.15)
				)
			)
		)
		(property "Val" "63k4"
			(at 0 0 180)
			(unlocked yes)
			(layer "F.Fab")
			(hide yes)
			(effects
				(font
					(size 1 1)
					(thickness 0.15)
				)
			)
		)
		(property "Tolerance" "0.1%"
			(at 0 0 180)
			(unlocked yes)
			(layer "F.Fab")
			(hide yes)
			(effects
				(font
					(size 1 1)
					(thickness 0.15)
				)
			)
		)
		(sheetname "/X710 DCDC converters/")
		(sheetfile "DCDC_converters_X710.kicad_sch")
		(attr smd)
		(fp_rect
			(start -0.925 -0.47)
			(end 0.925 0.47)
			(stroke
				(width 0.05)
				(type default)
			)
			(fill no)
			(layer "F.CrtYd")
		)
		(fp_rect
			(start -0.5 -0.25)
			(end 0.5 0.25)
			(stroke
				(width 0.15)
				(type solid)
			)
			(fill no)
			(layer "F.Fab")
		)
		(fp_text user "License: Apache-2.0"
			(at -0.95 5.169 180)
			(layer "F.Fab")
			(effects
				(font
					(size 0.7 0.7)
					(thickness 0.15)
				)
				(justify left bottom)
			)
		)
		(fp_text user "Author: Antmicro"
			(at -0.95 4.169 180)
			(layer "F.Fab")
			(effects
				(font
					(size 0.7 0.7)
					(thickness 0.15)
				)
				(justify left bottom)
			)
		)
		(fp_text user "${REFERENCE}"
			(at -0.95 3.168 180)
			(layer "F.Fab")
			(effects
				(font
					(size 0.7 0.7)
					(thickness 0.15)
				)
				(justify left bottom)
			)
		)
		(pad "1" smd roundrect
			(at -0.48 0 180)
			(size 0.59 0.64)
			(layers "F.Cu" "F.Mask" "F.Paste")
			(roundrect_rratio 0.25)
			(net 337 "/X710 DCDC converters/1V88_FB")
			(pintype "passive")
		)
		(pad "2" smd roundrect
			(at 0.48 0 180)
			(size 0.59 0.64)
			(layers "F.Cu" "F.Mask" "F.Paste")
			(roundrect_rratio 0.25)
			(net 338 "/X710 DCDC converters/+1V88_OUT")
			(pintype "passive")
		)
	)
	(footprint "antmicro-footprints:MP_Pad6mm_Drill3.2mm"
		(layer "F.Cu")
		(at 128 64 90)
		(property "Reference" "MP6"
			(at 2.8 -3.8 180)
			(layer "F.SilkS")
			(effects
				(font
					(size 0.7 0.7)
					(thickness 0.15)
				)
				(justify left bottom)
			)
		)
		(property "Value" "MP_Pad6mm_Drill3.2mm"
			(at 0 3.9 90)
			(layer "F.Fab")
			(effects
				(font
					(size 0.7 0.7)
					(thickness 0.15)
				)
				(justify left bottom)
			)
		)
		(property "Description" "Mechanical part"
			(at 0 0 90)
			(layer "F.Fab")
			(hide yes)
			(effects
				(font
					(size 1.27 1.27)
					(thickness 0.15)
				)
			)
		)
		(property "Author" "Antmicro"
			(at 0 0 90)
			(unlocked yes)
			(layer "F.Fab")
			(hide yes)
			(effects
				(font
					(size 1 1)
					(thickness 0.15)
				)
			)
		)
		(property "License" "Apache-2.0"
			(at 0 0 90)
			(unlocked yes)
			(layer "F.Fab")
			(hide yes)
			(effects
				(font
					(size 1 1)
					(thickness 0.15)
				)
			)
		)
		(sheetname "/")
		(sheetfile "thunderbolt-to-10gbe-adapter.kicad_sch")
		(attr exclude_from_pos_files exclude_from_bom)
		(fp_circle
			(center 0 0)
			(end 3.25 0)
			(stroke
				(width 0.05)
				(type default)
			)
			(fill no)
			(layer "F.CrtYd")
		)
		(fp_text user "License: Apache-2.0"
			(at -0.178 8.425 90)
			(layer "F.Fab")
			(effects
				(font
					(size 0.7 0.7)
					(thickness 0.15)
				)
				(justify left bottom)
			)
		)
		(fp_text user "${REFERENCE}"
			(at -0.178 6.025 90)
			(layer "F.Fab")
			(effects
				(font
					(size 0.7 0.7)
					(thickness 0.15)
				)
				(justify left bottom)
			)
		)
		(fp_text user "Author: Antmicro"
			(at -0.178 7.225 90)
			(layer "F.Fab")
			(effects
				(font
					(size 0.7 0.7)
					(thickness 0.15)
				)
				(justify left bottom)
			)
		)
		(pad "1" thru_hole circle
			(at 0 0 90)
			(size 6 6)
			(drill 3.2)
			(layers "*.Cu" "*.Mask")
			(remove_unused_layers no)
			(net 23 "GND")
			(pintype "passive")
		)
	)
	(footprint "antmicro-footprints:C_0603_1608Metric_EIA"
		(layer "F.Cu")
		(at 138.704999 99.775 -90)
		(descr "Capacitor SMD 0603, IPC-7351 Density Level A")
		(tags "Capacitor 0603")
		(property "Reference" "C261"
			(at -9.274999 -36.545001 270)
			(layer "F.SilkS")
			(effects
				(font
					(size 0.7 0.7)
					(thickness 0.15)
				)
			)
		)
		(property "Value" "C_22u_16V_0603"
			(at -1.42757 1.770288 270)
			(layer "F.Fab")
			(effects
				(font
					(size 0.7 0.7)
					(thickness 0.15)
				)
				(justify left bottom)
			)
		)
		(property "Datasheet" "https://product.samsungsem.com/mlcc/CL10A226MO7JZN.do"
			(at 0 0 270)
			(layer "F.Fab")
			(hide yes)
			(effects
				(font
					(size 1.27 1.27)
					(thickness 0.15)
				)
			)
		)
		(property "Description" "SMD Multilayer Ceramic Capacitor"
			(at 0 0 270)
			(layer "F.Fab")
			(hide yes)
			(effects
				(font
					(size 1.27 1.27)
					(thickness 0.15)
				)
			)
		)
		(property "MPN" "CL10A226MO7JZNC"
			(at 0 0 270)
			(unlocked yes)
			(layer "F.Fab")
			(hide yes)
			(effects
				(font
					(size 1 1)
					(thickness 0.15)
				)
			)
		)
		(property "Manufacturer" "Samsung Electro-Mechanics"
			(at 0 0 270)
			(unlocked yes)
			(layer "F.Fab")
			(hide yes)
			(effects
				(font
					(size 1 1)
					(thickness 0.15)
				)
			)
		)
		(property "License" "Apache-2.0"
			(at 0 0 270)
			(unlocked yes)
			(layer "F.Fab")
			(hide yes)
			(effects
				(font
					(size 1 1)
					(thickness 0.15)
				)
			)
		)
		(property "Author" "Antmicro"
			(at 0 0 270)
			(unlocked yes)
			(layer "F.Fab")
			(hide yes)
			(effects
				(font
					(size 1 1)
					(thickness 0.15)
				)
			)
		)
		(property "Val" "22u"
			(at 0 0 270)
			(unlocked yes)
			(layer "F.Fab")
			(hide yes)
			(effects
				(font
					(size 1 1)
					(thickness 0.15)
				)
			)
		)
		(property "Voltage" "16V"
			(at 0 0 270)
			(unlocked yes)
			(layer "F.Fab")
			(hide yes)
			(effects
				(font
					(size 1 1)
					(thickness 0.15)
				)
			)
		)
		(property "Dielectric" ""
			(at 0 0 270)
			(unlocked yes)
			(layer "F.Fab")
			(hide yes)
			(effects
				(font
					(size 1 1)
					(thickness 0.15)
				)
			)
		)
		(sheetname "/X710-AT2 power/")
		(sheetfile "x710-at2-power.kicad_sch")
		(attr smd)
		(fp_line
			(start -0.15 0.55)
			(end 0.15 0.55)
			(stroke
				(width 0.15)
				(type solid)
			)
			(layer "F.SilkS")
		)
		(fp_line
			(start -0.15 -0.55)
			(end 0.15 -0.55)
			(stroke
				(width 0.15)
				(type solid)
			)
			(layer "F.SilkS")
		)
		(fp_rect
			(start -1.25 -0.65)
			(end 1.25 0.65)
			(stroke
				(width 0.05)
				(type solid)
			)
			(fill no)
			(layer "F.CrtYd")
		)
		(fp_rect
			(start -0.8 -0.45)
			(end 0.8 0.45)
			(stroke
				(width 0.15)
				(type solid)
			)
			(fill no)
			(layer "F.Fab")
		)
		(fp_text user "Author: Antmicro"
			(at -1.682 4.894 270)
			(layer "F.Fab")
			(effects
				(font
					(size 0.7 0.7)
					(thickness 0.15)
				)
				(justify left bottom)
			)
		)
		(fp_text user "License: Apache-2.0"
			(at -1.682 5.895 270)
			(layer "F.Fab")
			(effects
				(font
					(size 0.7 0.7)
					(thickness 0.15)
				)
				(justify left bottom)
			)
		)
		(fp_text user "${REFERENCE}"
			(at -1.682 3.895 270)
			(layer "F.Fab")
			(effects
				(font
					(size 0.7 0.7)
					(thickness 0.15)
				)
				(justify left bottom)
			)
		)
		(pad "1" smd roundrect
			(at -0.7 0 270)
			(size 0.8 1.1)
			(layers "F.Cu" "F.Mask" "F.Paste")
			(roundrect_rratio 0.2)
			(net 23 "GND")
			(pintype "passive")
		)
		(pad "2" smd roundrect
			(at 0.7 0 270)
			(size 0.8 1.1)
			(layers "F.Cu" "F.Mask" "F.Paste")
			(roundrect_rratio 0.2)
			(net 9 "VCCD")
			(pintype "passive")
		)
	)
	(footprint "antmicro-footprints:C_0402_1005Metric"
		(layer "F.Cu")
		(at 120.4 128.6)
		(descr "Capacitor SMD 0402")
		(tags "capacitor SMD 0402")
		(property "Reference" "C43"
			(at -1 1.4 0)
			(layer "F.SilkS")
			(effects
				(font
					(size 0.7 0.7)
					(thickness 0.15)
				)
				(justify left bottom)
			)
		)
		(property "Value" "C_10p_0402"
			(at -1.022927 2.155213 0)
			(layer "F.Fab")
			(effects
				(font
					(size 0.7 0.7)
					(thickness 0.15)
				)
				(justify left bottom)
			)
		)
		(property "Datasheet" "https://www.murata.com/products/productdetail?partno=GCM1555C1H100GA16%23"
			(at 0 0 0)
			(layer "F.Fab")
			(hide yes)
			(effects
				(font
					(size 1.27 1.27)
					(thickness 0.15)
				)
			)
		)
		(property "Description" "SMD Multilayer Ceramic Capacitor, 10 pF, 50 V, 0402 [1005 Metric], ± 2%, C0G / NP0, GCM"
			(at 0 0 0)
			(layer "F.Fab")
			(hide yes)
			(effects
				(font
					(size 1.27 1.27)
					(thickness 0.15)
				)
			)
		)
		(property "MPN" "GCM1555C1H100GA16D"
			(at 0 0 0)
			(unlocked yes)
			(layer "F.Fab")
			(hide yes)
			(effects
				(font
					(size 1 1)
					(thickness 0.15)
				)
			)
		)
		(property "Manufacturer" "Murata"
			(at 0 0 0)
			(unlocked yes)
			(layer "F.Fab")
			(hide yes)
			(effects
				(font
					(size 1 1)
					(thickness 0.15)
				)
			)
		)
		(property "License" "Apache-2.0"
			(at 0 0 0)
			(unlocked yes)
			(layer "F.Fab")
			(hide yes)
			(effects
				(font
					(size 1 1)
					(thickness 0.15)
				)
			)
		)
		(property "Val" "10p"
			(at 0 0 0)
			(unlocked yes)
			(layer "F.Fab")
			(hide yes)
			(effects
				(font
					(size 1 1)
					(thickness 0.15)
				)
			)
		)
		(property "Voltage" "50V"
			(at 0 0 0)
			(unlocked yes)
			(layer "F.Fab")
			(hide yes)
			(effects
				(font
					(size 1 1)
					(thickness 0.15)
				)
			)
		)
		(property "Dielectric" "C0G"
			(at 0 0 0)
			(unlocked yes)
			(layer "F.Fab")
			(hide yes)
			(effects
				(font
					(size 1 1)
					(thickness 0.15)
				)
			)
		)
		(property "Author" "Antmicro"
			(at 0 0 0)
			(unlocked yes)
			(layer "F.Fab")
			(hide yes)
			(effects
				(font
					(size 1 1)
					(thickness 0.15)
				)
			)
		)
		(sheetname "/TB Controller/")
		(sheetfile "tb.kicad_sch")
		(attr smd)
		(fp_rect
			(start -0.925 -0.47)
			(end 0.925 0.47)
			(stroke
				(width 0.05)
				(type default)
			)
			(fill no)
			(layer "F.CrtYd")
		)
		(fp_line
			(start -0.494 -0.25)
			(end 0.504 -0.25)
			(stroke
				(width 0.15)
				(type solid)
			)
			(layer "F.Fab")
		)
		(fp_line
			(start -0.494 0.248)
			(end -0.494 -0.25)
			(stroke
				(width 0.15)
				(type solid)
			)
			(layer "F.Fab")
		)
		(fp_line
			(start 0.504 -0.25)
			(end 0.504 0.248)
			(stroke
				(width 0.15)
				(type solid)
			)
			(layer "F.Fab")
		)
		(fp_line
			(start 0.504 0.248)
			(end -0.494 0.248)
			(stroke
				(width 0.15)
				(type solid)
			)
			(layer "F.Fab")
		)
		(fp_text user "License: Apache-2.0"
			(at -0.939 5.799 0)
			(layer "F.Fab")
			(effects
				(font
					(size 0.7 0.7)
					(thickness 0.15)
				)
				(justify left bottom)
			)
		)
		(fp_text user "Author: Antmicro"
			(at -0.939 3.399 0)
			(layer "F.Fab")
			(effects
				(font
					(size 0.7 0.7)
					(thickness 0.15)
				)
				(justify left bottom)
			)
		)
		(fp_text user "${REFERENCE}"
			(at -0.939 4.599 0)
			(layer "F.Fab")
			(effects
				(font
					(size 0.7 0.7)
					(thickness 0.15)
				)
				(justify left bottom)
			)
		)
		(pad "1" smd roundrect
			(at -0.48 0)
			(size 0.59 0.64)
			(layers "F.Cu" "F.Mask" "F.Paste")
			(roundrect_rratio 0.25)
			(net 331 "/TB Controller/XTAL_25_OUT")
			(pintype "passive")
		)
		(pad "2" smd roundrect
			(at 0.48 0)
			(size 0.59 0.64)
			(layers "F.Cu" "F.Mask" "F.Paste")
			(roundrect_rratio 0.25)
			(net 23 "GND")
			(pintype "passive")
		)
	)
	(footprint "antmicro-footprints:C_0402_1005Metric"
		(layer "F.Cu")
		(at 156.500002 109.850002 90)
		(descr "Capacitor SMD 0402")
		(tags "capacitor SMD 0402")
		(property "Reference" "C126"
			(at -16.799996 13.650003 90)
			(layer "F.SilkS")
			(effects
				(font
					(size 0.7 0.7)
					(thickness 0.15)
				)
			)
		)
		(property "Value" "C_100n_0402"
			(at -1.022927 2.155213 90)
			(layer "F.Fab")
			(effects
				(font
					(size 0.7 0.7)
					(thickness 0.15)
				)
				(justify left bottom)
			)
		)
		(property "Datasheet" "https://www.murata.com/products/productdetail?partno=GRM155R61H104KE14%23"
			(at 0 0 90)
			(layer "F.Fab")
			(hide yes)
			(effects
				(font
					(size 1.27 1.27)
					(thickness 0.15)
				)
			)
		)
		(property "Description" "SMD Multilayer Ceramic Capacitor, 0.1 µF, 50 V, 0402 [1005 Metric], ± 10%, X5R, GRM Series"
			(at 0 0 90)
			(layer "F.Fab")
			(hide yes)
			(effects
				(font
					(size 1.27 1.27)
					(thickness 0.15)
				)
			)
		)
		(property "MPN" "GRM155R61H104KE14D"
			(at 0 0 90)
			(unlocked yes)
			(layer "F.Fab")
			(hide yes)
			(effects
				(font
					(size 1 1)
					(thickness 0.15)
				)
			)
		)
		(property "Manufacturer" "Murata"
			(at 0 0 90)
			(unlocked yes)
			(layer "F.Fab")
			(hide yes)
			(effects
				(font
					(size 1 1)
					(thickness 0.15)
				)
			)
		)
		(property "License" "Apache-2.0"
			(at 0 0 90)
			(unlocked yes)
			(layer "F.Fab")
			(hide yes)
			(effects
				(font
					(size 1 1)
					(thickness 0.15)
				)
			)
		)
		(property "Author" "Antmicro"
			(at 0 0 90)
			(unlocked yes)
			(layer "F.Fab")
			(hide yes)
			(effects
				(font
					(size 1 1)
					(thickness 0.15)
				)
			)
		)
		(property "Val" "100n"
			(at 0 0 90)
			(unlocked yes)
			(layer "F.Fab")
			(hide yes)
			(effects
				(font
					(size 1 1)
					(thickness 0.15)
				)
			)
		)
		(property "Voltage" "50V"
			(at 0 0 90)
			(unlocked yes)
			(layer "F.Fab")
			(hide yes)
			(effects
				(font
					(size 1 1)
					(thickness 0.15)
				)
			)
		)
		(property "Dielectric" "X5R"
			(at 0 0 90)
			(unlocked yes)
			(layer "F.Fab")
			(hide yes)
			(effects
				(font
					(size 1 1)
					(thickness 0.15)
				)
			)
		)
		(sheetname "/X710 DCDC converters/")
		(sheetfile "DCDC_converters_X710.kicad_sch")
		(attr smd)
		(fp_rect
			(start -0.925 -0.47)
			(end 0.925 0.47)
			(stroke
				(width 0.05)
				(type default)
			)
			(fill no)
			(layer "F.CrtYd")
		)
		(fp_line
			(start 0.504 -0.25)
			(end 0.504 0.248)
			(stroke
				(width 0.15)
				(type solid)
			)
			(layer "F.Fab")
		)
		(fp_line
			(start -0.494 -0.25)
			(end 0.504 -0.25)
			(stroke
				(width 0.15)
				(type solid)
			)
			(layer "F.Fab")
		)
		(fp_line
			(start 0.504 0.248)
			(end -0.494 0.248)
			(stroke
				(width 0.15)
				(type solid)
			)
			(layer "F.Fab")
		)
		(fp_line
			(start -0.494 0.248)
			(end -0.494 -0.25)
			(stroke
				(width 0.15)
				(type solid)
			)
			(layer "F.Fab")
		)
		(fp_text user "License: Apache-2.0"
			(at -0.939 5.799 90)
			(layer "F.Fab")
			(effects
				(font
					(size 0.7 0.7)
					(thickness 0.15)
				)
				(justify left bottom)
			)
		)
		(fp_text user "Author: Antmicro"
			(at -0.939 3.399 90)
			(layer "F.Fab")
			(effects
				(font
					(size 0.7 0.7)
					(thickness 0.15)
				)
				(justify left bottom)
			)
		)
		(fp_text user "${REFERENCE}"
			(at -0.939 4.599 90)
			(layer "F.Fab")
			(effects
				(font
					(size 0.7 0.7)
					(thickness 0.15)
				)
				(justify left bottom)
			)
		)
		(pad "1" smd roundrect
			(at -0.48 0 90)
			(size 0.59 0.64)
			(layers "F.Cu" "F.Mask" "F.Paste")
			(roundrect_rratio 0.25)
			(net 302 "/X710 DCDC converters/1V88_BST")
			(pintype "passive")
		)
		(pad "2" smd roundrect
			(at 0.48 0 90)
			(size 0.59 0.64)
			(layers "F.Cu" "F.Mask" "F.Paste")
			(roundrect_rratio 0.25)
			(net 241 "/X710 DCDC converters/1V88_SW")
			(pintype "passive")
		)
	)
	(footprint "antmicro-footprints:C_0603_1608Metric"
		(layer "F.Cu")
		(at 151.655 66.024999 90)
		(descr "Capacitor SMD 0603")
		(tags "capacitor 0603")
		(property "Reference" "C210"
			(at 12.424999 20.045 90)
			(layer "F.SilkS")
			(effects
				(font
					(size 0.7 0.7)
					(thickness 0.15)
				)
			)
		)
		(property "Value" "C_10u_10V_X7R_0603"
			(at -1.42757 1.770288 90)
			(layer "F.Fab")
			(effects
				(font
					(size 0.7 0.7)
					(thickness 0.15)
				)
				(justify left bottom)
			)
		)
		(property "Datasheet" "https://www.murata.com/products/productdetail?partno=GRM188Z71A106KA73%23"
			(at 0 0 90)
			(layer "F.Fab")
			(hide yes)
			(effects
				(font
					(size 1.27 1.27)
					(thickness 0.15)
				)
			)
		)
		(property "Description" "SMD Multilayer Ceramic Capacitor,  10µF, 10V, 0603, ±10%, X7R"
			(at 0 0 90)
			(layer "F.Fab")
			(hide yes)
			(effects
				(font
					(size 1.27 1.27)
					(thickness 0.15)
				)
			)
		)
		(property "MPN" "GRM188Z71A106KA73D"
			(at 0 0 90)
			(unlocked yes)
			(layer "F.Fab")
			(hide yes)
			(effects
				(font
					(size 1 1)
					(thickness 0.15)
				)
			)
		)
		(property "Val" "10u"
			(at 0 0 90)
			(unlocked yes)
			(layer "F.Fab")
			(hide yes)
			(effects
				(font
					(size 1 1)
					(thickness 0.15)
				)
			)
		)
		(property "Voltage" "10V"
			(at 0 0 90)
			(unlocked yes)
			(layer "F.Fab")
			(hide yes)
			(effects
				(font
					(size 1 1)
					(thickness 0.15)
				)
			)
		)
		(property "Dielectric" "X7R"
			(at 0 0 90)
			(unlocked yes)
			(layer "F.Fab")
			(hide yes)
			(effects
				(font
					(size 1 1)
					(thickness 0.15)
				)
			)
		)
		(property "Manufacturer" "Murata"
			(at 0 0 90)
			(unlocked yes)
			(layer "F.Fab")
			(hide yes)
			(effects
				(font
					(size 1 1)
					(thickness 0.15)
				)
			)
		)
		(property "License" "Apache-2.0"
			(at 0 0 90)
			(unlocked yes)
			(layer "F.Fab")
			(hide yes)
			(effects
				(font
					(size 1 1)
					(thickness 0.15)
				)
			)
		)
		(property "Author" "Antmicro"
			(at 0 0 90)
			(unlocked yes)
			(layer "F.Fab")
			(hide yes)
			(effects
				(font
					(size 1 1)
					(thickness 0.15)
				)
			)
		)
		(sheetname "/X710-AT2 power/")
		(sheetfile "x710-at2-power.kicad_sch")
		(attr smd)
		(fp_line
			(start -0.15 -0.4)
			(end 0.15 -0.4)
			(stroke
				(width 0.15)
				(type solid)
			)
			(layer "F.SilkS")
		)
		(fp_line
			(start -0.15 0.4)
			(end 0.15 0.4)
			(stroke
				(width 0.15)
				(type solid)
			)
			(layer "F.SilkS")
		)
		(fp_rect
			(start -1.25 -0.65)
			(end 1.25 0.65)
			(stroke
				(width 0.05)
				(type solid)
			)
			(fill no)
			(layer "F.CrtYd")
		)
		(fp_rect
			(start -0.8 -0.4)
			(end 0.8 0.4)
			(stroke
				(width 0.15)
				(type solid)
			)
			(fill no)
			(layer "F.Fab")
		)
		(fp_text user "${REFERENCE}"
			(at -1.682 3.895 90)
			(layer "F.Fab")
			(effects
				(font
					(size 0.7 0.7)
					(thickness 0.15)
				)
				(justify left bottom)
			)
		)
		(fp_text user "Author: Antmicro"
			(at -1.682 4.894 90)
			(layer "F.Fab")
			(effects
				(font
					(size 0.7 0.7)
					(thickness 0.15)
				)
				(justify left bottom)
			)
		)
		(fp_text user "License: Apache-2.0"
			(at -1.682 5.895 90)
			(layer "F.Fab")
			(effects
				(font
					(size 0.7 0.7)
					(thickness 0.15)
				)
				(justify left bottom)
			)
		)
		(pad "1" smd roundrect
			(at -0.7 0 90)
			(size 0.8 1)
			(layers "F.Cu" "F.Mask" "F.Paste")
			(roundrect_rratio 0.2)
			(net 23 "GND")
			(pintype "passive")
		)
		(pad "2" smd roundrect
			(at 0.7 0 90)
			(size 0.8 1)
			(layers "F.Cu" "F.Mask" "F.Paste")
			(roundrect_rratio 0.2)
			(net 1 "VCCA")
			(pintype "passive")
		)
	)
	(footprint "antmicro-footprints:C_0603_1608Metric_EIA"
		(layer "F.Cu")
		(at 139.500001 114.349999)
		(descr "Capacitor SMD 0603, IPC-7351 Density Level A")
		(tags "Capacitor 0603")
		(property "Reference" "C105"
			(at 16 16.600001 0)
			(layer "F.SilkS")
			(effects
				(font
					(size 0.7 0.7)
					(thickness 0.15)
				)
			)
		)
		(property "Value" "C_22u_16V_0603"
			(at -1.42757 1.770288 0)
			(layer "F.Fab")
			(effects
				(font
					(size 0.7 0.7)
					(thickness 0.15)
				)
				(justify left bottom)
			)
		)
		(property "Datasheet" "https://product.samsungsem.com/mlcc/CL10A226MO7JZN.do"
			(at 0 0 0)
			(layer "F.Fab")
			(hide yes)
			(effects
				(font
					(size 1.27 1.27)
					(thickness 0.15)
				)
			)
		)
		(property "Description" "SMD Multilayer Ceramic Capacitor"
			(at 0 0 0)
			(layer "F.Fab")
			(hide yes)
			(effects
				(font
					(size 1.27 1.27)
					(thickness 0.15)
				)
			)
		)
		(property "MPN" "CL10A226MO7JZNC"
			(at 0 0 0)
			(unlocked yes)
			(layer "F.Fab")
			(hide yes)
			(effects
				(font
					(size 1 1)
					(thickness 0.15)
				)
			)
		)
		(property "Manufacturer" "Samsung Electro-Mechanics"
			(at 0 0 0)
			(unlocked yes)
			(layer "F.Fab")
			(hide yes)
			(effects
				(font
					(size 1 1)
					(thickness 0.15)
				)
			)
		)
		(property "License" "Apache-2.0"
			(at 0 0 0)
			(unlocked yes)
			(layer "F.Fab")
			(hide yes)
			(effects
				(font
					(size 1 1)
					(thickness 0.15)
				)
			)
		)
		(property "Author" "Antmicro"
			(at 0 0 0)
			(unlocked yes)
			(layer "F.Fab")
			(hide yes)
			(effects
				(font
					(size 1 1)
					(thickness 0.15)
				)
			)
		)
		(property "Val" "22u"
			(at 0 0 0)
			(unlocked yes)
			(layer "F.Fab")
			(hide yes)
			(effects
				(font
					(size 1 1)
					(thickness 0.15)
				)
			)
		)
		(property "Voltage" "16V"
			(at 0 0 0)
			(unlocked yes)
			(layer "F.Fab")
			(hide yes)
			(effects
				(font
					(size 1 1)
					(thickness 0.15)
				)
			)
		)
		(property "Dielectric" ""
			(at 0 0 0)
			(unlocked yes)
			(layer "F.Fab")
			(hide yes)
			(effects
				(font
					(size 1 1)
					(thickness 0.15)
				)
			)
		)
		(sheetname "/X710 DCDC converters/")
		(sheetfile "DCDC_converters_X710.kicad_sch")
		(attr smd)
		(fp_line
			(start -0.15 -0.55)
			(end 0.15 -0.55)
			(stroke
				(width 0.15)
				(type solid)
			)
			(layer "F.SilkS")
		)
		(fp_line
			(start -0.15 0.55)
			(end 0.15 0.55)
			(stroke
				(width 0.15)
				(type solid)
			)
			(layer "F.SilkS")
		)
		(fp_rect
			(start -1.25 -0.65)
			(end 1.25 0.65)
			(stroke
				(width 0.05)
				(type solid)
			)
			(fill no)
			(layer "F.CrtYd")
		)
		(fp_rect
			(start -0.8 -0.45)
			(end 0.8 0.45)
			(stroke
				(width 0.15)
				(type solid)
			)
			(fill no)
			(layer "F.Fab")
		)
		(fp_text user "${REFERENCE}"
			(at -1.682 3.895 0)
			(layer "F.Fab")
			(effects
				(font
					(size 0.7 0.7)
					(thickness 0.15)
				)
				(justify left bottom)
			)
		)
		(fp_text user "Author: Antmicro"
			(at -1.682 4.894 0)
			(layer "F.Fab")
			(effects
				(font
					(size 0.7 0.7)
					(thickness 0.15)
				)
				(justify left bottom)
			)
		)
		(fp_text user "License: Apache-2.0"
			(at -1.682 5.895 0)
			(layer "F.Fab")
			(effects
				(font
					(size 0.7 0.7)
					(thickness 0.15)
				)
				(justify left bottom)
			)
		)
		(pad "1" smd roundrect
			(at -0.7 0)
			(size 0.8 1.1)
			(layers "F.Cu" "F.Mask" "F.Paste")
			(roundrect_rratio 0.2)
			(net 23 "GND")
			(pintype "passive")
		)
		(pad "2" smd roundrect
			(at 0.7 0)
			(size 0.8 1.1)
			(layers "F.Cu" "F.Mask" "F.Paste")
			(roundrect_rratio 0.2)
			(net 40 "+5V")
			(pintype "passive")
		)
	)
	(footprint "antmicro-footprints:C_0603_1608Metric_EIA"
		(layer "F.Cu")
		(at 131.955001 89.274999 -90)
		(descr "Capacitor SMD 0603, IPC-7351 Density Level A")
		(tags "Capacitor 0603")
		(property "Reference" "C262"
			(at 4.225001 15.705001 270)
			(layer "F.SilkS")
			(effects
				(font
					(size 0.7 0.7)
					(thickness 0.15)
				)
				(justify left bottom)
			)
		)
		(property "Value" "C_22u_16V_0603"
			(at -1.42757 1.770288 270)
			(layer "F.Fab")
			(effects
				(font
					(size 0.7 0.7)
					(thickness 0.15)
				)
				(justify left bottom)
			)
		)
		(property "Datasheet" "https://product.samsungsem.com/mlcc/CL10A226MO7JZN.do"
			(at 0 0 270)
			(layer "F.Fab")
			(hide yes)
			(effects
				(font
					(size 1.27 1.27)
					(thickness 0.15)
				)
			)
		)
		(property "Description" "SMD Multilayer Ceramic Capacitor"
			(at 0 0 270)
			(layer "F.Fab")
			(hide yes)
			(effects
				(font
					(size 1.27 1.27)
					(thickness 0.15)
				)
			)
		)
		(property "MPN" "CL10A226MO7JZNC"
			(at 0 0 270)
			(unlocked yes)
			(layer "F.Fab")
			(hide yes)
			(effects
				(font
					(size 1 1)
					(thickness 0.15)
				)
			)
		)
		(property "Manufacturer" "Samsung Electro-Mechanics"
			(at 0 0 270)
			(unlocked yes)
			(layer "F.Fab")
			(hide yes)
			(effects
				(font
					(size 1 1)
					(thickness 0.15)
				)
			)
		)
		(property "License" "Apache-2.0"
			(at 0 0 270)
			(unlocked yes)
			(layer "F.Fab")
			(hide yes)
			(effects
				(font
					(size 1 1)
					(thickness 0.15)
				)
			)
		)
		(property "Author" "Antmicro"
			(at 0 0 270)
			(unlocked yes)
			(layer "F.Fab")
			(hide yes)
			(effects
				(font
					(size 1 1)
					(thickness 0.15)
				)
			)
		)
		(property "Val" "22u"
			(at 0 0 270)
			(unlocked yes)
			(layer "F.Fab")
			(hide yes)
			(effects
				(font
					(size 1 1)
					(thickness 0.15)
				)
			)
		)
		(property "Voltage" "16V"
			(at 0 0 270)
			(unlocked yes)
			(layer "F.Fab")
			(hide yes)
			(effects
				(font
					(size 1 1)
					(thickness 0.15)
				)
			)
		)
		(property "Dielectric" ""
			(at 0 0 270)
			(unlocked yes)
			(layer "F.Fab")
			(hide yes)
			(effects
				(font
					(size 1 1)
					(thickness 0.15)
				)
			)
		)
		(sheetname "/X710-AT2 power/")
		(sheetfile "x710-at2-power.kicad_sch")
		(attr smd)
		(fp_line
			(start -0.15 0.55)
			(end 0.15 0.55)
			(stroke
				(width 0.15)
				(type solid)
			)
			(layer "F.SilkS")
		)
		(fp_line
			(start -0.15 -0.55)
			(end 0.15 -0.55)
			(stroke
				(width 0.15)
				(type solid)
			)
			(layer "F.SilkS")
		)
		(fp_rect
			(start -1.25 -0.65)
			(end 1.25 0.65)
			(stroke
				(width 0.05)
				(type solid)
			)
			(fill no)
			(layer "F.CrtYd")
		)
		(fp_rect
			(start -0.8 -0.45)
			(end 0.8 0.45)
			(stroke
				(width 0.15)
				(type solid)
			)
			(fill no)
			(layer "F.Fab")
		)
		(fp_text user "Author: Antmicro"
			(at -1.682 4.894 270)
			(layer "F.Fab")
			(effects
				(font
					(size 0.7 0.7)
					(thickness 0.15)
				)
				(justify left bottom)
			)
		)
		(fp_text user "License: Apache-2.0"
			(at -1.682 5.895 270)
			(layer "F.Fab")
			(effects
				(font
					(size 0.7 0.7)
					(thickness 0.15)
				)
				(justify left bottom)
			)
		)
		(fp_text user "${REFERENCE}"
			(at -1.682 3.895 270)
			(layer "F.Fab")
			(effects
				(font
					(size 0.7 0.7)
					(thickness 0.15)
				)
				(justify left bottom)
			)
		)
		(pad "1" smd roundrect
			(at -0.7 0 270)
			(size 0.8 1.1)
			(layers "F.Cu" "F.Mask" "F.Paste")
			(roundrect_rratio 0.2)
			(net 23 "GND")
			(pintype "passive")
		)
		(pad "2" smd roundrect
			(at 0.7 0 270)
			(size 0.8 1.1)
			(layers "F.Cu" "F.Mask" "F.Paste")
			(roundrect_rratio 0.2)
			(net 7 "+3V3")
			(pintype "passive")
		)
	)
	(footprint "antmicro-footprints:R_0402_1005Metric"
		(layer "F.Cu")
		(at 164 78.4 180)
		(descr "Resistor SMD 0402")
		(tags "resistor SMD 0402")
		(property "Reference" "R208"
			(at 1 -6.4 180)
			(layer "F.SilkS")
			(effects
				(font
					(size 0.7 0.7)
					(thickness 0.15)
				)
				(justify left bottom)
			)
		)
		(property "Value" "R_0R_0402"
			(at -1.011843 1.772047 180)
			(layer "F.Fab")
			(effects
				(font
					(size 0.7 0.7)
					(thickness 0.15)
				)
				(justify left bottom)
			)
		)
		(property "Datasheet" "https://industrial.panasonic.com/cdbs/www-data/pdf/RDA0000/AOA0000C301.pdf"
			(at 0 0 180)
			(layer "F.Fab")
			(hide yes)
			(effects
				(font
					(size 1.27 1.27)
					(thickness 0.15)
				)
			)
		)
		(property "Description" "SMD Chip Resistor, Jumper, 0 ohm, 100 mW, 0402 [1005 Metric], Thick Film, General Purpose"
			(at 0 0 180)
			(layer "F.Fab")
			(hide yes)
			(effects
				(font
					(size 1.27 1.27)
					(thickness 0.15)
				)
			)
		)
		(property "MPN" "ERJ2GE0R00X"
			(at 0 0 180)
			(unlocked yes)
			(layer "F.Fab")
			(hide yes)
			(effects
				(font
					(size 1 1)
					(thickness 0.15)
				)
			)
		)
		(property "Manufacturer" "Panasonic"
			(at 0 0 180)
			(unlocked yes)
			(layer "F.Fab")
			(hide yes)
			(effects
				(font
					(size 1 1)
					(thickness 0.15)
				)
			)
		)
		(property "License" "Apache-2.0"
			(at 0 0 180)
			(unlocked yes)
			(layer "F.Fab")
			(hide yes)
			(effects
				(font
					(size 1 1)
					(thickness 0.15)
				)
			)
		)
		(property "Author" "Antmicro"
			(at 0 0 180)
			(unlocked yes)
			(layer "F.Fab")
			(hide yes)
			(effects
				(font
					(size 1 1)
					(thickness 0.15)
				)
			)
		)
		(property "Val" "0R"
			(at 0 0 180)
			(unlocked yes)
			(layer "F.Fab")
			(hide yes)
			(effects
				(font
					(size 1 1)
					(thickness 0.15)
				)
			)
		)
		(property "Tolerance" "~"
			(at 0 0 180)
			(unlocked yes)
			(layer "F.Fab")
			(hide yes)
			(effects
				(font
					(size 1 1)
					(thickness 0.15)
				)
			)
		)
		(property "Current" "1A"
			(at 0 0 180)
			(unlocked yes)
			(layer "F.Fab")
			(hide yes)
			(effects
				(font
					(size 1 1)
					(thickness 0.15)
				)
			)
		)
		(sheetname "/X710-AT2 10GbE/")
		(sheetfile "x710-at2-10gbe.kicad_sch")
		(attr smd)
		(fp_rect
			(start -0.925 -0.47)
			(end 0.925 0.47)
			(stroke
				(width 0.05)
				(type default)
			)
			(fill no)
			(layer "F.CrtYd")
		)
		(fp_rect
			(start -0.5 -0.25)
			(end 0.5 0.25)
			(stroke
				(width 0.15)
				(type solid)
			)
			(fill no)
			(layer "F.Fab")
		)
		(fp_text user "${REFERENCE}"
			(at -0.95 3.168 180)
			(layer "F.Fab")
			(effects
				(font
					(size 0.7 0.7)
					(thickness 0.15)
				)
				(justify left bottom)
			)
		)
		(fp_text user "License: Apache-2.0"
			(at -0.95 5.169 180)
			(layer "F.Fab")
			(effects
				(font
					(size 0.7 0.7)
					(thickness 0.15)
				)
				(justify left bottom)
			)
		)
		(fp_text user "Author: Antmicro"
			(at -0.95 4.169 180)
			(layer "F.Fab")
			(effects
				(font
					(size 0.7 0.7)
					(thickness 0.15)
				)
				(justify left bottom)
			)
		)
		(pad "1" smd roundrect
			(at -0.48 0 180)
			(size 0.59 0.64)
			(layers "F.Cu" "F.Mask" "F.Paste")
			(roundrect_rratio 0.25)
			(net 23 "GND")
			(pintype "passive")
		)
		(pad "2" smd roundrect
			(at 0.48 0 180)
			(size 0.59 0.64)
			(layers "F.Cu" "F.Mask" "F.Paste")
			(roundrect_rratio 0.25)
			(net 131 "/X710-AT2 10GbE/TPIN_5")
			(pintype "passive")
		)
	)
	(footprint "antmicro-footprints:R_0402_1005Metric"
		(layer "F.Cu")
		(at 117 71.9 180)
		(descr "Resistor SMD 0402")
		(tags "resistor SMD 0402")
		(property "Reference" "R216"
			(at -3.6 10.5 180)
			(layer "F.SilkS")
			(effects
				(font
					(size 0.7 0.7)
					(thickness 0.15)
				)
				(justify left bottom)
			)
		)
		(property "Value" "R_6k04_0.1%_0402"
			(at -1.011843 1.772047 180)
			(layer "F.Fab")
			(effects
				(font
					(size 0.7 0.7)
					(thickness 0.15)
				)
				(justify left bottom)
			)
		)
		(property "Datasheet" "https://www.vishay.com/docs/28758/tnpw_e3.pdf"
			(at 0 0 180)
			(layer "F.Fab")
			(hide yes)
			(effects
				(font
					(size 1.27 1.27)
					(thickness 0.15)
				)
			)
		)
		(property "Description" "SMD Chip Resistor, 6.49 kohm, ± 1%, 62.5 mW, 0402 [1005 Metric], Thick Film, General Purpose"
			(at 0 0 180)
			(layer "F.Fab")
			(hide yes)
			(effects
				(font
					(size 1.27 1.27)
					(thickness 0.15)
				)
			)
		)
		(property "MPN" "TNPW04026K04BEED"
			(at 0 0 180)
			(unlocked yes)
			(layer "F.Fab")
			(hide yes)
			(effects
				(font
					(size 1 1)
					(thickness 0.15)
				)
			)
		)
		(property "Manufacturer" "Vishay"
			(at 0 0 180)
			(unlocked yes)
			(layer "F.Fab")
			(hide yes)
			(effects
				(font
					(size 1 1)
					(thickness 0.15)
				)
			)
		)
		(property "License" "Apache-2.0"
			(at 0 0 180)
			(unlocked yes)
			(layer "F.Fab")
			(hide yes)
			(effects
				(font
					(size 1 1)
					(thickness 0.15)
				)
			)
		)
		(property "Author" "Antmicro"
			(at 0 0 180)
			(unlocked yes)
			(layer "F.Fab")
			(hide yes)
			(effects
				(font
					(size 1 1)
					(thickness 0.15)
				)
			)
		)
		(property "Val" "6k04"
			(at 0 0 180)
			(unlocked yes)
			(layer "F.Fab")
			(hide yes)
			(effects
				(font
					(size 1 1)
					(thickness 0.15)
				)
			)
		)
		(property "Tolerance" "0.1%"
			(at 0 0 180)
			(unlocked yes)
			(layer "F.Fab")
			(hide yes)
			(effects
				(font
					(size 1 1)
					(thickness 0.15)
				)
			)
		)
		(sheetname "/Fan controller/")
		(sheetfile "fan-controller.kicad_sch")
		(attr smd)
		(fp_rect
			(start -0.925 -0.47)
			(end 0.925 0.47)
			(stroke
				(width 0.05)
				(type default)
			)
			(fill no)
			(layer "F.CrtYd")
		)
		(fp_rect
			(start -0.5 -0.25)
			(end 0.5 0.25)
			(stroke
				(width 0.15)
				(type solid)
			)
			(fill no)
			(layer "F.Fab")
		)
		(fp_text user "${REFERENCE}"
			(at -0.95 3.168 180)
			(layer "F.Fab")
			(effects
				(font
					(size 0.7 0.7)
					(thickness 0.15)
				)
				(justify left bottom)
			)
		)
		(fp_text user "License: Apache-2.0"
			(at -0.95 5.169 180)
			(layer "F.Fab")
			(effects
				(font
					(size 0.7 0.7)
					(thickness 0.15)
				)
				(justify left bottom)
			)
		)
		(fp_text user "Author: Antmicro"
			(at -0.95 4.169 180)
			(layer "F.Fab")
			(effects
				(font
					(size 0.7 0.7)
					(thickness 0.15)
				)
				(justify left bottom)
			)
		)
		(pad "1" smd roundrect
			(at -0.48 0 180)
			(size 0.59 0.64)
			(layers "F.Cu" "F.Mask" "F.Paste")
			(roundrect_rratio 0.25)
			(net 446 "Net-(R216-Pad1)")
			(pintype "passive")
		)
		(pad "2" smd roundrect
			(at 0.48 0 180)
			(size 0.59 0.64)
			(layers "F.Cu" "F.Mask" "F.Paste")
			(roundrect_rratio 0.25)
			(net 40 "+5V")
			(pintype "passive")
		)
	)
	(footprint "antmicro-footprints:C_0402_1005Metric"
		(layer "F.Cu")
		(at 116.4 106.09 180)
		(descr "Capacitor SMD 0402")
		(tags "capacitor SMD 0402")
		(property "Reference" "C17"
			(at 0 8.1 180)
			(layer "F.SilkS")
			(effects
				(font
					(size 0.7 0.7)
					(thickness 0.15)
				)
			)
		)
		(property "Value" "C_33p_0402"
			(at -1.022927 2.155213 180)
			(layer "F.Fab")
			(effects
				(font
					(size 0.7 0.7)
					(thickness 0.15)
				)
				(justify left bottom)
			)
		)
		(property "Datasheet" "https://spicat.kyocera-avx.com/product/mlcc/chartview/04025A330FAT2A/"
			(at 0 0 180)
			(layer "F.Fab")
			(hide yes)
			(effects
				(font
					(size 1.27 1.27)
					(thickness 0.15)
				)
			)
		)
		(property "Description" "SMD Multilayer Ceramic Capacitor, 33 pF, 50 V, 0402 [1005 Metric], ± 5%, C0G / NP0, MC"
			(at 0 0 180)
			(layer "F.Fab")
			(hide yes)
			(effects
				(font
					(size 1.27 1.27)
					(thickness 0.15)
				)
			)
		)
		(property "MPN" "04025A330FAT2A"
			(at 0 0 180)
			(unlocked yes)
			(layer "F.Fab")
			(hide yes)
			(effects
				(font
					(size 1 1)
					(thickness 0.15)
				)
			)
		)
		(property "Manufacturer" "KYOCERA AVX"
			(at 0 0 180)
			(unlocked yes)
			(layer "F.Fab")
			(hide yes)
			(effects
				(font
					(size 1 1)
					(thickness 0.15)
				)
			)
		)
		(property "License" "Apache-2.0"
			(at 0 0 180)
			(unlocked yes)
			(layer "F.Fab")
			(hide yes)
			(effects
				(font
					(size 1 1)
					(thickness 0.15)
				)
			)
		)
		(property "Val" "33p"
			(at 0 0 180)
			(unlocked yes)
			(layer "F.Fab")
			(hide yes)
			(effects
				(font
					(size 1 1)
					(thickness 0.15)
				)
			)
		)
		(property "Voltage" ""
			(at 0 0 180)
			(unlocked yes)
			(layer "F.Fab")
			(hide yes)
			(effects
				(font
					(size 1 1)
					(thickness 0.15)
				)
			)
		)
		(property "Dielectric" ""
			(at 0 0 180)
			(unlocked yes)
			(layer "F.Fab")
			(hide yes)
			(effects
				(font
					(size 1 1)
					(thickness 0.15)
				)
			)
		)
		(property "Author" "Antmicro"
			(at 0 0 180)
			(unlocked yes)
			(layer "F.Fab")
			(hide yes)
			(effects
				(font
					(size 1 1)
					(thickness 0.15)
				)
			)
		)
		(sheetname "/PD and TB DC-DC/")
		(sheetfile "PD_and_TB_DC_DC.kicad_sch")
		(attr smd)
		(fp_rect
			(start -0.925 -0.47)
			(end 0.925 0.47)
			(stroke
				(width 0.05)
				(type default)
			)
			(fill no)
			(layer "F.CrtYd")
		)
		(fp_line
			(start 0.504 0.248)
			(end -0.494 0.248)
			(stroke
				(width 0.15)
				(type solid)
			)
			(layer "F.Fab")
		)
		(fp_line
			(start 0.504 -0.25)
			(end 0.504 0.248)
			(stroke
				(width 0.15)
				(type solid)
			)
			(layer "F.Fab")
		)
		(fp_line
			(start -0.494 0.248)
			(end -0.494 -0.25)
			(stroke
				(width 0.15)
				(type solid)
			)
			(layer "F.Fab")
		)
		(fp_line
			(start -0.494 -0.25)
			(end 0.504 -0.25)
			(stroke
				(width 0.15)
				(type solid)
			)
			(layer "F.Fab")
		)
		(fp_text user "Author: Antmicro"
			(at -0.939 3.399 180)
			(layer "F.Fab")
			(effects
				(font
					(size 0.7 0.7)
					(thickness 0.15)
				)
				(justify left bottom)
			)
		)
		(fp_text user "${REFERENCE}"
			(at -0.939 4.599 180)
			(layer "F.Fab")
			(effects
				(font
					(size 0.7 0.7)
					(thickness 0.15)
				)
				(justify left bottom)
			)
		)
		(fp_text user "License: Apache-2.0"
			(at -0.939 5.799 180)
			(layer "F.Fab")
			(effects
				(font
					(size 0.7 0.7)
					(thickness 0.15)
				)
				(justify left bottom)
			)
		)
		(pad "1" smd roundrect
			(at -0.48 0 180)
			(size 0.59 0.64)
			(layers "F.Cu" "F.Mask" "F.Paste")
			(roundrect_rratio 0.25)
			(net 166 "Net-(U2-FB)")
			(pintype "passive")
		)
		(pad "2" smd roundrect
			(at 0.48 0 180)
			(size 0.59 0.64)
			(layers "F.Cu" "F.Mask" "F.Paste")
			(roundrect_rratio 0.25)
			(net 399 "Net-(D4-A)")
			(pintype "passive")
		)
	)
	(footprint "antmicro-footprints:R_0402_1005Metric"
		(layer "F.Cu")
		(at 134 84.2 90)
		(descr "Resistor SMD 0402")
		(tags "resistor SMD 0402")
		(property "Reference" "R138"
			(at -1.2 -4.2 90)
			(layer "F.SilkS")
			(effects
				(font
					(size 0.7 0.7)
					(thickness 0.15)
				)
				(justify left bottom)
			)
		)
		(property "Value" "R_0R_0402"
			(at -1.011843 1.772047 90)
			(layer "F.Fab")
			(effects
				(font
					(size 0.7 0.7)
					(thickness 0.15)
				)
				(justify left bottom)
			)
		)
		(property "Datasheet" "https://industrial.panasonic.com/cdbs/www-data/pdf/RDA0000/AOA0000C301.pdf"
			(at 0 0 90)
			(layer "F.Fab")
			(hide yes)
			(effects
				(font
					(size 1.27 1.27)
					(thickness 0.15)
				)
			)
		)
		(property "Description" "SMD Chip Resistor, Jumper, 0 ohm, 100 mW, 0402 [1005 Metric], Thick Film, General Purpose"
			(at 0 0 90)
			(layer "F.Fab")
			(hide yes)
			(effects
				(font
					(size 1.27 1.27)
					(thickness 0.15)
				)
			)
		)
		(property "MPN" "ERJ2GE0R00X"
			(at 0 0 90)
			(unlocked yes)
			(layer "F.Fab")
			(hide yes)
			(effects
				(font
					(size 1 1)
					(thickness 0.15)
				)
			)
		)
		(property "Manufacturer" "Panasonic"
			(at 0 0 90)
			(unlocked yes)
			(layer "F.Fab")
			(hide yes)
			(effects
				(font
					(size 1 1)
					(thickness 0.15)
				)
			)
		)
		(property "License" "Apache-2.0"
			(at 0 0 90)
			(unlocked yes)
			(layer "F.Fab")
			(hide yes)
			(effects
				(font
					(size 1 1)
					(thickness 0.15)
				)
			)
		)
		(property "Author" "Antmicro"
			(at 0 0 90)
			(unlocked yes)
			(layer "F.Fab")
			(hide yes)
			(effects
				(font
					(size 1 1)
					(thickness 0.15)
				)
			)
		)
		(property "Val" "0R"
			(at 0 0 90)
			(unlocked yes)
			(layer "F.Fab")
			(hide yes)
			(effects
				(font
					(size 1 1)
					(thickness 0.15)
				)
			)
		)
		(property "Tolerance" "~"
			(at 0 0 90)
			(unlocked yes)
			(layer "F.Fab")
			(hide yes)
			(effects
				(font
					(size 1 1)
					(thickness 0.15)
				)
			)
		)
		(property "Current" "1A"
			(at 0 0 90)
			(unlocked yes)
			(layer "F.Fab")
			(hide yes)
			(effects
				(font
					(size 1 1)
					(thickness 0.15)
				)
			)
		)
		(sheetname "/X710-AT2 Misc/")
		(sheetfile "x710-at2-mics.kicad_sch")
		(attr smd dnp)
		(fp_rect
			(start -0.925 -0.47)
			(end 0.925 0.47)
			(stroke
				(width 0.05)
				(type default)
			)
			(fill no)
			(layer "F.CrtYd")
		)
		(fp_rect
			(start -0.5 -0.25)
			(end 0.5 0.25)
			(stroke
				(width 0.15)
				(type solid)
			)
			(fill no)
			(layer "F.Fab")
		)
		(fp_text user "License: Apache-2.0"
			(at -0.95 5.169 90)
			(layer "F.Fab")
			(effects
				(font
					(size 0.7 0.7)
					(thickness 0.15)
				)
				(justify left bottom)
			)
		)
		(fp_text user "${REFERENCE}"
			(at -0.95 3.168 90)
			(layer "F.Fab")
			(effects
				(font
					(size 0.7 0.7)
					(thickness 0.15)
				)
				(justify left bottom)
			)
		)
		(fp_text user "Author: Antmicro"
			(at -0.95 4.169 90)
			(layer "F.Fab")
			(effects
				(font
					(size 0.7 0.7)
					(thickness 0.15)
				)
				(justify left bottom)
			)
		)
		(pad "1" smd roundrect
			(at -0.48 0 90)
			(size 0.59 0.64)
			(layers "F.Cu" "F.Mask" "F.Paste")
			(roundrect_rratio 0.25)
			(net 437 "Net-(U15-A)")
			(pintype "passive")
		)
		(pad "2" smd roundrect
			(at 0.48 0 90)
			(size 0.59 0.64)
			(layers "F.Cu" "F.Mask" "F.Paste")
			(roundrect_rratio 0.25)
			(net 74 "/X710-AT2 Misc/LAN_PWR_GOOD")
			(pintype "passive")
		)
	)
	(footprint "antmicro-footprints:LED_0603_1608Metric_G"
		(layer "F.Cu")
		(at 130.4 143.6 -90)
		(descr "LED SMD 0603 Green")
		(tags "LED SMD 0603 Green")
		(property "Reference" "D18"
			(at 1 0.8 270)
			(layer "F.SilkS")
			(effects
				(font
					(size 0.7 0.7)
					(thickness 0.15)
				)
				(justify left bottom)
			)
		)
		(property "Value" "LED_G_0603_LTST-C190GKT"
			(at -0.001 1.599 270)
			(layer "F.Fab")
			(effects
				(font
					(size 0.7 0.7)
					(thickness 0.15)
				)
				(justify left bottom)
			)
		)
		(property "Datasheet" "https://media.digikey.com/pdf/Data%20Sheets/Lite-On%20PDFs/LTST-C190GKT.pdf"
			(at 0 0 270)
			(layer "F.Fab")
			(hide yes)
			(effects
				(font
					(size 1.27 1.27)
					(thickness 0.15)
				)
			)
		)
		(property "Description" "LED, Green, SMD, 0603, 20 mA, 2.1 V, 569 nm"
			(at 0 0 270)
			(layer "F.Fab")
			(hide yes)
			(effects
				(font
					(size 1.27 1.27)
					(thickness 0.15)
				)
			)
		)
		(property "MPN" "LTST-C190GKT"
			(at 0 0 270)
			(unlocked yes)
			(layer "F.Fab")
			(hide yes)
			(effects
				(font
					(size 1 1)
					(thickness 0.15)
				)
			)
		)
		(property "Manufacturer" "Lite-On"
			(at 0 0 270)
			(unlocked yes)
			(layer "F.Fab")
			(hide yes)
			(effects
				(font
					(size 1 1)
					(thickness 0.15)
				)
			)
		)
		(property "Author" "Antmicro"
			(at 0 0 270)
			(unlocked yes)
			(layer "F.Fab")
			(hide yes)
			(effects
				(font
					(size 1 1)
					(thickness 0.15)
				)
			)
		)
		(property "License" "Apache-2.0"
			(at 0 0 270)
			(unlocked yes)
			(layer "F.Fab")
			(hide yes)
			(effects
				(font
					(size 1 1)
					(thickness 0.15)
				)
			)
		)
		(property "Color" "Green"
			(at 0 0 270)
			(unlocked yes)
			(layer "F.Fab")
			(hide yes)
			(effects
				(font
					(size 1 1)
					(thickness 0.15)
				)
			)
		)
		(sheetname "/Power input/")
		(sheetfile "power_input.kicad_sch")
		(attr smd)
		(fp_line
			(start 0.22 0.35)
			(end -0.22 0.35)
			(stroke
				(width 0.15)
				(type solid)
			)
			(layer "F.SilkS")
		)
		(fp_line
			(start -0.094672 0.201008)
			(end -0.094672 -0.198992)
			(stroke
				(width 0.1)
				(type solid)
			)
			(layer "F.SilkS")
		)
		(fp_line
			(start 0.105328 0.201008)
			(end -0.094672 0.001008)
			(stroke
				(width 0.1)
				(type solid)
			)
			(layer "F.SilkS")
		)
		(fp_line
			(start 0.105328 0.201008)
			(end 0.105328 -0.198992)
			(stroke
				(width 0.1)
				(type solid)
			)
			(layer "F.SilkS")
		)
		(fp_line
			(start -0.094672 0.001008)
			(end -0.24 0.001008)
			(stroke
				(width 0.1)
				(type solid)
			)
			(layer "F.SilkS")
		)
		(fp_line
			(start -0.094672 0.001008)
			(end 0.105328 -0.198992)
			(stroke
				(width 0.1)
				(type solid)
			)
			(layer "F.SilkS")
		)
		(fp_line
			(start 0.105328 0.001008)
			(end 0.24 0.001)
			(stroke
				(width 0.1)
				(type solid)
			)
			(layer "F.SilkS")
		)
		(fp_line
			(start -1.18 -0.319)
			(end -1.18 0.321)
			(stroke
				(width 0.15)
				(type solid)
			)
			(layer "F.SilkS")
		)
		(fp_line
			(start 0.22 -0.35)
			(end -0.22 -0.35)
			(stroke
				(width 0.15)
				(type solid)
			)
			(layer "F.SilkS")
		)
		(fp_rect
			(start 1.25 0.65)
			(end -1.25 -0.65)
			(stroke
				(width 0.05)
				(type solid)
			)
			(fill no)
			(layer "F.CrtYd")
		)
		(fp_line
			(start -0.199 0.2)
			(end -0.199 0.1)
			(stroke
				(width 0.15)
				(type solid)
			)
			(layer "F.Fab")
		)
		(fp_line
			(start 0.201 0.2)
			(end 0.201 0)
			(stroke
				(width 0.15)
				(type solid)
			)
			(layer "F.Fab")
		)
		(fp_line
			(start -0.199 0)
			(end -0.597 0)
			(stroke
				(width 0.15)
				(type solid)
			)
			(layer "F.Fab")
		)
		(fp_line
			(start -0.101 0)
			(end 0.201 0.2)
			(stroke
				(width 0.15)
				(type solid)
			)
			(layer "F.Fab")
		)
		(fp_line
			(start 0.201 0)
			(end 0.201 -0.202)
			(stroke
				(width 0.15)
				(type solid)
			)
			(layer "F.Fab")
		)
		(fp_line
			(start 0.599 0)
			(end 0.201 0)
			(stroke
				(width 0.15)
				(type solid)
			)
			(layer "F.Fab")
		)
		(fp_line
			(start -0.199 -0.202)
			(end -0.199 0.1)
			(stroke
				(width 0.15)
				(type solid)
			)
			(layer "F.Fab")
		)
		(fp_line
			(start 0.201 -0.202)
			(end -0.101 0)
			(stroke
				(width 0.15)
				(type solid)
			)
			(layer "F.Fab")
		)
		(fp_rect
			(start 0.848 0.4)
			(end -0.85 -0.402)
			(stroke
				(width 0.15)
				(type solid)
			)
			(fill no)
			(layer "F.Fab")
		)
		(fp_text user "Author: Antmicro"
			(at -1.4224 4.799 270)
			(layer "F.Fab")
			(effects
				(font
					(size 0.7 0.7)
					(thickness 0.15)
				)
				(justify left bottom)
			)
		)
		(fp_text user "License: Apache-2.0"
			(at -1.4224 3.599 270)
			(layer "F.Fab")
			(effects
				(font
					(size 0.7 0.7)
					(thickness 0.15)
				)
				(justify left bottom)
			)
		)
		(fp_text user "${REFERENCE}"
			(at -1.4224 5.999 270)
			(layer "F.Fab")
			(effects
				(font
					(size 0.7 0.7)
					(thickness 0.15)
				)
				(justify left bottom)
			)
		)
		(pad "1" smd roundrect
			(at -0.7 0 90)
			(size 0.8 1)
			(layers "F.Cu" "F.Mask" "F.Paste")
			(roundrect_rratio 0.2)
			(net 23 "GND")
			(pinfunction "C")
			(pintype "passive")
		)
		(pad "2" smd roundrect
			(at 0.7 0 90)
			(size 0.8 1)
			(layers "F.Cu" "F.Mask" "F.Paste")
			(roundrect_rratio 0.2)
			(net 421 "Net-(D18-A)")
			(pinfunction "A")
			(pintype "passive")
		)
	)
	(footprint "antmicro-footprints:C_0402_1005Metric"
		(layer "F.Cu")
		(at 151.955 98.574999)
		(descr "Capacitor SMD 0402")
		(tags "capacitor SMD 0402")
		(property "Reference" "C158"
			(at 23.294999 19.625001 0)
			(layer "F.SilkS")
			(effects
				(font
					(size 0.7 0.7)
					(thickness 0.15)
				)
			)
		)
		(property "Value" "C_100n_0402"
			(at -1.022927 2.155213 0)
			(layer "F.Fab")
			(effects
				(font
					(size 0.7 0.7)
					(thickness 0.15)
				)
				(justify left bottom)
			)
		)
		(property "Datasheet" "https://www.murata.com/products/productdetail?partno=GRM155R61H104KE14%23"
			(at 0 0 0)
			(layer "F.Fab")
			(hide yes)
			(effects
				(font
					(size 1.27 1.27)
					(thickness 0.15)
				)
			)
		)
		(property "Description" "SMD Multilayer Ceramic Capacitor, 0.1 µF, 50 V, 0402 [1005 Metric], ± 10%, X5R, GRM Series"
			(at 0 0 0)
			(layer "F.Fab")
			(hide yes)
			(effects
				(font
					(size 1.27 1.27)
					(thickness 0.15)
				)
			)
		)
		(property "MPN" "GRM155R61H104KE14D"
			(at 0 0 0)
			(unlocked yes)
			(layer "F.Fab")
			(hide yes)
			(effects
				(font
					(size 1 1)
					(thickness 0.15)
				)
			)
		)
		(property "Val" "100n"
			(at 0 0 0)
			(unlocked yes)
			(layer "F.Fab")
			(hide yes)
			(effects
				(font
					(size 1 1)
					(thickness 0.15)
				)
			)
		)
		(property "Voltage" "50V"
			(at 0 0 0)
			(unlocked yes)
			(layer "F.Fab")
			(hide yes)
			(effects
				(font
					(size 1 1)
					(thickness 0.15)
				)
			)
		)
		(property "Dielectric" "X5R"
			(at 0 0 0)
			(unlocked yes)
			(layer "F.Fab")
			(hide yes)
			(effects
				(font
					(size 1 1)
					(thickness 0.15)
				)
			)
		)
		(property "Manufacturer" "Murata"
			(at 0 0 0)
			(unlocked yes)
			(layer "F.Fab")
			(hide yes)
			(effects
				(font
					(size 1 1)
					(thickness 0.15)
				)
			)
		)
		(property "License" "Apache-2.0"
			(at 0 0 0)
			(unlocked yes)
			(layer "F.Fab")
			(hide yes)
			(effects
				(font
					(size 1 1)
					(thickness 0.15)
				)
			)
		)
		(property "Author" "Antmicro"
			(at 0 0 0)
			(unlocked yes)
			(layer "F.Fab")
			(hide yes)
			(effects
				(font
					(size 1 1)
					(thickness 0.15)
				)
			)
		)
		(sheetname "/X710-AT2 power/")
		(sheetfile "x710-at2-power.kicad_sch")
		(attr smd)
		(fp_rect
			(start -0.925 -0.47)
			(end 0.925 0.47)
			(stroke
				(width 0.05)
				(type default)
			)
			(fill no)
			(layer "F.CrtYd")
		)
		(fp_line
			(start -0.494 -0.25)
			(end 0.504 -0.25)
			(stroke
				(width 0.15)
				(type solid)
			)
			(layer "F.Fab")
		)
		(fp_line
			(start -0.494 0.248)
			(end -0.494 -0.25)
			(stroke
				(width 0.15)
				(type solid)
			)
			(layer "F.Fab")
		)
		(fp_line
			(start 0.504 -0.25)
			(end 0.504 0.248)
			(stroke
				(width 0.15)
				(type solid)
			)
			(layer "F.Fab")
		)
		(fp_line
			(start 0.504 0.248)
			(end -0.494 0.248)
			(stroke
				(width 0.15)
				(type solid)
			)
			(layer "F.Fab")
		)
		(fp_text user "License: Apache-2.0"
			(at -0.939 5.799 0)
			(layer "F.Fab")
			(effects
				(font
					(size 0.7 0.7)
					(thickness 0.15)
				)
				(justify left bottom)
			)
		)
		(fp_text user "${REFERENCE}"
			(at -0.939 4.599 0)
			(layer "F.Fab")
			(effects
				(font
					(size 0.7 0.7)
					(thickness 0.15)
				)
				(justify left bottom)
			)
		)
		(fp_text user "Author: Antmicro"
			(at -0.939 3.399 0)
			(layer "F.Fab")
			(effects
				(font
					(size 0.7 0.7)
					(thickness 0.15)
				)
				(justify left bottom)
			)
		)
		(pad "1" smd roundrect
			(at -0.48 0)
			(size 0.59 0.64)
			(layers "F.Cu" "F.Mask" "F.Paste")
			(roundrect_rratio 0.25)
			(net 23 "GND")
			(pintype "passive")
		)
		(pad "2" smd roundrect
			(at 0.48 0)
			(size 0.59 0.64)
			(layers "F.Cu" "F.Mask" "F.Paste")
			(roundrect_rratio 0.25)
			(net 136 "+1V0")
			(pintype "passive")
		)
	)
	(footprint "antmicro-footprints:C_0402_1005Metric"
		(layer "F.Cu")
		(at 154.900001 111.85)
		(descr "Capacitor SMD 0402")
		(tags "capacitor SMD 0402")
		(property "Reference" "C116"
			(at 13.650003 16.799998 0)
			(layer "F.SilkS")
			(effects
				(font
					(size 0.7 0.7)
					(thickness 0.15)
				)
			)
		)
		(property "Value" "C_100n_0402"
			(at -1.022927 2.155213 0)
			(layer "F.Fab")
			(effects
				(font
					(size 0.7 0.7)
					(thickness 0.15)
				)
				(justify left bottom)
			)
		)
		(property "Datasheet" "https://www.murata.com/products/productdetail?partno=GRM155R61H104KE14%23"
			(at 0 0 0)
			(layer "F.Fab")
			(hide yes)
			(effects
				(font
					(size 1.27 1.27)
					(thickness 0.15)
				)
			)
		)
		(property "Description" "SMD Multilayer Ceramic Capacitor, 0.1 µF, 50 V, 0402 [1005 Metric], ± 10%, X5R, GRM Series"
			(at 0 0 0)
			(layer "F.Fab")
			(hide yes)
			(effects
				(font
					(size 1.27 1.27)
					(thickness 0.15)
				)
			)
		)
		(property "MPN" "GRM155R61H104KE14D"
			(at 0 0 0)
			(unlocked yes)
			(layer "F.Fab")
			(hide yes)
			(effects
				(font
					(size 1 1)
					(thickness 0.15)
				)
			)
		)
		(property "Manufacturer" "Murata"
			(at 0 0 0)
			(unlocked yes)
			(layer "F.Fab")
			(hide yes)
			(effects
				(font
					(size 1 1)
					(thickness 0.15)
				)
			)
		)
		(property "License" "Apache-2.0"
			(at 0 0 0)
			(unlocked yes)
			(layer "F.Fab")
			(hide yes)
			(effects
				(font
					(size 1 1)
					(thickness 0.15)
				)
			)
		)
		(property "Author" "Antmicro"
			(at 0 0 0)
			(unlocked yes)
			(layer "F.Fab")
			(hide yes)
			(effects
				(font
					(size 1 1)
					(thickness 0.15)
				)
			)
		)
		(property "Val" "100n"
			(at 0 0 0)
			(unlocked yes)
			(layer "F.Fab")
			(hide yes)
			(effects
				(font
					(size 1 1)
					(thickness 0.15)
				)
			)
		)
		(property "Voltage" "50V"
			(at 0 0 0)
			(unlocked yes)
			(layer "F.Fab")
			(hide yes)
			(effects
				(font
					(size 1 1)
					(thickness 0.15)
				)
			)
		)
		(property "Dielectric" "X5R"
			(at 0 0 0)
			(unlocked yes)
			(layer "F.Fab")
			(hide yes)
			(effects
				(font
					(size 1 1)
					(thickness 0.15)
				)
			)
		)
		(sheetname "/X710 DCDC converters/")
		(sheetfile "DCDC_converters_X710.kicad_sch")
		(attr smd)
		(fp_rect
			(start -0.925 -0.47)
			(end 0.925 0.47)
			(stroke
				(width 0.05)
				(type default)
			)
			(fill no)
			(layer "F.CrtYd")
		)
		(fp_line
			(start -0.494 -0.25)
			(end 0.504 -0.25)
			(stroke
				(width 0.15)
				(type solid)
			)
			(layer "F.Fab")
		)
		(fp_line
			(start -0.494 0.248)
			(end -0.494 -0.25)
			(stroke
				(width 0.15)
				(type solid)
			)
			(layer "F.Fab")
		)
		(fp_line
			(start 0.504 -0.25)
			(end 0.504 0.248)
			(stroke
				(width 0.15)
				(type solid)
			)
			(layer "F.Fab")
		)
		(fp_line
			(start 0.504 0.248)
			(end -0.494 0.248)
			(stroke
				(width 0.15)
				(type solid)
			)
			(layer "F.Fab")
		)
		(fp_text user "License: Apache-2.0"
			(at -0.939 5.799 0)
			(layer "F.Fab")
			(effects
				(font
					(size 0.7 0.7)
					(thickness 0.15)
				)
				(justify left bottom)
			)
		)
		(fp_text user "${REFERENCE}"
			(at -0.939 4.599 0)
			(layer "F.Fab")
			(effects
				(font
					(size 0.7 0.7)
					(thickness 0.15)
				)
				(justify left bottom)
			)
		)
		(fp_text user "Author: Antmicro"
			(at -0.939 3.399 0)
			(layer "F.Fab")
			(effects
				(font
					(size 0.7 0.7)
					(thickness 0.15)
				)
				(justify left bottom)
			)
		)
		(pad "1" smd roundrect
			(at -0.48 0)
			(size 0.59 0.64)
			(layers "F.Cu" "F.Mask" "F.Paste")
			(roundrect_rratio 0.25)
			(net 23 "GND")
			(pintype "passive")
		)
		(pad "2" smd roundrect
			(at 0.48 0)
			(size 0.59 0.64)
			(layers "F.Cu" "F.Mask" "F.Paste")
			(roundrect_rratio 0.25)
			(net 40 "+5V")
			(pintype "passive")
		)
	)
	(footprint "antmicro-footprints:C_0603_1608Metric_EIA"
		(layer "F.Cu")
		(at 137.355 89.274999 -90)
		(descr "Capacitor SMD 0603, IPC-7351 Density Level A")
		(tags "Capacitor 0603")
		(property "Reference" "C244"
			(at 4.225001 17.105 270)
			(layer "F.SilkS")
			(effects
				(font
					(size 0.7 0.7)
					(thickness 0.15)
				)
				(justify left bottom)
			)
		)
		(property "Value" "C_22u_16V_0603"
			(at -1.42757 1.770288 270)
			(layer "F.Fab")
			(effects
				(font
					(size 0.7 0.7)
					(thickness 0.15)
				)
				(justify left bottom)
			)
		)
		(property "Datasheet" "https://product.samsungsem.com/mlcc/CL10A226MO7JZN.do"
			(at 0 0 270)
			(layer "F.Fab")
			(hide yes)
			(effects
				(font
					(size 1.27 1.27)
					(thickness 0.15)
				)
			)
		)
		(property "Description" "SMD Multilayer Ceramic Capacitor"
			(at 0 0 270)
			(layer "F.Fab")
			(hide yes)
			(effects
				(font
					(size 1.27 1.27)
					(thickness 0.15)
				)
			)
		)
		(property "MPN" "CL10A226MO7JZNC"
			(at 0 0 270)
			(unlocked yes)
			(layer "F.Fab")
			(hide yes)
			(effects
				(font
					(size 1 1)
					(thickness 0.15)
				)
			)
		)
		(property "Manufacturer" "Samsung Electro-Mechanics"
			(at 0 0 270)
			(unlocked yes)
			(layer "F.Fab")
			(hide yes)
			(effects
				(font
					(size 1 1)
					(thickness 0.15)
				)
			)
		)
		(property "License" "Apache-2.0"
			(at 0 0 270)
			(unlocked yes)
			(layer "F.Fab")
			(hide yes)
			(effects
				(font
					(size 1 1)
					(thickness 0.15)
				)
			)
		)
		(property "Author" "Antmicro"
			(at 0 0 270)
			(unlocked yes)
			(layer "F.Fab")
			(hide yes)
			(effects
				(font
					(size 1 1)
					(thickness 0.15)
				)
			)
		)
		(property "Val" "22u"
			(at 0 0 270)
			(unlocked yes)
			(layer "F.Fab")
			(hide yes)
			(effects
				(font
					(size 1 1)
					(thickness 0.15)
				)
			)
		)
		(property "Voltage" "16V"
			(at 0 0 270)
			(unlocked yes)
			(layer "F.Fab")
			(hide yes)
			(effects
				(font
					(size 1 1)
					(thickness 0.15)
				)
			)
		)
		(property "Dielectric" ""
			(at 0 0 270)
			(unlocked yes)
			(layer "F.Fab")
			(hide yes)
			(effects
				(font
					(size 1 1)
					(thickness 0.15)
				)
			)
		)
		(sheetname "/X710-AT2 power/")
		(sheetfile "x710-at2-power.kicad_sch")
		(attr smd)
		(fp_line
			(start -0.15 0.55)
			(end 0.15 0.55)
			(stroke
				(width 0.15)
				(type solid)
			)
			(layer "F.SilkS")
		)
		(fp_line
			(start -0.15 -0.55)
			(end 0.15 -0.55)
			(stroke
				(width 0.15)
				(type solid)
			)
			(layer "F.SilkS")
		)
		(fp_rect
			(start -1.25 -0.65)
			(end 1.25 0.65)
			(stroke
				(width 0.05)
				(type solid)
			)
			(fill no)
			(layer "F.CrtYd")
		)
		(fp_rect
			(start -0.8 -0.45)
			(end 0.8 0.45)
			(stroke
				(width 0.15)
				(type solid)
			)
			(fill no)
			(layer "F.Fab")
		)
		(fp_text user "Author: Antmicro"
			(at -1.682 4.894 270)
			(layer "F.Fab")
			(effects
				(font
					(size 0.7 0.7)
					(thickness 0.15)
				)
				(justify left bottom)
			)
		)
		(fp_text user "License: Apache-2.0"
			(at -1.682 5.895 270)
			(layer "F.Fab")
			(effects
				(font
					(size 0.7 0.7)
					(thickness 0.15)
				)
				(justify left bottom)
			)
		)
		(fp_text user "${REFERENCE}"
			(at -1.682 3.895 270)
			(layer "F.Fab")
			(effects
				(font
					(size 0.7 0.7)
					(thickness 0.15)
				)
				(justify left bottom)
			)
		)
		(pad "1" smd roundrect
			(at -0.7 0 270)
			(size 0.8 1.1)
			(layers "F.Cu" "F.Mask" "F.Paste")
			(roundrect_rratio 0.2)
			(net 23 "GND")
			(pintype "passive")
		)
		(pad "2" smd roundrect
			(at 0.7 0 270)
			(size 0.8 1.1)
			(layers "F.Cu" "F.Mask" "F.Paste")
			(roundrect_rratio 0.2)
			(net 7 "+3V3")
			(pintype "passive")
		)
	)
	(footprint "antmicro-footprints:C_Pol_EIA-B"
		(layer "F.Cu")
		(at 139.25 130.25 90)
		(property "Reference" "C53"
			(at 0.55 5.750001 90)
			(layer "F.SilkS")
			(effects
				(font
					(size 0.7 0.7)
					(thickness 0.15)
				)
				(justify left bottom)
			)
		)
		(property "Value" "C_Pol_330u_6.3V_KEMET-T520-B"
			(at 0 2.85 90)
			(layer "F.Fab")
			(effects
				(font
					(size 0.7 0.7)
					(thickness 0.15)
				)
				(justify left bottom)
			)
		)
		(property "Datasheet" "https://www.kemet.com/en/us/capacitors/product/T520B337M006ATE040.html"
			(at 0 0 90)
			(layer "F.Fab")
			(hide yes)
			(effects
				(font
					(size 1.27 1.27)
					(thickness 0.15)
				)
			)
		)
		(property "Description" "Tantalum Polymer Capacitor, KO-CAP®, 330 µF, ± 20%, 6.3 V, B, 0.04 ohm, 1411 [3528 Metric]"
			(at 0 0 90)
			(layer "F.Fab")
			(hide yes)
			(effects
				(font
					(size 1.27 1.27)
					(thickness 0.15)
				)
			)
		)
		(property "Val" "330u"
			(at 0 0 90)
			(unlocked yes)
			(layer "F.Fab")
			(hide yes)
			(effects
				(font
					(size 1 1)
					(thickness 0.15)
				)
			)
		)
		(property "MPN" "T520B337M006ATE040"
			(at 0 0 90)
			(unlocked yes)
			(layer "F.Fab")
			(hide yes)
			(effects
				(font
					(size 1 1)
					(thickness 0.15)
				)
			)
		)
		(property "Manufacturer" "KEMET"
			(at 0 0 90)
			(unlocked yes)
			(layer "F.Fab")
			(hide yes)
			(effects
				(font
					(size 1 1)
					(thickness 0.15)
				)
			)
		)
		(property "License" "Apache-2.0"
			(at 0 0 90)
			(unlocked yes)
			(layer "F.Fab")
			(hide yes)
			(effects
				(font
					(size 1 1)
					(thickness 0.15)
				)
			)
		)
		(property "Author" "Antmicro"
			(at 0 0 90)
			(unlocked yes)
			(layer "F.Fab")
			(hide yes)
			(effects
				(font
					(size 1 1)
					(thickness 0.15)
				)
			)
		)
		(property "Voltage" "6.3V"
			(at 0 0 90)
			(unlocked yes)
			(layer "F.Fab")
			(hide yes)
			(effects
				(font
					(size 1 1)
					(thickness 0.15)
				)
			)
		)
		(property "Dielectric" "template_dielectric"
			(at 0 0 90)
			(unlocked yes)
			(layer "F.Fab")
			(hide yes)
			(effects
				(font
					(size 1 1)
					(thickness 0.15)
				)
			)
		)
		(sheetname "/TB Controller - Power/")
		(sheetfile "tb-power.kicad_sch")
		(attr smd)
		(fp_line
			(start -2.521 -1.676)
			(end -2.123 -1.676)
			(stroke
				(width 0.15)
				(type solid)
			)
			(layer "F.SilkS")
		)
		(fp_line
			(start -1.8 -1.6)
			(end 1.8 -1.6)
			(stroke
				(width 0.15)
				(type solid)
			)
			(layer "F.SilkS")
		)
		(fp_line
			(start -2.325 -1.475)
			(end -2.325 -1.878)
			(stroke
				(width 0.15)
				(type solid)
			)
			(layer "F.SilkS")
		)
		(fp_line
			(start 1.8 -1.3)
			(end 1.8 -1.6)
			(stroke
				(width 0.15)
				(type solid)
			)
			(layer "F.SilkS")
		)
		(fp_line
			(start -1.8 -1.3)
			(end -1.8 -1.6)
			(stroke
				(width 0.15)
				(type solid)
			)
			(layer "F.SilkS")
		)
		(fp_line
			(start 1.8 1.3)
			(end 1.8 1.6)
			(stroke
				(width 0.15)
				(type solid)
			)
			(layer "F.SilkS")
		)
		(fp_line
			(start -1.8 1.3)
			(end -1.8 1.6)
			(stroke
				(width 0.15)
				(type solid)
			)
			(layer "F.SilkS")
		)
		(fp_line
			(start 1.8 1.6)
			(end -1.8 1.6)
			(stroke
				(width 0.15)
				(type solid)
			)
			(layer "F.SilkS")
		)
		(fp_line
			(start 1.959 -1.75)
			(end -1.97 -1.75)
			(stroke
				(width 0.05)
				(type solid)
			)
			(layer "F.CrtYd")
		)
		(fp_line
			(start 1.959 -1.75)
			(end 1.959 -1.35)
			(stroke
				(width 0.05)
				(type solid)
			)
			(layer "F.CrtYd")
		)
		(fp_line
			(start -1.97 -1.75)
			(end -1.97 -1.35)
			(stroke
				(width 0.05)
				(type solid)
			)
			(layer "F.CrtYd")
		)
		(fp_line
			(start 2.399 -1.35)
			(end 1.959 -1.35)
			(stroke
				(width 0.05)
				(type solid)
			)
			(layer "F.CrtYd")
		)
		(fp_line
			(start 2.399 -1.35)
			(end 2.4 1.35)
			(stroke
				(width 0.05)
				(type solid)
			)
			(layer "F.CrtYd")
		)
		(fp_line
			(start -1.97 -1.35)
			(end -2.41 -1.35)
			(stroke
				(width 0.05)
				(type solid)
			)
			(layer "F.CrtYd")
		)
		(fp_line
			(start -2.411 -1.35)
			(end -2.41 1.35)
			(stroke
				(width 0.05)
				(type solid)
			)
			(layer "F.CrtYd")
		)
		(fp_line
			(start 2.4 1.35)
			(end 1.96 1.35)
			(stroke
				(width 0.05)
				(type solid)
			)
			(layer "F.CrtYd")
		)
		(fp_line
			(start 1.96 1.35)
			(end 1.96 1.75)
			(stroke
				(width 0.05)
				(type solid)
			)
			(layer "F.CrtYd")
		)
		(fp_line
			(start -1.97 1.35)
			(end -2.41 1.35)
			(stroke
				(width 0.05)
				(type solid)
			)
			(layer "F.CrtYd")
		)
		(fp_line
			(start -1.97 1.35)
			(end -1.97 1.75)
			(stroke
				(width 0.05)
				(type solid)
			)
			(layer "F.CrtYd")
		)
		(fp_line
			(start 1.96 1.75)
			(end -1.97 1.75)
			(stroke
				(width 0.05)
				(type solid)
			)
			(layer "F.CrtYd")
		)
		(fp_line
			(start -1.7 1.324)
			(end -1.551 1.475)
			(stroke
				(width 0.15)
				(type solid)
			)
			(layer "F.Fab")
		)
		(fp_rect
			(start -1.72 -1.5)
			(end 1.719 1.499)
			(stroke
				(width 0.15)
				(type solid)
			)
			(fill no)
			(layer "F.Fab")
		)
		(fp_text user "Author: Antmicro"
			(at -2.665 6.85 90)
			(layer "F.Fab")
			(effects
				(font
					(size 0.7 0.7)
					(thickness 0.15)
				)
				(justify left bottom)
			)
		)
		(fp_text user "License: Apache-2.0"
			(at -2.665 5.65 90)
			(layer "F.Fab")
			(effects
				(font
					(size 0.7 0.7)
					(thickness 0.15)
				)
				(justify left bottom)
			)
		)
		(fp_text user "${REFERENCE}"
			(at -2.665 4.45 90)
			(layer "F.Fab")
			(effects
				(font
					(size 0.7 0.7)
					(thickness 0.15)
				)
				(justify left bottom)
			)
		)
		(pad "1" smd roundrect
			(at -1.551 0 90)
			(size 1.2 2.2)
			(layers "F.Cu" "F.Mask" "F.Paste")
			(roundrect_rratio 0.1)
			(net 57 "+3V3_TB")
			(pintype "passive")
		)
		(pad "2" smd roundrect
			(at 1.55 0 90)
			(size 1.2 2.2)
			(layers "F.Cu" "F.Mask" "F.Paste")
			(roundrect_rratio 0.1)
			(net 23 "GND")
			(pintype "passive")
		)
	)
	(footprint "antmicro-footprints:SOT-23-5"
		(layer "F.Cu")
		(at 119 89)
		(property "Reference" "U6"
			(at -2 -2 0)
			(layer "F.SilkS")
			(effects
				(font
					(size 0.7 0.7)
					(thickness 0.15)
				)
				(justify left bottom)
			)
		)
		(property "Value" "MCP6541_SOT23-5"
			(at 0.002 2.799 0)
			(layer "F.Fab")
			(effects
				(font
					(size 0.7 0.7)
					(thickness 0.15)
				)
				(justify left bottom)
			)
		)
		(property "Datasheet" "https://www.farnell.com/datasheets/1641674.pdf"
			(at 0 0 0)
			(layer "F.Fab")
			(hide yes)
			(effects
				(font
					(size 1.27 1.27)
					(thickness 0.15)
				)
			)
		)
		(property "Description" "Push-Pull Output Comparator, 1,6V to 5.5V, SOT-23-5"
			(at 0 0 0)
			(layer "F.Fab")
			(hide yes)
			(effects
				(font
					(size 1.27 1.27)
					(thickness 0.15)
				)
			)
		)
		(property "MPN" "MCP6541T-E/OT"
			(at 0 0 0)
			(unlocked yes)
			(layer "F.Fab")
			(hide yes)
			(effects
				(font
					(size 1 1)
					(thickness 0.15)
				)
			)
		)
		(property "Manufacturer" "Microchip Technology"
			(at 0 0 0)
			(unlocked yes)
			(layer "F.Fab")
			(hide yes)
			(effects
				(font
					(size 1 1)
					(thickness 0.15)
				)
			)
		)
		(property "Author" "Antmicro"
			(at 0 0 0)
			(unlocked yes)
			(layer "F.Fab")
			(hide yes)
			(effects
				(font
					(size 1 1)
					(thickness 0.15)
				)
			)
		)
		(property "License" "Apache-2.0"
			(at 0 0 0)
			(unlocked yes)
			(layer "F.Fab")
			(hide yes)
			(effects
				(font
					(size 1 1)
					(thickness 0.15)
				)
			)
		)
		(sheetname "/TB Controller - Power/")
		(sheetfile "tb-power.kicad_sch")
		(attr smd)
		(fp_line
			(start -0.85 1.6)
			(end -0.85 1.301)
			(stroke
				(width 0.15)
				(type solid)
			)
			(layer "F.SilkS")
		)
		(fp_line
			(start -0.8 -1.6)
			(end -0.8 -1.3)
			(stroke
				(width 0.15)
				(type solid)
			)
			(layer "F.SilkS")
		)
		(fp_line
			(start -0.8 -1.6)
			(end -0.5 -1.6)
			(stroke
				(width 0.15)
				(type solid)
			)
			(layer "F.SilkS")
		)
		(fp_line
			(start -0.55 1.6)
			(end -0.85 1.6)
			(stroke
				(width 0.15)
				(type solid)
			)
			(layer "F.SilkS")
		)
		(fp_line
			(start 0.8 -1.6)
			(end 0.5 -1.6)
			(stroke
				(width 0.15)
				(type solid)
			)
			(layer "F.SilkS")
		)
		(fp_line
			(start 0.8 -1.3)
			(end 0.8 -1.6)
			(stroke
				(width 0.15)
				(type solid)
			)
			(layer "F.SilkS")
		)
		(fp_line
			(start 0.8 0.55)
			(end 0.8 -0.55)
			(stroke
				(width 0.15)
				(type solid)
			)
			(layer "F.SilkS")
		)
		(fp_line
			(start 0.8 1.3)
			(end 0.8 1.599)
			(stroke
				(width 0.15)
				(type solid)
			)
			(layer "F.SilkS")
		)
		(fp_line
			(start 0.8 1.599)
			(end 0.549 1.599)
			(stroke
				(width 0.15)
				(type solid)
			)
			(layer "F.SilkS")
		)
		(fp_circle
			(center -1.25 -1.5)
			(end -1.2 -1.5)
			(stroke
				(width 0.15)
				(type solid)
			)
			(fill yes)
			(layer "F.SilkS")
		)
		(fp_rect
			(start 1.9 -1.76)
			(end -1.9 1.75)
			(stroke
				(width 0.05)
				(type solid)
			)
			(fill no)
			(layer "F.CrtYd")
		)
		(fp_line
			(start -0.398 -1.526)
			(end -0.874 -1.05)
			(stroke
				(width 0.15)
				(type solid)
			)
			(layer "F.Fab")
		)
		(fp_rect
			(start 0.874 1.523)
			(end -0.873 -1.525)
			(stroke
				(width 0.15)
				(type solid)
			)
			(fill no)
			(layer "F.Fab")
		)
		(fp_text user "Author: Antmicro"
			(at -1.898 5.499 0)
			(layer "F.Fab")
			(effects
				(font
					(size 0.7 0.7)
					(thickness 0.15)
				)
				(justify left bottom)
			)
		)
		(fp_text user "License: Apache-2.0"
			(at -1.898 6.7 0)
			(layer "F.Fab")
			(effects
				(font
					(size 0.7 0.7)
					(thickness 0.15)
				)
				(justify left bottom)
			)
		)
		(fp_text user "${REFERENCE}"
			(at -1.898 4.299 0)
			(layer "F.Fab")
			(effects
				(font
					(size 0.7 0.7)
					(thickness 0.15)
				)
				(justify left bottom)
			)
		)
		(pad "1" smd rect
			(at -1.351 -0.951 270)
			(size 0.55 1)
			(layers "F.Cu" "F.Mask" "F.Paste")
			(net 356 "/TB Controller - Power/0P9_BUFFERED")
			(pintype "output")
		)
		(pad "2" smd rect
			(at -1.351 0 270)
			(size 0.55 1)
			(layers "F.Cu" "F.Mask" "F.Paste")
			(net 23 "GND")
			(pinfunction "VSS")
			(pintype "power_in")
		)
		(pad "3" smd rect
			(at -1.351 0.949 270)
			(size 0.55 1)
			(layers "F.Cu" "F.Mask" "F.Paste")
			(net 436 "Net-(R77-Pad1)")
			(pintype "input")
		)
		(pad "4" smd rect
			(at 1.35 0.949 270)
			(size 0.55 1)
			(layers "F.Cu" "F.Mask" "F.Paste")
			(net 435 "Net-(R75-Pad1)")
			(pintype "input")
		)
		(pad "5" smd rect
			(at 1.35 -0.951 270)
			(size 0.55 1)
			(layers "F.Cu" "F.Mask" "F.Paste")
			(net 57 "+3V3_TB")
			(pinfunction "VDD")
			(pintype "power_in")
		)
	)
	(footprint "antmicro-footprints:R_0402_1005Metric"
		(layer "F.Cu")
		(at 165.265 60.1 90)
		(descr "Resistor SMD 0402")
		(tags "resistor SMD 0402")
		(property "Reference" "R184"
			(at 6.7 -0.065 90)
			(layer "F.SilkS")
			(effects
				(font
					(size 0.7 0.7)
					(thickness 0.15)
				)
				(justify left bottom)
			)
		)
		(property "Value" "R_10k_0402"
			(at -1.011843 1.772047 90)
			(layer "F.Fab")
			(effects
				(font
					(size 0.7 0.7)
					(thickness 0.15)
				)
				(justify left bottom)
			)
		)
		(property "Datasheet" "https://www.bourns.com/docs/product-datasheets/cr.pdf"
			(at 0 0 90)
			(layer "F.Fab")
			(hide yes)
			(effects
				(font
					(size 1.27 1.27)
					(thickness 0.15)
				)
			)
		)
		(property "Description" "SMD Chip Resistor, 10 kohm, ± 1%, 62.5 mW, 0402 [1005 Metric], Thick Film, General Purpose"
			(at 0 0 90)
			(layer "F.Fab")
			(hide yes)
			(effects
				(font
					(size 1.27 1.27)
					(thickness 0.15)
				)
			)
		)
		(property "MPN" "CR0402-FX-1002GLF"
			(at 0 0 90)
			(unlocked yes)
			(layer "F.Fab")
			(hide yes)
			(effects
				(font
					(size 1 1)
					(thickness 0.15)
				)
			)
		)
		(property "Manufacturer" "Bourns"
			(at 0 0 90)
			(unlocked yes)
			(layer "F.Fab")
			(hide yes)
			(effects
				(font
					(size 1 1)
					(thickness 0.15)
				)
			)
		)
		(property "License" "Apache-2.0"
			(at 0 0 90)
			(unlocked yes)
			(layer "F.Fab")
			(hide yes)
			(effects
				(font
					(size 1 1)
					(thickness 0.15)
				)
			)
		)
		(property "Author" "Antmicro"
			(at 0 0 90)
			(unlocked yes)
			(layer "F.Fab")
			(hide yes)
			(effects
				(font
					(size 1 1)
					(thickness 0.15)
				)
			)
		)
		(property "Val" "10k"
			(at 0 0 90)
			(unlocked yes)
			(layer "F.Fab")
			(hide yes)
			(effects
				(font
					(size 1 1)
					(thickness 0.15)
				)
			)
		)
		(property "Tolerance" "1%"
			(at 0 0 90)
			(unlocked yes)
			(layer "F.Fab")
			(hide yes)
			(effects
				(font
					(size 1 1)
					(thickness 0.15)
				)
			)
		)
		(sheetname "/X710-AT2 10GbE/")
		(sheetfile "x710-at2-10gbe.kicad_sch")
		(attr smd)
		(fp_rect
			(start -0.925 -0.47)
			(end 0.925 0.47)
			(stroke
				(width 0.05)
				(type default)
			)
			(fill no)
			(layer "F.CrtYd")
		)
		(fp_rect
			(start -0.5 -0.25)
			(end 0.5 0.25)
			(stroke
				(width 0.15)
				(type solid)
			)
			(fill no)
			(layer "F.Fab")
		)
		(fp_text user "License: Apache-2.0"
			(at -0.95 5.169 90)
			(layer "F.Fab")
			(effects
				(font
					(size 0.7 0.7)
					(thickness 0.15)
				)
				(justify left bottom)
			)
		)
		(fp_text user "${REFERENCE}"
			(at -0.95 3.168 90)
			(layer "F.Fab")
			(effects
				(font
					(size 0.7 0.7)
					(thickness 0.15)
				)
				(justify left bottom)
			)
		)
		(fp_text user "Author: Antmicro"
			(at -0.95 4.169 90)
			(layer "F.Fab")
			(effects
				(font
					(size 0.7 0.7)
					(thickness 0.15)
				)
				(justify left bottom)
			)
		)
		(pad "1" smd roundrect
			(at -0.48 0 90)
			(size 0.59 0.64)
			(layers "F.Cu" "F.Mask" "F.Paste")
			(roundrect_rratio 0.25)
			(net 56 "/X710-AT2 10GbE/3V3_OSC")
			(pintype "passive")
		)
		(pad "2" smd roundrect
			(at 0.48 0 90)
			(size 0.59 0.64)
			(layers "F.Cu" "F.Mask" "F.Paste")
			(roundrect_rratio 0.25)
			(net 113 "/X710-AT2 10GbE/EN_OSC")
			(pintype "passive")
		)
	)
	(footprint "antmicro-footprints:C_0603_1608Metric_EIA"
		(layer "F.Cu")
		(at 142.799999 105.600003 90)
		(descr "Capacitor SMD 0603, IPC-7351 Density Level A")
		(tags "Capacitor 0603")
		(property "Reference" "C138"
			(at -17.849995 15.649999 90)
			(layer "F.SilkS")
			(effects
				(font
					(size 0.7 0.7)
					(thickness 0.15)
				)
			)
		)
		(property "Value" "C_22u_16V_0603"
			(at -1.42757 1.770288 90)
			(layer "F.Fab")
			(effects
				(font
					(size 0.7 0.7)
					(thickness 0.15)
				)
				(justify left bottom)
			)
		)
		(property "Datasheet" "https://product.samsungsem.com/mlcc/CL10A226MO7JZN.do"
			(at 0 0 90)
			(layer "F.Fab")
			(hide yes)
			(effects
				(font
					(size 1.27 1.27)
					(thickness 0.15)
				)
			)
		)
		(property "Description" "SMD Multilayer Ceramic Capacitor"
			(at 0 0 90)
			(layer "F.Fab")
			(hide yes)
			(effects
				(font
					(size 1.27 1.27)
					(thickness 0.15)
				)
			)
		)
		(property "MPN" "CL10A226MO7JZNC"
			(at 0 0 90)
			(unlocked yes)
			(layer "F.Fab")
			(hide yes)
			(effects
				(font
					(size 1 1)
					(thickness 0.15)
				)
			)
		)
		(property "Manufacturer" "Samsung Electro-Mechanics"
			(at 0 0 90)
			(unlocked yes)
			(layer "F.Fab")
			(hide yes)
			(effects
				(font
					(size 1 1)
					(thickness 0.15)
				)
			)
		)
		(property "License" "Apache-2.0"
			(at 0 0 90)
			(unlocked yes)
			(layer "F.Fab")
			(hide yes)
			(effects
				(font
					(size 1 1)
					(thickness 0.15)
				)
			)
		)
		(property "Author" "Antmicro"
			(at 0 0 90)
			(unlocked yes)
			(layer "F.Fab")
			(hide yes)
			(effects
				(font
					(size 1 1)
					(thickness 0.15)
				)
			)
		)
		(property "Val" "22u"
			(at 0 0 90)
			(unlocked yes)
			(layer "F.Fab")
			(hide yes)
			(effects
				(font
					(size 1 1)
					(thickness 0.15)
				)
			)
		)
		(property "Voltage" "16V"
			(at 0 0 90)
			(unlocked yes)
			(layer "F.Fab")
			(hide yes)
			(effects
				(font
					(size 1 1)
					(thickness 0.15)
				)
			)
		)
		(property "Dielectric" ""
			(at 0 0 90)
			(unlocked yes)
			(layer "F.Fab")
			(hide yes)
			(effects
				(font
					(size 1 1)
					(thickness 0.15)
				)
			)
		)
		(sheetname "/X710 DCDC converters/")
		(sheetfile "DCDC_converters_X710.kicad_sch")
		(attr smd)
		(fp_line
			(start -0.15 -0.55)
			(end 0.15 -0.55)
			(stroke
				(width 0.15)
				(type solid)
			)
			(layer "F.SilkS")
		)
		(fp_line
			(start -0.15 0.55)
			(end 0.15 0.55)
			(stroke
				(width 0.15)
				(type solid)
			)
			(layer "F.SilkS")
		)
		(fp_rect
			(start -1.25 -0.65)
			(end 1.25 0.65)
			(stroke
				(width 0.05)
				(type solid)
			)
			(fill no)
			(layer "F.CrtYd")
		)
		(fp_rect
			(start -0.8 -0.45)
			(end 0.8 0.45)
			(stroke
				(width 0.15)
				(type solid)
			)
			(fill no)
			(layer "F.Fab")
		)
		(fp_text user "License: Apache-2.0"
			(at -1.682 5.895 90)
			(layer "F.Fab")
			(effects
				(font
					(size 0.7 0.7)
					(thickness 0.15)
				)
				(justify left bottom)
			)
		)
		(fp_text user "${REFERENCE}"
			(at -1.682 3.895 90)
			(layer "F.Fab")
			(effects
				(font
					(size 0.7 0.7)
					(thickness 0.15)
				)
				(justify left bottom)
			)
		)
		(fp_text user "Author: Antmicro"
			(at -1.682 4.894 90)
			(layer "F.Fab")
			(effects
				(font
					(size 0.7 0.7)
					(thickness 0.15)
				)
				(justify left bottom)
			)
		)
		(pad "1" smd roundrect
			(at -0.7 0 90)
			(size 0.8 1.1)
			(layers "F.Cu" "F.Mask" "F.Paste")
			(roundrect_rratio 0.2)
			(net 23 "GND")
			(pintype "passive")
		)
		(pad "2" smd roundrect
			(at 0.7 0 90)
			(size 0.8 1.1)
			(layers "F.Cu" "F.Mask" "F.Paste")
			(roundrect_rratio 0.2)
			(net 341 "/X710 DCDC converters/+DVDD_OUT")
			(pintype "passive")
		)
	)
	(footprint "antmicro-footprints:C_0603_1608Metric_EIA"
		(layer "F.Cu")
		(at 166.505 99.224999 -90)
		(descr "Capacitor SMD 0603, IPC-7351 Density Level A")
		(tags "Capacitor 0603")
		(property "Reference" "C156"
			(at 0 -7.695 270)
			(layer "F.SilkS")
			(effects
				(font
					(size 0.7 0.7)
					(thickness 0.15)
				)
			)
		)
		(property "Value" "C_22u_16V_0603"
			(at -1.42757 1.770288 270)
			(layer "F.Fab")
			(effects
				(font
					(size 0.7 0.7)
					(thickness 0.15)
				)
				(justify left bottom)
			)
		)
		(property "Datasheet" "https://product.samsungsem.com/mlcc/CL10A226MO7JZN.do"
			(at 0 0 270)
			(layer "F.Fab")
			(hide yes)
			(effects
				(font
					(size 1.27 1.27)
					(thickness 0.15)
				)
			)
		)
		(property "Description" "SMD Multilayer Ceramic Capacitor"
			(at 0 0 270)
			(layer "F.Fab")
			(hide yes)
			(effects
				(font
					(size 1.27 1.27)
					(thickness 0.15)
				)
			)
		)
		(property "MPN" "CL10A226MO7JZNC"
			(at 0 0 270)
			(unlocked yes)
			(layer "F.Fab")
			(hide yes)
			(effects
				(font
					(size 1 1)
					(thickness 0.15)
				)
			)
		)
		(property "Manufacturer" "Samsung Electro-Mechanics"
			(at 0 0 270)
			(unlocked yes)
			(layer "F.Fab")
			(hide yes)
			(effects
				(font
					(size 1 1)
					(thickness 0.15)
				)
			)
		)
		(property "License" "Apache-2.0"
			(at 0 0 270)
			(unlocked yes)
			(layer "F.Fab")
			(hide yes)
			(effects
				(font
					(size 1 1)
					(thickness 0.15)
				)
			)
		)
		(property "Author" "Antmicro"
			(at 0 0 270)
			(unlocked yes)
			(layer "F.Fab")
			(hide yes)
			(effects
				(font
					(size 1 1)
					(thickness 0.15)
				)
			)
		)
		(property "Val" "22u"
			(at 0 0 270)
			(unlocked yes)
			(layer "F.Fab")
			(hide yes)
			(effects
				(font
					(size 1 1)
					(thickness 0.15)
				)
			)
		)
		(property "Voltage" "16V"
			(at 0 0 270)
			(unlocked yes)
			(layer "F.Fab")
			(hide yes)
			(effects
				(font
					(size 1 1)
					(thickness 0.15)
				)
			)
		)
		(property "Dielectric" ""
			(at 0 0 270)
			(unlocked yes)
			(layer "F.Fab")
			(hide yes)
			(effects
				(font
					(size 1 1)
					(thickness 0.15)
				)
			)
		)
		(sheetname "/X710-AT2 power/")
		(sheetfile "x710-at2-power.kicad_sch")
		(attr smd)
		(fp_line
			(start -0.15 0.55)
			(end 0.15 0.55)
			(stroke
				(width 0.15)
				(type solid)
			)
			(layer "F.SilkS")
		)
		(fp_line
			(start -0.15 -0.55)
			(end 0.15 -0.55)
			(stroke
				(width 0.15)
				(type solid)
			)
			(layer "F.SilkS")
		)
		(fp_rect
			(start -1.25 -0.65)
			(end 1.25 0.65)
			(stroke
				(width 0.05)
				(type solid)
			)
			(fill no)
			(layer "F.CrtYd")
		)
		(fp_rect
			(start -0.8 -0.45)
			(end 0.8 0.45)
			(stroke
				(width 0.15)
				(type solid)
			)
			(fill no)
			(layer "F.Fab")
		)
		(fp_text user "License: Apache-2.0"
			(at -1.682 5.895 270)
			(layer "F.Fab")
			(effects
				(font
					(size 0.7 0.7)
					(thickness 0.15)
				)
				(justify left bottom)
			)
		)
		(fp_text user "${REFERENCE}"
			(at -1.682 3.895 270)
			(layer "F.Fab")
			(effects
				(font
					(size 0.7 0.7)
					(thickness 0.15)
				)
				(justify left bottom)
			)
		)
		(fp_text user "Author: Antmicro"
			(at -1.682 4.894 270)
			(layer "F.Fab")
			(effects
				(font
					(size 0.7 0.7)
					(thickness 0.15)
				)
				(justify left bottom)
			)
		)
		(pad "1" smd roundrect
			(at -0.7 0 270)
			(size 0.8 1.1)
			(layers "F.Cu" "F.Mask" "F.Paste")
			(roundrect_rratio 0.2)
			(net 23 "GND")
			(pintype "passive")
		)
		(pad "2" smd roundrect
			(at 0.7 0 270)
			(size 0.8 1.1)
			(layers "F.Cu" "F.Mask" "F.Paste")
			(roundrect_rratio 0.2)
			(net 136 "+1V0")
			(pintype "passive")
		)
	)
	(footprint "antmicro-footprints:R_0402_1005Metric"
		(layer "F.Cu")
		(at 136.149999 110.149999 180)
		(descr "Resistor SMD 0402")
		(tags "resistor SMD 0402")
		(property "Reference" "R100"
			(at -16.549997 -17.25 180)
			(layer "F.SilkS")
			(effects
				(font
					(size 0.7 0.7)
					(thickness 0.15)
				)
			)
		)
		(property "Value" "R_16k_0402"
			(at -1.011843 1.772047 180)
			(layer "F.Fab")
			(effects
				(font
					(size 0.7 0.7)
					(thickness 0.15)
				)
				(justify left bottom)
			)
		)
		(property "Datasheet" "https://www.bourns.com/docs/product-datasheets/cr.pdf"
			(at 0 0 180)
			(layer "F.Fab")
			(hide yes)
			(effects
				(font
					(size 1.27 1.27)
					(thickness 0.15)
				)
			)
		)
		(property "Description" "SMD Chip Resistor"
			(at 0 0 180)
			(layer "F.Fab")
			(hide yes)
			(effects
				(font
					(size 1.27 1.27)
					(thickness 0.15)
				)
			)
		)
		(property "MPN" "CR0402-FX-1602GLF"
			(at 0 0 180)
			(unlocked yes)
			(layer "F.Fab")
			(hide yes)
			(effects
				(font
					(size 1 1)
					(thickness 0.15)
				)
			)
		)
		(property "Manufacturer" "Bourns"
			(at 0 0 180)
			(unlocked yes)
			(layer "F.Fab")
			(hide yes)
			(effects
				(font
					(size 1 1)
					(thickness 0.15)
				)
			)
		)
		(property "License" "Apache-2.0"
			(at 0 0 180)
			(unlocked yes)
			(layer "F.Fab")
			(hide yes)
			(effects
				(font
					(size 1 1)
					(thickness 0.15)
				)
			)
		)
		(property "Author" "Antmicro"
			(at 0 0 180)
			(unlocked yes)
			(layer "F.Fab")
			(hide yes)
			(effects
				(font
					(size 1 1)
					(thickness 0.15)
				)
			)
		)
		(property "Val" "16k"
			(at 0 0 180)
			(unlocked yes)
			(layer "F.Fab")
			(hide yes)
			(effects
				(font
					(size 1 1)
					(thickness 0.15)
				)
			)
		)
		(property "Tolerance" "1%"
			(at 0 0 180)
			(unlocked yes)
			(layer "F.Fab")
			(hide yes)
			(effects
				(font
					(size 1 1)
					(thickness 0.15)
				)
			)
		)
		(sheetname "/X710 DCDC converters/")
		(sheetfile "DCDC_converters_X710.kicad_sch")
		(attr smd)
		(fp_rect
			(start -0.925 -0.47)
			(end 0.925 0.47)
			(stroke
				(width 0.05)
				(type default)
			)
			(fill no)
			(layer "F.CrtYd")
		)
		(fp_rect
			(start -0.5 -0.25)
			(end 0.5 0.25)
			(stroke
				(width 0.15)
				(type solid)
			)
			(fill no)
			(layer "F.Fab")
		)
		(fp_text user "${REFERENCE}"
			(at -0.95 3.168 180)
			(layer "F.Fab")
			(effects
				(font
					(size 0.7 0.7)
					(thickness 0.15)
				)
				(justify left bottom)
			)
		)
		(fp_text user "License: Apache-2.0"
			(at -0.95 5.169 180)
			(layer "F.Fab")
			(effects
				(font
					(size 0.7 0.7)
					(thickness 0.15)
				)
				(justify left bottom)
			)
		)
		(fp_text user "Author: Antmicro"
			(at -0.95 4.169 180)
			(layer "F.Fab")
			(effects
				(font
					(size 0.7 0.7)
					(thickness 0.15)
				)
				(justify left bottom)
			)
		)
		(pad "1" smd roundrect
			(at -0.48 0 180)
			(size 0.59 0.64)
			(layers "F.Cu" "F.Mask" "F.Paste")
			(roundrect_rratio 0.25)
			(net 336 "/X710 DCDC converters/VCCD_FB")
			(pintype "passive")
		)
		(pad "2" smd roundrect
			(at 0.48 0 180)
			(size 0.59 0.64)
			(layers "F.Cu" "F.Mask" "F.Paste")
			(roundrect_rratio 0.25)
			(net 335 "/X710 DCDC converters/+VCCD_OUT")
			(pintype "passive")
		)
	)
	(footprint "antmicro-footprints:C_0402_1005Metric"
		(layer "F.Cu")
		(at 134.2 60.4)
		(descr "Capacitor SMD 0402")
		(tags "capacitor SMD 0402")
		(property "Reference" "C323"
			(at -3.8 0.4 0)
			(layer "F.SilkS")
			(effects
				(font
					(size 0.7 0.7)
					(thickness 0.15)
				)
				(justify left bottom)
			)
		)
		(property "Value" "C_1u_25V_0402"
			(at -1.022927 2.155213 0)
			(layer "F.Fab")
			(effects
				(font
					(size 0.7 0.7)
					(thickness 0.15)
				)
				(justify left bottom)
			)
		)
		(property "Datasheet" "https://www.murata.com/products/productdetail?partno=GRM155R61E105KE11%23"
			(at 0 0 0)
			(layer "F.Fab")
			(hide yes)
			(effects
				(font
					(size 1.27 1.27)
					(thickness 0.15)
				)
			)
		)
		(property "Description" "SMD Multilayer Ceramic Capacitor, 1 µF, 25 V, 0402 [1005 Metric], ± 10%, X5R, GRM Series"
			(at 0 0 0)
			(layer "F.Fab")
			(hide yes)
			(effects
				(font
					(size 1.27 1.27)
					(thickness 0.15)
				)
			)
		)
		(property "MPN" "GRM155R61E105KE11J"
			(at 0 0 0)
			(unlocked yes)
			(layer "F.Fab")
			(hide yes)
			(effects
				(font
					(size 1 1)
					(thickness 0.15)
				)
			)
		)
		(property "Manufacturer" "Murata"
			(at 0 0 0)
			(unlocked yes)
			(layer "F.Fab")
			(hide yes)
			(effects
				(font
					(size 1 1)
					(thickness 0.15)
				)
			)
		)
		(property "License" "Apache-2.0"
			(at 0 0 0)
			(unlocked yes)
			(layer "F.Fab")
			(hide yes)
			(effects
				(font
					(size 1 1)
					(thickness 0.15)
				)
			)
		)
		(property "Author" "Antmicro"
			(at 0 0 0)
			(unlocked yes)
			(layer "F.Fab")
			(hide yes)
			(effects
				(font
					(size 1 1)
					(thickness 0.15)
				)
			)
		)
		(property "Val" "1u"
			(at 0 0 0)
			(unlocked yes)
			(layer "F.Fab")
			(hide yes)
			(effects
				(font
					(size 1 1)
					(thickness 0.15)
				)
			)
		)
		(property "Voltage" "25V"
			(at 0 0 0)
			(unlocked yes)
			(layer "F.Fab")
			(hide yes)
			(effects
				(font
					(size 1 1)
					(thickness 0.15)
				)
			)
		)
		(property "Dielectric" "X5R"
			(at 0 0 0)
			(unlocked yes)
			(layer "F.Fab")
			(hide yes)
			(effects
				(font
					(size 1 1)
					(thickness 0.15)
				)
			)
		)
		(sheetname "/Power input/")
		(sheetfile "power_input.kicad_sch")
		(attr smd)
		(fp_rect
			(start -0.925 -0.47)
			(end 0.925 0.47)
			(stroke
				(width 0.05)
				(type default)
			)
			(fill no)
			(layer "F.CrtYd")
		)
		(fp_line
			(start -0.494 -0.25)
			(end 0.504 -0.25)
			(stroke
				(width 0.15)
				(type solid)
			)
			(layer "F.Fab")
		)
		(fp_line
			(start -0.494 0.248)
			(end -0.494 -0.25)
			(stroke
				(width 0.15)
				(type solid)
			)
			(layer "F.Fab")
		)
		(fp_line
			(start 0.504 -0.25)
			(end 0.504 0.248)
			(stroke
				(width 0.15)
				(type solid)
			)
			(layer "F.Fab")
		)
		(fp_line
			(start 0.504 0.248)
			(end -0.494 0.248)
			(stroke
				(width 0.15)
				(type solid)
			)
			(layer "F.Fab")
		)
		(fp_text user "Author: Antmicro"
			(at -0.939 3.399 0)
			(layer "F.Fab")
			(effects
				(font
					(size 0.7 0.7)
					(thickness 0.15)
				)
				(justify left bottom)
			)
		)
		(fp_text user "License: Apache-2.0"
			(at -0.939 5.799 0)
			(layer "F.Fab")
			(effects
				(font
					(size 0.7 0.7)
					(thickness 0.15)
				)
				(justify left bottom)
			)
		)
		(fp_text user "${REFERENCE}"
			(at -0.939 4.599 0)
			(layer "F.Fab")
			(effects
				(font
					(size 0.7 0.7)
					(thickness 0.15)
				)
				(justify left bottom)
			)
		)
		(pad "1" smd roundrect
			(at -0.48 0)
			(size 0.59 0.64)
			(layers "F.Cu" "F.Mask" "F.Paste")
			(roundrect_rratio 0.25)
			(net 23 "GND")
			(pintype "passive")
		)
		(pad "2" smd roundrect
			(at 0.48 0)
			(size 0.59 0.64)
			(layers "F.Cu" "F.Mask" "F.Paste")
			(roundrect_rratio 0.25)
			(net 40 "+5V")
			(pintype "passive")
		)
	)
	(footprint "antmicro-footprints:VQFN-HR-9_2x1.5mm"
		(layer "F.Cu")
		(at 133.950001 95.799998 -90)
		(property "Reference" "U9"
			(at -9.199999 -36.934999 270)
			(layer "F.SilkS")
			(effects
				(font
					(size 0.7 0.7)
					(thickness 0.15)
				)
			)
		)
		(property "Value" "TPS566231P"
			(at -1.65 2.15 270)
			(layer "F.Fab")
			(effects
				(font
					(size 0.7 0.7)
					(thickness 0.15)
				)
				(justify left bottom)
			)
		)
		(property "Datasheet" "https://www.ti.com/lit/ds/symlink/tps566231.pdf"
			(at 0 -0.045 270)
			(layer "F.Fab")
			(effects
				(font
					(size 0.7 0.7)
					(thickness 0.15)
				)
				(justify left bottom)
			)
		)
		(property "Description" "Switching Voltage Regulators 3-V to 18-V, 6-A synchronous buck converter"
			(at -1.45 3.65 270)
			(layer "F.Fab")
			(effects
				(font
					(size 0.7 0.7)
					(thickness 0.15)
				)
				(justify left bottom)
			)
		)
		(property "Manufacturer" "Texas Instruments"
			(at 0 0 270)
			(unlocked yes)
			(layer "F.Fab")
			(hide yes)
			(effects
				(font
					(size 1 1)
					(thickness 0.15)
				)
			)
		)
		(property "MPN" "TPS566231PRQFR"
			(at 0 0 270)
			(unlocked yes)
			(layer "F.Fab")
			(hide yes)
			(effects
				(font
					(size 1 1)
					(thickness 0.15)
				)
			)
		)
		(property "Author" "Antmicro"
			(at 0 0 270)
			(unlocked yes)
			(layer "F.Fab")
			(hide yes)
			(effects
				(font
					(size 1 1)
					(thickness 0.15)
				)
			)
		)
		(property "License" "Apache-2.0"
			(at 0 0 270)
			(unlocked yes)
			(layer "F.Fab")
			(hide yes)
			(effects
				(font
					(size 1 1)
					(thickness 0.15)
				)
			)
		)
		(sheetname "/X710 DCDC converters/")
		(sheetfile "DCDC_converters_X710.kicad_sch")
		(attr smd)
		(fp_line
			(start -1 0.945)
			(end -0.695 0.945)
			(stroke
				(width 0.15)
				(type solid)
			)
			(layer "F.SilkS")
		)
		(fp_line
			(start 1 0.945)
			(end 0.2 0.945)
			(stroke
				(width 0.15)
				(type solid)
			)
			(layer "F.SilkS")
		)
		(fp_line
			(start -1 -0.945)
			(end -0.695 -0.945)
			(stroke
				(width 0.15)
				(type solid)
			)
			(layer "F.SilkS")
		)
		(fp_line
			(start 1 -0.945)
			(end 0.695 -0.945)
			(stroke
				(width 0.15)
				(type solid)
			)
			(layer "F.SilkS")
		)
		(fp_circle
			(center -1.18 -0.77)
			(end -1.13 -0.77)
			(stroke
				(width 0.15)
				(type solid)
			)
			(fill yes)
			(layer "F.SilkS")
		)
		(fp_rect
			(start -1.3 -1.05)
			(end 1.3 1.05)
			(stroke
				(width 0.05)
				(type solid)
			)
			(fill no)
			(layer "F.CrtYd")
		)
		(fp_rect
			(start -1 -0.75)
			(end 1 0.75)
			(stroke
				(width 0.15)
				(type solid)
			)
			(fill no)
			(layer "F.Fab")
		)
		(fp_text user "License: Apache-2.0"
			(at -1.65 5.75 270)
			(layer "F.Fab")
			(effects
				(font
					(size 0.7 0.7)
					(thickness 0.15)
				)
				(justify left bottom)
			)
		)
		(fp_text user "Author: Antmicro"
			(at -1.65 4.55 270)
			(layer "F.Fab")
			(effects
				(font
					(size 0.7 0.7)
					(thickness 0.15)
				)
				(justify left bottom)
			)
		)
		(fp_text user "${REFERENCE}"
			(at -1.65 3.35 270)
			(layer "F.Fab")
			(effects
				(font
					(size 0.7 0.7)
					(thickness 0.15)
				)
				(justify left bottom)
			)
		)
		(pad "1" smd roundrect
			(at -0.925 -0.5 270)
			(size 0.55 0.25)
			(layers "F.Cu" "F.Mask" "F.Paste")
			(roundrect_rratio 0.125)
			(net 80 "/X710 DCDC converters/3V3_VCC")
			(pinfunction "V_{CC}")
			(pintype "passive")
		)
		(pad "2" smd roundrect
			(at -0.925 0 270)
			(size 0.55 0.25)
			(layers "F.Cu" "F.Mask" "F.Paste")
			(roundrect_rratio 0.125)
			(net 333 "/X710 DCDC converters/3V3_FB")
			(pinfunction "FB")
			(pintype "input")
		)
		(pad "3" smd roundrect
			(at -0.925 0.5 270)
			(size 0.55 0.25)
			(layers "F.Cu" "F.Mask" "F.Paste")
			(roundrect_rratio 0.125)
			(net 356 "/TB Controller - Power/0P9_BUFFERED")
			(pinfunction "EN")
			(pintype "input")
		)
		(pad "4" smd roundrect
			(at -0.25 0.45 270)
			(size 0.25 1)
			(layers "F.Cu" "F.Mask" "F.Paste")
			(roundrect_rratio 0.125)
			(net 23 "GND")
			(pinfunction "PGND")
			(pintype "power_in")
		)
		(pad "5" smd roundrect
			(at 0.925 0.5 270)
			(size 0.55 0.25)
			(layers "F.Cu" "F.Mask" "F.Paste")
			(roundrect_rratio 0.125)
			(net 40 "+5V")
			(pinfunction "V_{IN}")
			(pintype "power_in")
		)
		(pad "6" smd roundrect
			(at 0.925 0 270)
			(size 0.55 0.25)
			(layers "F.Cu" "F.Mask" "F.Paste")
			(roundrect_rratio 0.125)
			(net 40 "+5V")
			(pinfunction "V_{IN}")
			(pintype "passive")
		)
		(pad "7" smd roundrect
			(at 0.925 -0.5 270)
			(size 0.55 0.25)
			(layers "F.Cu" "F.Mask" "F.Paste")
			(roundrect_rratio 0.125)
			(net 118 "/X710 DCDC converters/3V3_BST")
			(pinfunction "BST")
			(pintype "passive")
		)
		(pad "8" smd roundrect
			(at 0.25 -0.3 270)
			(size 0.25 1.3)
			(layers "F.Cu" "F.Mask" "F.Paste")
			(roundrect_rratio 0.125)
			(net 117 "/X710 DCDC converters/3V3_SW")
			(pinfunction "SW")
			(pintype "power_out")
		)
		(pad "9" smd roundrect
			(at -0.25 -0.675 270)
			(size 0.25 0.55)
			(layers "F.Cu" "F.Mask" "F.Paste")
			(roundrect_rratio 0.125)
			(net 378 "/X710 DCDC converters/3V3_PG")
			(pinfunction "PG")
			(pintype "passive")
		)
	)
	(footprint "antmicro-footprints:R_0402_1005Metric"
		(layer "F.Cu")
		(at 158.105 65.174999 -90)
		(descr "Resistor SMD 0402")
		(tags "resistor SMD 0402")
		(property "Reference" "R156"
			(at -2.374999 -0.095001 270)
			(layer "F.SilkS")
			(effects
				(font
					(size 0.7 0.7)
					(thickness 0.15)
				)
			)
		)
		(property "Value" "R_100k_0402"
			(at -1.011843 1.772047 270)
			(layer "F.Fab")
			(effects
				(font
					(size 0.7 0.7)
					(thickness 0.15)
				)
				(justify left bottom)
			)
		)
		(property "Datasheet" "https://www.bourns.com/docs/product-datasheets/cr.pdf"
			(at 0 0 270)
			(layer "F.Fab")
			(hide yes)
			(effects
				(font
					(size 1.27 1.27)
					(thickness 0.15)
				)
			)
		)
		(property "Description" "SMD Chip Resistor, 100 kohm, ± 1%, 62.5 mW, 0402 [1005 Metric], Thick Film, General Purpose"
			(at 0 0 270)
			(layer "F.Fab")
			(hide yes)
			(effects
				(font
					(size 1.27 1.27)
					(thickness 0.15)
				)
			)
		)
		(property "MPN" "CR0402-FX-1003GLF"
			(at 0 0 270)
			(unlocked yes)
			(layer "F.Fab")
			(hide yes)
			(effects
				(font
					(size 1 1)
					(thickness 0.15)
				)
			)
		)
		(property "Manufacturer" "Bourns"
			(at 0 0 270)
			(unlocked yes)
			(layer "F.Fab")
			(hide yes)
			(effects
				(font
					(size 1 1)
					(thickness 0.15)
				)
			)
		)
		(property "License" "Apache-2.0"
			(at 0 0 270)
			(unlocked yes)
			(layer "F.Fab")
			(hide yes)
			(effects
				(font
					(size 1 1)
					(thickness 0.15)
				)
			)
		)
		(property "Author" "Antmicro"
			(at 0 0 270)
			(unlocked yes)
			(layer "F.Fab")
			(hide yes)
			(effects
				(font
					(size 1 1)
					(thickness 0.15)
				)
			)
		)
		(property "Val" "100k"
			(at 0 0 270)
			(unlocked yes)
			(layer "F.Fab")
			(hide yes)
			(effects
				(font
					(size 1 1)
					(thickness 0.15)
				)
			)
		)
		(property "Tolerance" "1%"
			(at 0 0 270)
			(unlocked yes)
			(layer "F.Fab")
			(hide yes)
			(effects
				(font
					(size 1 1)
					(thickness 0.15)
				)
			)
		)
		(sheetname "/X710-AT2 Misc/")
		(sheetfile "x710-at2-mics.kicad_sch")
		(attr smd)
		(fp_rect
			(start -0.925 -0.47)
			(end 0.925 0.47)
			(stroke
				(width 0.05)
				(type default)
			)
			(fill no)
			(layer "F.CrtYd")
		)
		(fp_rect
			(start -0.5 -0.25)
			(end 0.5 0.25)
			(stroke
				(width 0.15)
				(type solid)
			)
			(fill no)
			(layer "F.Fab")
		)
		(fp_text user "${REFERENCE}"
			(at -0.95 3.168 270)
			(layer "F.Fab")
			(effects
				(font
					(size 0.7 0.7)
					(thickness 0.15)
				)
				(justify left bottom)
			)
		)
		(fp_text user "License: Apache-2.0"
			(at -0.95 5.169 270)
			(layer "F.Fab")
			(effects
				(font
					(size 0.7 0.7)
					(thickness 0.15)
				)
				(justify left bottom)
			)
		)
		(fp_text user "Author: Antmicro"
			(at -0.95 4.169 270)
			(layer "F.Fab")
			(effects
				(font
					(size 0.7 0.7)
					(thickness 0.15)
				)
				(justify left bottom)
			)
		)
		(pad "1" smd roundrect
			(at -0.48 0 270)
			(size 0.59 0.64)
			(layers "F.Cu" "F.Mask" "F.Paste")
			(roundrect_rratio 0.25)
			(net 140 "/X710-AT2 Misc/NCSI.TXD_0")
			(pintype "passive")
		)
		(pad "2" smd roundrect
			(at 0.48 0 270)
			(size 0.59 0.64)
			(layers "F.Cu" "F.Mask" "F.Paste")
			(roundrect_rratio 0.25)
			(net 7 "+3V3")
			(pintype "passive")
		)
	)
	(footprint "antmicro-footprints:R_0402_1005Metric"
		(layer "F.Cu")
		(at 136.15 108.15 180)
		(descr "Resistor SMD 0402")
		(tags "resistor SMD 0402")
		(property "Reference" "R88"
			(at -16.549997 -17.25 180)
			(layer "F.SilkS")
			(effects
				(font
					(size 0.7 0.7)
					(thickness 0.15)
				)
			)
		)
		(property "Value" "R_100k_0402"
			(at -1.011843 1.772047 180)
			(layer "F.Fab")
			(effects
				(font
					(size 0.7 0.7)
					(thickness 0.15)
				)
				(justify left bottom)
			)
		)
		(property "Datasheet" "https://www.bourns.com/docs/product-datasheets/cr.pdf"
			(at 0 0 180)
			(layer "F.Fab")
			(hide yes)
			(effects
				(font
					(size 1.27 1.27)
					(thickness 0.15)
				)
			)
		)
		(property "Description" "SMD Chip Resistor, 100 kohm, ± 1%, 62.5 mW, 0402 [1005 Metric], Thick Film, General Purpose"
			(at 0 0 180)
			(layer "F.Fab")
			(hide yes)
			(effects
				(font
					(size 1.27 1.27)
					(thickness 0.15)
				)
			)
		)
		(property "MPN" "CR0402-FX-1003GLF"
			(at 0 0 180)
			(unlocked yes)
			(layer "F.Fab")
			(hide yes)
			(effects
				(font
					(size 1 1)
					(thickness 0.15)
				)
			)
		)
		(property "Manufacturer" "Bourns"
			(at 0 0 180)
			(unlocked yes)
			(layer "F.Fab")
			(hide yes)
			(effects
				(font
					(size 1 1)
					(thickness 0.15)
				)
			)
		)
		(property "License" "Apache-2.0"
			(at 0 0 180)
			(unlocked yes)
			(layer "F.Fab")
			(hide yes)
			(effects
				(font
					(size 1 1)
					(thickness 0.15)
				)
			)
		)
		(property "Author" "Antmicro"
			(at 0 0 180)
			(unlocked yes)
			(layer "F.Fab")
			(hide yes)
			(effects
				(font
					(size 1 1)
					(thickness 0.15)
				)
			)
		)
		(property "Val" "100k"
			(at 0 0 180)
			(unlocked yes)
			(layer "F.Fab")
			(hide yes)
			(effects
				(font
					(size 1 1)
					(thickness 0.15)
				)
			)
		)
		(property "Tolerance" "1%"
			(at 0 0 180)
			(unlocked yes)
			(layer "F.Fab")
			(hide yes)
			(effects
				(font
					(size 1 1)
					(thickness 0.15)
				)
			)
		)
		(sheetname "/X710 DCDC converters/")
		(sheetfile "DCDC_converters_X710.kicad_sch")
		(attr smd)
		(fp_rect
			(start -0.925 -0.47)
			(end 0.925 0.47)
			(stroke
				(width 0.05)
				(type default)
			)
			(fill no)
			(layer "F.CrtYd")
		)
		(fp_rect
			(start -0.5 -0.25)
			(end 0.5 0.25)
			(stroke
				(width 0.15)
				(type solid)
			)
			(fill no)
			(layer "F.Fab")
		)
		(fp_text user "Author: Antmicro"
			(at -0.95 4.169 180)
			(layer "F.Fab")
			(effects
				(font
					(size 0.7 0.7)
					(thickness 0.15)
				)
				(justify left bottom)
			)
		)
		(fp_text user "${REFERENCE}"
			(at -0.95 3.168 180)
			(layer "F.Fab")
			(effects
				(font
					(size 0.7 0.7)
					(thickness 0.15)
				)
				(justify left bottom)
			)
		)
		(fp_text user "License: Apache-2.0"
			(at -0.95 5.169 180)
			(layer "F.Fab")
			(effects
				(font
					(size 0.7 0.7)
					(thickness 0.15)
				)
				(justify left bottom)
			)
		)
		(pad "1" smd roundrect
			(at -0.48 0 180)
			(size 0.59 0.64)
			(layers "F.Cu" "F.Mask" "F.Paste")
			(roundrect_rratio 0.25)
			(net 379 "/X710 DCDC converters/VCCD_PG")
			(pintype "passive")
		)
		(pad "2" smd roundrect
			(at 0.48 0 180)
			(size 0.59 0.64)
			(layers "F.Cu" "F.Mask" "F.Paste")
			(roundrect_rratio 0.25)
			(net 83 "/X710 DCDC converters/VCCD_VCC")
			(pintype "passive")
		)
	)
	(footprint "antmicro-footprints:C_0603_1608Metric_EIA"
		(layer "F.Cu")
		(at 135.905001 99.774999 -90)
		(descr "Capacitor SMD 0603, IPC-7351 Density Level A")
		(tags "Capacitor 0603")
		(property "Reference" "C242"
			(at -9.274999 -37.344999 270)
			(layer "F.SilkS")
			(effects
				(font
					(size 0.7 0.7)
					(thickness 0.15)
				)
			)
		)
		(property "Value" "C_22u_16V_0603"
			(at -1.42757 1.770288 270)
			(layer "F.Fab")
			(effects
				(font
					(size 0.7 0.7)
					(thickness 0.15)
				)
				(justify left bottom)
			)
		)
		(property "Datasheet" "https://product.samsungsem.com/mlcc/CL10A226MO7JZN.do"
			(at 0 0 270)
			(layer "F.Fab")
			(hide yes)
			(effects
				(font
					(size 1.27 1.27)
					(thickness 0.15)
				)
			)
		)
		(property "Description" "SMD Multilayer Ceramic Capacitor"
			(at 0 0 270)
			(layer "F.Fab")
			(hide yes)
			(effects
				(font
					(size 1.27 1.27)
					(thickness 0.15)
				)
			)
		)
		(property "MPN" "CL10A226MO7JZNC"
			(at 0 0 270)
			(unlocked yes)
			(layer "F.Fab")
			(hide yes)
			(effects
				(font
					(size 1 1)
					(thickness 0.15)
				)
			)
		)
		(property "Manufacturer" "Samsung Electro-Mechanics"
			(at 0 0 270)
			(unlocked yes)
			(layer "F.Fab")
			(hide yes)
			(effects
				(font
					(size 1 1)
					(thickness 0.15)
				)
			)
		)
		(property "License" "Apache-2.0"
			(at 0 0 270)
			(unlocked yes)
			(layer "F.Fab")
			(hide yes)
			(effects
				(font
					(size 1 1)
					(thickness 0.15)
				)
			)
		)
		(property "Author" "Antmicro"
			(at 0 0 270)
			(unlocked yes)
			(layer "F.Fab")
			(hide yes)
			(effects
				(font
					(size 1 1)
					(thickness 0.15)
				)
			)
		)
		(property "Val" "22u"
			(at 0 0 270)
			(unlocked yes)
			(layer "F.Fab")
			(hide yes)
			(effects
				(font
					(size 1 1)
					(thickness 0.15)
				)
			)
		)
		(property "Voltage" "16V"
			(at 0 0 270)
			(unlocked yes)
			(layer "F.Fab")
			(hide yes)
			(effects
				(font
					(size 1 1)
					(thickness 0.15)
				)
			)
		)
		(property "Dielectric" ""
			(at 0 0 270)
			(unlocked yes)
			(layer "F.Fab")
			(hide yes)
			(effects
				(font
					(size 1 1)
					(thickness 0.15)
				)
			)
		)
		(sheetname "/X710-AT2 power/")
		(sheetfile "x710-at2-power.kicad_sch")
		(attr smd)
		(fp_line
			(start -0.15 0.55)
			(end 0.15 0.55)
			(stroke
				(width 0.15)
				(type solid)
			)
			(layer "F.SilkS")
		)
		(fp_line
			(start -0.15 -0.55)
			(end 0.15 -0.55)
			(stroke
				(width 0.15)
				(type solid)
			)
			(layer "F.SilkS")
		)
		(fp_rect
			(start -1.25 -0.65)
			(end 1.25 0.65)
			(stroke
				(width 0.05)
				(type solid)
			)
			(fill no)
			(layer "F.CrtYd")
		)
		(fp_rect
			(start -0.8 -0.45)
			(end 0.8 0.45)
			(stroke
				(width 0.15)
				(type solid)
			)
			(fill no)
			(layer "F.Fab")
		)
		(fp_text user "License: Apache-2.0"
			(at -1.682 5.895 270)
			(layer "F.Fab")
			(effects
				(font
					(size 0.7 0.7)
					(thickness 0.15)
				)
				(justify left bottom)
			)
		)
		(fp_text user "Author: Antmicro"
			(at -1.682 4.894 270)
			(layer "F.Fab")
			(effects
				(font
					(size 0.7 0.7)
					(thickness 0.15)
				)
				(justify left bottom)
			)
		)
		(fp_text user "${REFERENCE}"
			(at -1.682 3.895 270)
			(layer "F.Fab")
			(effects
				(font
					(size 0.7 0.7)
					(thickness 0.15)
				)
				(justify left bottom)
			)
		)
		(pad "1" smd roundrect
			(at -0.7 0 270)
			(size 0.8 1.1)
			(layers "F.Cu" "F.Mask" "F.Paste")
			(roundrect_rratio 0.2)
			(net 23 "GND")
			(pintype "passive")
		)
		(pad "2" smd roundrect
			(at 0.7 0 270)
			(size 0.8 1.1)
			(layers "F.Cu" "F.Mask" "F.Paste")
			(roundrect_rratio 0.2)
			(net 9 "VCCD")
			(pintype "passive")
		)
	)
	(footprint "antmicro-footprints:C_0402_1005Metric"
		(layer "F.Cu")
		(at 136.85 131.1 90)
		(descr "Capacitor SMD 0402")
		(tags "capacitor SMD 0402")
		(property "Reference" "C101"
			(at -0.170996 7.15 90)
			(layer "F.SilkS")
			(effects
				(font
					(size 0.7 0.7)
					(thickness 0.15)
				)
				(justify left bottom)
			)
		)
		(property "Value" "C_10u_0402"
			(at -1.022927 2.155213 90)
			(layer "F.Fab")
			(effects
				(font
					(size 0.7 0.7)
					(thickness 0.15)
				)
				(justify left bottom)
			)
		)
		(property "Datasheet" "https://www.yageo.com/en/Chart/Download/pdf/CC0402MRX5R5BB106"
			(at 0 0 90)
			(layer "F.Fab")
			(hide yes)
			(effects
				(font
					(size 1.27 1.27)
					(thickness 0.15)
				)
			)
		)
		(property "Description" "SMD Multilayer Ceramic Capacitor, 10 µF, 6.3 V, 0402 [1005 Metric], ± 20%, X5R, CC Series"
			(at 0 0 90)
			(layer "F.Fab")
			(hide yes)
			(effects
				(font
					(size 1.27 1.27)
					(thickness 0.15)
				)
			)
		)
		(property "MPN" "CC0402MRX5R5BB106"
			(at 0 0 90)
			(unlocked yes)
			(layer "F.Fab")
			(hide yes)
			(effects
				(font
					(size 1 1)
					(thickness 0.15)
				)
			)
		)
		(property "Manufacturer" "YAGEO"
			(at 0 0 90)
			(unlocked yes)
			(layer "F.Fab")
			(hide yes)
			(effects
				(font
					(size 1 1)
					(thickness 0.15)
				)
			)
		)
		(property "License" "Apache-2.0"
			(at 0 0 90)
			(unlocked yes)
			(layer "F.Fab")
			(hide yes)
			(effects
				(font
					(size 1 1)
					(thickness 0.15)
				)
			)
		)
		(property "Val" "10u"
			(at 0 0 90)
			(unlocked yes)
			(layer "F.Fab")
			(hide yes)
			(effects
				(font
					(size 1 1)
					(thickness 0.15)
				)
			)
		)
		(property "Voltage" ""
			(at 0 0 90)
			(unlocked yes)
			(layer "F.Fab")
			(hide yes)
			(effects
				(font
					(size 1 1)
					(thickness 0.15)
				)
			)
		)
		(property "Dielectric" ""
			(at 0 0 90)
			(unlocked yes)
			(layer "F.Fab")
			(hide yes)
			(effects
				(font
					(size 1 1)
					(thickness 0.15)
				)
			)
		)
		(property "Author" "Antmicro"
			(at 0 0 90)
			(unlocked yes)
			(layer "F.Fab")
			(hide yes)
			(effects
				(font
					(size 1 1)
					(thickness 0.15)
				)
			)
		)
		(sheetname "/TB Controller - Power/")
		(sheetfile "tb-power.kicad_sch")
		(attr smd)
		(fp_rect
			(start -0.925 -0.47)
			(end 0.925 0.47)
			(stroke
				(width 0.05)
				(type default)
			)
			(fill no)
			(layer "F.CrtYd")
		)
		(fp_line
			(start 0.504 -0.25)
			(end 0.504 0.248)
			(stroke
				(width 0.15)
				(type solid)
			)
			(layer "F.Fab")
		)
		(fp_line
			(start -0.494 -0.25)
			(end 0.504 -0.25)
			(stroke
				(width 0.15)
				(type solid)
			)
			(layer "F.Fab")
		)
		(fp_line
			(start 0.504 0.248)
			(end -0.494 0.248)
			(stroke
				(width 0.15)
				(type solid)
			)
			(layer "F.Fab")
		)
		(fp_line
			(start -0.494 0.248)
			(end -0.494 -0.25)
			(stroke
				(width 0.15)
				(type solid)
			)
			(layer "F.Fab")
		)
		(fp_text user "License: Apache-2.0"
			(at -0.939 5.799 90)
			(layer "F.Fab")
			(effects
				(font
					(size 0.7 0.7)
					(thickness 0.15)
				)
				(justify left bottom)
			)
		)
		(fp_text user "Author: Antmicro"
			(at -0.939 3.399 90)
			(layer "F.Fab")
			(effects
				(font
					(size 0.7 0.7)
					(thickness 0.15)
				)
				(justify left bottom)
			)
		)
		(fp_text user "${REFERENCE}"
			(at -0.939 4.599 90)
			(layer "F.Fab")
			(effects
				(font
					(size 0.7 0.7)
					(thickness 0.15)
				)
				(justify left bottom)
			)
		)
		(pad "1" smd roundrect
			(at -0.48 0 90)
			(size 0.59 0.64)
			(layers "F.Cu" "F.Mask" "F.Paste")
			(roundrect_rratio 0.25)
			(net 23 "GND")
			(pintype "passive")
		)
		(pad "2" smd roundrect
			(at 0.48 0 90)
			(size 0.59 0.64)
			(layers "F.Cu" "F.Mask" "F.Paste")
			(roundrect_rratio 0.25)
			(net 57 "+3V3_TB")
			(pintype "passive")
		)
	)
	(footprint "antmicro-footprints:C_0402_1005Metric"
		(layer "F.Cu")
		(at 124.75 134.75 90)
		(descr "Capacitor SMD 0402")
		(tags "capacitor SMD 0402")
		(property "Reference" "C33"
			(at -3.05 0.45 90)
			(layer "F.SilkS")
			(effects
				(font
					(size 0.7 0.7)
					(thickness 0.15)
				)
				(justify left bottom)
			)
		)
		(property "Value" "C_220n_0402"
			(at -1.022927 2.155213 90)
			(layer "F.Fab")
			(effects
				(font
					(size 0.7 0.7)
					(thickness 0.15)
				)
				(justify left bottom)
			)
		)
		(property "Datasheet" "https://www.yageo.com/en/Chart/Download/pdf/CC0402KRX5R6BB224"
			(at 0 0 90)
			(layer "F.Fab")
			(hide yes)
			(effects
				(font
					(size 1.27 1.27)
					(thickness 0.15)
				)
			)
		)
		(property "Description" "SMD Multilayer Ceramic Capacitor, 0.22 µF, 10 V, 0402 [1005 Metric], ± 10%, X5R, CC Series"
			(at 0 0 90)
			(layer "F.Fab")
			(hide yes)
			(effects
				(font
					(size 1.27 1.27)
					(thickness 0.15)
				)
			)
		)
		(property "MPN" "CC0402KRX5R6BB224"
			(at 0 0 90)
			(unlocked yes)
			(layer "F.Fab")
			(hide yes)
			(effects
				(font
					(size 1 1)
					(thickness 0.15)
				)
			)
		)
		(property "Manufacturer" "YAGEO"
			(at 0 0 90)
			(unlocked yes)
			(layer "F.Fab")
			(hide yes)
			(effects
				(font
					(size 1 1)
					(thickness 0.15)
				)
			)
		)
		(property "License" "Apache-2.0"
			(at 0 0 90)
			(unlocked yes)
			(layer "F.Fab")
			(hide yes)
			(effects
				(font
					(size 1 1)
					(thickness 0.15)
				)
			)
		)
		(property "Author" "Antmicro"
			(at 0 0 90)
			(unlocked yes)
			(layer "F.Fab")
			(hide yes)
			(effects
				(font
					(size 1 1)
					(thickness 0.15)
				)
			)
		)
		(property "Val" "220n"
			(at 0 0 90)
			(unlocked yes)
			(layer "F.Fab")
			(hide yes)
			(effects
				(font
					(size 1 1)
					(thickness 0.15)
				)
			)
		)
		(property "Voltage" ""
			(at 0 0 90)
			(unlocked yes)
			(layer "F.Fab")
			(hide yes)
			(effects
				(font
					(size 1 1)
					(thickness 0.15)
				)
			)
		)
		(property "Dielectric" ""
			(at 0 0 90)
			(unlocked yes)
			(layer "F.Fab")
			(hide yes)
			(effects
				(font
					(size 1 1)
					(thickness 0.15)
				)
			)
		)
		(sheetname "/TB Controller/")
		(sheetfile "tb.kicad_sch")
		(attr smd)
		(fp_rect
			(start -0.925 -0.47)
			(end 0.925 0.47)
			(stroke
				(width 0.05)
				(type default)
			)
			(fill no)
			(layer "F.CrtYd")
		)
		(fp_line
			(start 0.504 -0.25)
			(end 0.504 0.248)
			(stroke
				(width 0.15)
				(type solid)
			)
			(layer "F.Fab")
		)
		(fp_line
			(start -0.494 -0.25)
			(end 0.504 -0.25)
			(stroke
				(width 0.15)
				(type solid)
			)
			(layer "F.Fab")
		)
		(fp_line
			(start 0.504 0.248)
			(end -0.494 0.248)
			(stroke
				(width 0.15)
				(type solid)
			)
			(layer "F.Fab")
		)
		(fp_line
			(start -0.494 0.248)
			(end -0.494 -0.25)
			(stroke
				(width 0.15)
				(type solid)
			)
			(layer "F.Fab")
		)
		(fp_text user "Author: Antmicro"
			(at -0.939 3.399 90)
			(layer "F.Fab")
			(effects
				(font
					(size 0.7 0.7)
					(thickness 0.15)
				)
				(justify left bottom)
			)
		)
		(fp_text user "License: Apache-2.0"
			(at -0.939 5.799 90)
			(layer "F.Fab")
			(effects
				(font
					(size 0.7 0.7)
					(thickness 0.15)
				)
				(justify left bottom)
			)
		)
		(fp_text user "${REFERENCE}"
			(at -0.939 4.599 90)
			(layer "F.Fab")
			(effects
				(font
					(size 0.7 0.7)
					(thickness 0.15)
				)
				(justify left bottom)
			)
		)
		(pad "1" smd roundrect
			(at -0.48 0 90)
			(size 0.59 0.64)
			(layers "F.Cu" "F.Mask" "F.Paste")
			(roundrect_rratio 0.25)
			(net 308 "/PD and TB DC-DC/USB3.TX0_P")
			(pintype "passive")
		)
		(pad "2" smd roundrect
			(at 0.48 0 90)
			(size 0.59 0.64)
			(layers "F.Cu" "F.Mask" "F.Paste")
			(roundrect_rratio 0.25)
			(net 167 "/TB Controller/PA_TX0_P")
			(pintype "passive")
		)
	)
	(footprint "antmicro-footprints:R_0402_1005Metric"
		(layer "F.Cu")
		(at 148.4 128.2 -90)
		(descr "Resistor SMD 0402")
		(tags "resistor SMD 0402")
		(property "Reference" "R80"
			(at 3.2 -0.4 270)
			(layer "F.SilkS")
			(effects
				(font
					(size 0.7 0.7)
					(thickness 0.15)
				)
				(justify left bottom)
			)
		)
		(property "Value" "R_3k3_0402"
			(at -1.011843 1.772047 270)
			(layer "F.Fab")
			(effects
				(font
					(size 0.7 0.7)
					(thickness 0.15)
				)
				(justify left bottom)
			)
		)
		(property "Datasheet" "https://www.bourns.com/docs/product-datasheets/cr.pdf"
			(at 0 0 270)
			(layer "F.Fab")
			(hide yes)
			(effects
				(font
					(size 1.27 1.27)
					(thickness 0.15)
				)
			)
		)
		(property "Description" "SMD Chip Resistor, 3.3 kohm, ± 1%, 63 mW, 0402 [1005 Metric], Thick Film, General Purpose"
			(at 0 0 270)
			(layer "F.Fab")
			(hide yes)
			(effects
				(font
					(size 1.27 1.27)
					(thickness 0.15)
				)
			)
		)
		(property "MPN" "CR0402-FX-3301GLF"
			(at 0 0 270)
			(unlocked yes)
			(layer "F.Fab")
			(hide yes)
			(effects
				(font
					(size 1 1)
					(thickness 0.15)
				)
			)
		)
		(property "Manufacturer" "Bourns"
			(at 0 0 270)
			(unlocked yes)
			(layer "F.Fab")
			(hide yes)
			(effects
				(font
					(size 1 1)
					(thickness 0.15)
				)
			)
		)
		(property "License" "Apache-2.0"
			(at 0 0 270)
			(unlocked yes)
			(layer "F.Fab")
			(hide yes)
			(effects
				(font
					(size 1 1)
					(thickness 0.15)
				)
			)
		)
		(property "Val" "3k3"
			(at 0 0 270)
			(unlocked yes)
			(layer "F.Fab")
			(hide yes)
			(effects
				(font
					(size 1 1)
					(thickness 0.15)
				)
			)
		)
		(property "Tolerance" "1%"
			(at 0 0 270)
			(unlocked yes)
			(layer "F.Fab")
			(hide yes)
			(effects
				(font
					(size 1 1)
					(thickness 0.15)
				)
			)
		)
		(property "Author" "Antmicro"
			(at 0 0 270)
			(unlocked yes)
			(layer "F.Fab")
			(hide yes)
			(effects
				(font
					(size 1 1)
					(thickness 0.15)
				)
			)
		)
		(sheetname "/TB flash memory/")
		(sheetfile "flash-memory.kicad_sch")
		(attr smd)
		(fp_rect
			(start -0.925 -0.47)
			(end 0.925 0.47)
			(stroke
				(width 0.05)
				(type default)
			)
			(fill no)
			(layer "F.CrtYd")
		)
		(fp_rect
			(start -0.5 -0.25)
			(end 0.5 0.25)
			(stroke
				(width 0.15)
				(type solid)
			)
			(fill no)
			(layer "F.Fab")
		)
		(fp_text user "License: Apache-2.0"
			(at -0.95 5.169 270)
			(layer "F.Fab")
			(effects
				(font
					(size 0.7 0.7)
					(thickness 0.15)
				)
				(justify left bottom)
			)
		)
		(fp_text user "Author: Antmicro"
			(at -0.95 4.169 270)
			(layer "F.Fab")
			(effects
				(font
					(size 0.7 0.7)
					(thickness 0.15)
				)
				(justify left bottom)
			)
		)
		(fp_text user "${REFERENCE}"
			(at -0.95 3.168 270)
			(layer "F.Fab")
			(effects
				(font
					(size 0.7 0.7)
					(thickness 0.15)
				)
				(justify left bottom)
			)
		)
		(pad "1" smd roundrect
			(at -0.48 0 270)
			(size 0.59 0.64)
			(layers "F.Cu" "F.Mask" "F.Paste")
			(roundrect_rratio 0.25)
			(net 358 "/TB flash memory/FLASH_WP")
			(pintype "passive")
		)
		(pad "2" smd roundrect
			(at 0.48 0 270)
			(size 0.59 0.64)
			(layers "F.Cu" "F.Mask" "F.Paste")
			(roundrect_rratio 0.25)
			(net 57 "+3V3_TB")
			(pintype "passive")
		)
	)
	(footprint "antmicro-footprints:C_0402_1005Metric"
		(layer "F.Cu")
		(at 138 77.75)
		(descr "Capacitor SMD 0402")
		(tags "capacitor SMD 0402")
		(property "Reference" "C272"
			(at -3.8 0.45 0)
			(layer "F.SilkS")
			(effects
				(font
					(size 0.7 0.7)
					(thickness 0.15)
				)
				(justify left bottom)
			)
		)
		(property "Value" "C_220n_16V_0402"
			(at -1.022927 2.155213 0)
			(layer "F.Fab")
			(effects
				(font
					(size 0.7 0.7)
					(thickness 0.15)
				)
				(justify left bottom)
			)
		)
		(property "Datasheet" "https://www.murata.com/products/productdetail?partno=GRM155R71C224KA12%23"
			(at 0 0 0)
			(layer "F.Fab")
			(hide yes)
			(effects
				(font
					(size 1.27 1.27)
					(thickness 0.15)
				)
			)
		)
		(property "Description" "SMD Multilayer Ceramic Capacitor, 0.22 µF, 16 V, 0402 [1005 Metric], ± 10%, X7R, GRM Series"
			(at 0 0 0)
			(layer "F.Fab")
			(hide yes)
			(effects
				(font
					(size 1.27 1.27)
					(thickness 0.15)
				)
			)
		)
		(property "MPN" "GRM155R71C224KA12D"
			(at 0 0 0)
			(unlocked yes)
			(layer "F.Fab")
			(hide yes)
			(effects
				(font
					(size 1 1)
					(thickness 0.15)
				)
			)
		)
		(property "Manufacturer" "Murata"
			(at 0 0 0)
			(unlocked yes)
			(layer "F.Fab")
			(hide yes)
			(effects
				(font
					(size 1 1)
					(thickness 0.15)
				)
			)
		)
		(property "License" "Apache-2.0"
			(at 0 0 0)
			(unlocked yes)
			(layer "F.Fab")
			(hide yes)
			(effects
				(font
					(size 1 1)
					(thickness 0.15)
				)
			)
		)
		(property "Author" "Antmicro"
			(at 0 0 0)
			(unlocked yes)
			(layer "F.Fab")
			(hide yes)
			(effects
				(font
					(size 1 1)
					(thickness 0.15)
				)
			)
		)
		(property "Val" "220n"
			(at 0 0 0)
			(unlocked yes)
			(layer "F.Fab")
			(hide yes)
			(effects
				(font
					(size 1 1)
					(thickness 0.15)
				)
			)
		)
		(property "Voltage" "16V"
			(at 0 0 0)
			(unlocked yes)
			(layer "F.Fab")
			(hide yes)
			(effects
				(font
					(size 1 1)
					(thickness 0.15)
				)
			)
		)
		(property "Dielectric" "X7R"
			(at 0 0 0)
			(unlocked yes)
			(layer "F.Fab")
			(hide yes)
			(effects
				(font
					(size 1 1)
					(thickness 0.15)
				)
			)
		)
		(sheetname "/X710-AT2 PCIe/")
		(sheetfile "x710-at2-pcie.kicad_sch")
		(attr smd)
		(fp_rect
			(start -0.925 -0.47)
			(end 0.925 0.47)
			(stroke
				(width 0.05)
				(type default)
			)
			(fill no)
			(layer "F.CrtYd")
		)
		(fp_line
			(start -0.494 -0.25)
			(end 0.504 -0.25)
			(stroke
				(width 0.15)
				(type solid)
			)
			(layer "F.Fab")
		)
		(fp_line
			(start -0.494 0.248)
			(end -0.494 -0.25)
			(stroke
				(width 0.15)
				(type solid)
			)
			(layer "F.Fab")
		)
		(fp_line
			(start 0.504 -0.25)
			(end 0.504 0.248)
			(stroke
				(width 0.15)
				(type solid)
			)
			(layer "F.Fab")
		)
		(fp_line
			(start 0.504 0.248)
			(end -0.494 0.248)
			(stroke
				(width 0.15)
				(type solid)
			)
			(layer "F.Fab")
		)
		(fp_text user "${REFERENCE}"
			(at -0.939 4.599 0)
			(layer "F.Fab")
			(effects
				(font
					(size 0.7 0.7)
					(thickness 0.15)
				)
				(justify left bottom)
			)
		)
		(fp_text user "Author: Antmicro"
			(at -0.939 3.399 0)
			(layer "F.Fab")
			(effects
				(font
					(size 0.7 0.7)
					(thickness 0.15)
				)
				(justify left bottom)
			)
		)
		(fp_text user "License: Apache-2.0"
			(at -0.939 5.799 0)
			(layer "F.Fab")
			(effects
				(font
					(size 0.7 0.7)
					(thickness 0.15)
				)
				(justify left bottom)
			)
		)
		(pad "1" smd roundrect
			(at -0.48 0)
			(size 0.59 0.64)
			(layers "F.Cu" "F.Mask" "F.Paste")
			(roundrect_rratio 0.25)
			(net 602 "/TB Controller/PCIex4.TX2+")
			(pintype "passive")
		)
		(pad "2" smd roundrect
			(at 0.48 0)
			(size 0.59 0.64)
			(layers "F.Cu" "F.Mask" "F.Paste")
			(roundrect_rratio 0.25)
			(net 31 "/X710-AT2 PCIe/PCIe_{x4}_AC.TX2+")
			(pintype "passive")
		)
	)
	(footprint "antmicro-footprints:C_0402_1005Metric"
		(layer "F.Cu")
		(at 117.8 124 180)
		(descr "Capacitor SMD 0402")
		(tags "capacitor SMD 0402")
		(property "Reference" "C46"
			(at -0.8 -0.2 180)
			(layer "F.SilkS")
			(effects
				(font
					(size 0.7 0.7)
					(thickness 0.15)
				)
				(justify left bottom)
			)
		)
		(property "Value" "C_220n_0402"
			(at -1.022927 2.155213 180)
			(layer "F.Fab")
			(effects
				(font
					(size 0.7 0.7)
					(thickness 0.15)
				)
				(justify left bottom)
			)
		)
		(property "Datasheet" "https://www.yageo.com/en/Chart/Download/pdf/CC0402KRX5R6BB224"
			(at 0 0 180)
			(layer "F.Fab")
			(hide yes)
			(effects
				(font
					(size 1.27 1.27)
					(thickness 0.15)
				)
			)
		)
		(property "Description" "SMD Multilayer Ceramic Capacitor, 0.22 µF, 10 V, 0402 [1005 Metric], ± 10%, X5R, CC Series"
			(at 0 0 180)
			(layer "F.Fab")
			(hide yes)
			(effects
				(font
					(size 1.27 1.27)
					(thickness 0.15)
				)
			)
		)
		(property "MPN" "CC0402KRX5R6BB224"
			(at 0 0 180)
			(unlocked yes)
			(layer "F.Fab")
			(hide yes)
			(effects
				(font
					(size 1 1)
					(thickness 0.15)
				)
			)
		)
		(property "Manufacturer" "YAGEO"
			(at 0 0 180)
			(unlocked yes)
			(layer "F.Fab")
			(hide yes)
			(effects
				(font
					(size 1 1)
					(thickness 0.15)
				)
			)
		)
		(property "License" "Apache-2.0"
			(at 0 0 180)
			(unlocked yes)
			(layer "F.Fab")
			(hide yes)
			(effects
				(font
					(size 1 1)
					(thickness 0.15)
				)
			)
		)
		(property "Val" "220n"
			(at 0 0 180)
			(unlocked yes)
			(layer "F.Fab")
			(hide yes)
			(effects
				(font
					(size 1 1)
					(thickness 0.15)
				)
			)
		)
		(property "Voltage" ""
			(at 0 0 180)
			(unlocked yes)
			(layer "F.Fab")
			(hide yes)
			(effects
				(font
					(size 1 1)
					(thickness 0.15)
				)
			)
		)
		(property "Dielectric" ""
			(at 0 0 180)
			(unlocked yes)
			(layer "F.Fab")
			(hide yes)
			(effects
				(font
					(size 1 1)
					(thickness 0.15)
				)
			)
		)
		(property "Author" "Antmicro"
			(at 0 0 180)
			(unlocked yes)
			(layer "F.Fab")
			(hide yes)
			(effects
				(font
					(size 1 1)
					(thickness 0.15)
				)
			)
		)
		(sheetname "/TB Controller/")
		(sheetfile "tb.kicad_sch")
		(attr smd)
		(fp_rect
			(start -0.925 -0.47)
			(end 0.925 0.47)
			(stroke
				(width 0.05)
				(type default)
			)
			(fill no)
			(layer "F.CrtYd")
		)
		(fp_line
			(start 0.504 0.248)
			(end -0.494 0.248)
			(stroke
				(width 0.15)
				(type solid)
			)
			(layer "F.Fab")
		)
		(fp_line
			(start 0.504 -0.25)
			(end 0.504 0.248)
			(stroke
				(width 0.15)
				(type solid)
			)
			(layer "F.Fab")
		)
		(fp_line
			(start -0.494 0.248)
			(end -0.494 -0.25)
			(stroke
				(width 0.15)
				(type solid)
			)
			(layer "F.Fab")
		)
		(fp_line
			(start -0.494 -0.25)
			(end 0.504 -0.25)
			(stroke
				(width 0.15)
				(type solid)
			)
			(layer "F.Fab")
		)
		(fp_text user "License: Apache-2.0"
			(at -0.939 5.799 180)
			(layer "F.Fab")
			(effects
				(font
					(size 0.7 0.7)
					(thickness 0.15)
				)
				(justify left bottom)
			)
		)
		(fp_text user "Author: Antmicro"
			(at -0.939 3.399 180)
			(layer "F.Fab")
			(effects
				(font
					(size 0.7 0.7)
					(thickness 0.15)
				)
				(justify left bottom)
			)
		)
		(fp_text user "${REFERENCE}"
			(at -0.939 4.599 180)
			(layer "F.Fab")
			(effects
				(font
					(size 0.7 0.7)
					(thickness 0.15)
				)
				(justify left bottom)
			)
		)
		(pad "1" smd roundrect
			(at -0.48 0 180)
			(size 0.59 0.64)
			(layers "F.Cu" "F.Mask" "F.Paste")
			(roundrect_rratio 0.25)
			(net 327 "/TB Controller/TB_PCIE_TX2_P")
			(pintype "passive")
		)
		(pad "2" smd roundrect
			(at 0.48 0 180)
			(size 0.59 0.64)
			(layers "F.Cu" "F.Mask" "F.Paste")
			(roundrect_rratio 0.25)
			(net 319 "/TB Controller/PCIex4.RX2+")
			(pintype "passive")
		)
	)
	(footprint "antmicro-footprints:R_0402_1005Metric"
		(layer "F.Cu")
		(at 140.4 138.55)
		(descr "Resistor SMD 0402")
		(tags "resistor SMD 0402")
		(property "Reference" "R11"
			(at -1.2 -1.75 0)
			(layer "F.SilkS")
			(effects
				(font
					(size 0.7 0.7)
					(thickness 0.15)
				)
				(justify left bottom)
			)
		)
		(property "Value" "R_100k_0402"
			(at -1.011843 1.772047 0)
			(layer "F.Fab")
			(effects
				(font
					(size 0.7 0.7)
					(thickness 0.15)
				)
				(justify left bottom)
			)
		)
		(property "Datasheet" "https://www.bourns.com/docs/product-datasheets/cr.pdf"
			(at 0 0 0)
			(layer "F.Fab")
			(hide yes)
			(effects
				(font
					(size 1.27 1.27)
					(thickness 0.15)
				)
			)
		)
		(property "Description" "SMD Chip Resistor, 100 kohm, ± 1%, 62.5 mW, 0402 [1005 Metric], Thick Film, General Purpose"
			(at 0 0 0)
			(layer "F.Fab")
			(hide yes)
			(effects
				(font
					(size 1.27 1.27)
					(thickness 0.15)
				)
			)
		)
		(property "MPN" "CR0402-FX-1003GLF"
			(at 0 0 0)
			(unlocked yes)
			(layer "F.Fab")
			(hide yes)
			(effects
				(font
					(size 1 1)
					(thickness 0.15)
				)
			)
		)
		(property "Manufacturer" "Bourns"
			(at 0 0 0)
			(unlocked yes)
			(layer "F.Fab")
			(hide yes)
			(effects
				(font
					(size 1 1)
					(thickness 0.15)
				)
			)
		)
		(property "License" "Apache-2.0"
			(at 0 0 0)
			(unlocked yes)
			(layer "F.Fab")
			(hide yes)
			(effects
				(font
					(size 1 1)
					(thickness 0.15)
				)
			)
		)
		(property "Val" "100k"
			(at 0 0 0)
			(unlocked yes)
			(layer "F.Fab")
			(hide yes)
			(effects
				(font
					(size 1 1)
					(thickness 0.15)
				)
			)
		)
		(property "Tolerance" "1%"
			(at 0 0 0)
			(unlocked yes)
			(layer "F.Fab")
			(hide yes)
			(effects
				(font
					(size 1 1)
					(thickness 0.15)
				)
			)
		)
		(property "Author" "Antmicro"
			(at 0 0 0)
			(unlocked yes)
			(layer "F.Fab")
			(hide yes)
			(effects
				(font
					(size 1 1)
					(thickness 0.15)
				)
			)
		)
		(sheetname "/PD and TB DC-DC/")
		(sheetfile "PD_and_TB_DC_DC.kicad_sch")
		(attr smd)
		(fp_rect
			(start -0.925 -0.47)
			(end 0.925 0.47)
			(stroke
				(width 0.05)
				(type default)
			)
			(fill no)
			(layer "F.CrtYd")
		)
		(fp_rect
			(start -0.5 -0.25)
			(end 0.5 0.25)
			(stroke
				(width 0.15)
				(type solid)
			)
			(fill no)
			(layer "F.Fab")
		)
		(fp_text user "${REFERENCE}"
			(at -0.95 3.168 0)
			(layer "F.Fab")
			(effects
				(font
					(size 0.7 0.7)
					(thickness 0.15)
				)
				(justify left bottom)
			)
		)
		(fp_text user "Author: Antmicro"
			(at -0.95 4.169 0)
			(layer "F.Fab")
			(effects
				(font
					(size 0.7 0.7)
					(thickness 0.15)
				)
				(justify left bottom)
			)
		)
		(fp_text user "License: Apache-2.0"
			(at -0.95 5.169 0)
			(layer "F.Fab")
			(effects
				(font
					(size 0.7 0.7)
					(thickness 0.15)
				)
				(justify left bottom)
			)
		)
		(pad "1" smd roundrect
			(at -0.48 0)
			(size 0.59 0.64)
			(layers "F.Cu" "F.Mask" "F.Paste")
			(roundrect_rratio 0.25)
			(net 23 "GND")
			(pintype "passive")
		)
		(pad "2" smd roundrect
			(at 0.48 0)
			(size 0.59 0.64)
			(layers "F.Cu" "F.Mask" "F.Paste")
			(roundrect_rratio 0.25)
			(net 374 "/PD and TB DC-DC/HPD")
			(pintype "passive")
		)
	)
	(footprint "antmicro-footprints:C_0402_1005Metric"
		(layer "F.Cu")
		(at 116.4 102.1 180)
		(descr "Capacitor SMD 0402")
		(tags "capacitor SMD 0402")
		(property "Reference" "C16"
			(at 0 8.1 180)
			(layer "F.SilkS")
			(effects
				(font
					(size 0.7 0.7)
					(thickness 0.15)
				)
			)
		)
		(property "Value" "C_220n_0402"
			(at -1.022927 2.155213 180)
			(layer "F.Fab")
			(effects
				(font
					(size 0.7 0.7)
					(thickness 0.15)
				)
				(justify left bottom)
			)
		)
		(property "Datasheet" "https://www.yageo.com/en/Chart/Download/pdf/CC0402KRX5R6BB224"
			(at 0 0 180)
			(layer "F.Fab")
			(hide yes)
			(effects
				(font
					(size 1.27 1.27)
					(thickness 0.15)
				)
			)
		)
		(property "Description" "SMD Multilayer Ceramic Capacitor, 0.22 µF, 10 V, 0402 [1005 Metric], ± 10%, X5R, CC Series"
			(at 0 0 180)
			(layer "F.Fab")
			(hide yes)
			(effects
				(font
					(size 1.27 1.27)
					(thickness 0.15)
				)
			)
		)
		(property "MPN" "CC0402KRX5R6BB224"
			(at 0 0 180)
			(unlocked yes)
			(layer "F.Fab")
			(hide yes)
			(effects
				(font
					(size 1 1)
					(thickness 0.15)
				)
			)
		)
		(property "Manufacturer" "YAGEO"
			(at 0 0 180)
			(unlocked yes)
			(layer "F.Fab")
			(hide yes)
			(effects
				(font
					(size 1 1)
					(thickness 0.15)
				)
			)
		)
		(property "License" "Apache-2.0"
			(at 0 0 180)
			(unlocked yes)
			(layer "F.Fab")
			(hide yes)
			(effects
				(font
					(size 1 1)
					(thickness 0.15)
				)
			)
		)
		(property "Val" "220n"
			(at 0 0 180)
			(unlocked yes)
			(layer "F.Fab")
			(hide yes)
			(effects
				(font
					(size 1 1)
					(thickness 0.15)
				)
			)
		)
		(property "Voltage" ""
			(at 0 0 180)
			(unlocked yes)
			(layer "F.Fab")
			(hide yes)
			(effects
				(font
					(size 1 1)
					(thickness 0.15)
				)
			)
		)
		(property "Dielectric" ""
			(at 0 0 180)
			(unlocked yes)
			(layer "F.Fab")
			(hide yes)
			(effects
				(font
					(size 1 1)
					(thickness 0.15)
				)
			)
		)
		(property "Author" "Antmicro"
			(at 0 0 180)
			(unlocked yes)
			(layer "F.Fab")
			(hide yes)
			(effects
				(font
					(size 1 1)
					(thickness 0.15)
				)
			)
		)
		(sheetname "/PD and TB DC-DC/")
		(sheetfile "PD_and_TB_DC_DC.kicad_sch")
		(attr smd)
		(fp_rect
			(start -0.925 -0.47)
			(end 0.925 0.47)
			(stroke
				(width 0.05)
				(type default)
			)
			(fill no)
			(layer "F.CrtYd")
		)
		(fp_line
			(start 0.504 0.248)
			(end -0.494 0.248)
			(stroke
				(width 0.15)
				(type solid)
			)
			(layer "F.Fab")
		)
		(fp_line
			(start 0.504 -0.25)
			(end 0.504 0.248)
			(stroke
				(width 0.15)
				(type solid)
			)
			(layer "F.Fab")
		)
		(fp_line
			(start -0.494 0.248)
			(end -0.494 -0.25)
			(stroke
				(width 0.15)
				(type solid)
			)
			(layer "F.Fab")
		)
		(fp_line
			(start -0.494 -0.25)
			(end 0.504 -0.25)
			(stroke
				(width 0.15)
				(type solid)
			)
			(layer "F.Fab")
		)
		(fp_text user "License: Apache-2.0"
			(at -0.939 5.799 180)
			(layer "F.Fab")
			(effects
				(font
					(size 0.7 0.7)
					(thickness 0.15)
				)
				(justify left bottom)
			)
		)
		(fp_text user "Author: Antmicro"
			(at -0.939 3.399 180)
			(layer "F.Fab")
			(effects
				(font
					(size 0.7 0.7)
					(thickness 0.15)
				)
				(justify left bottom)
			)
		)
		(fp_text user "${REFERENCE}"
			(at -0.939 4.599 180)
			(layer "F.Fab")
			(effects
				(font
					(size 0.7 0.7)
					(thickness 0.15)
				)
				(justify left bottom)
			)
		)
		(pad "1" smd roundrect
			(at -0.48 0 180)
			(size 0.59 0.64)
			(layers "F.Cu" "F.Mask" "F.Paste")
			(roundrect_rratio 0.25)
			(net 162 "Net-(U2-BST)")
			(pintype "passive")
		)
		(pad "2" smd roundrect
			(at 0.48 0 180)
			(size 0.59 0.64)
			(layers "F.Cu" "F.Mask" "F.Paste")
			(roundrect_rratio 0.25)
			(net 163 "Net-(U2-SW)")
			(pintype "passive")
		)
	)
	(footprint "antmicro-footprints:LED_0603_1608Metric_G"
		(layer "F.Cu")
		(at 139.5 143.5 90)
		(descr "LED SMD 0603 Green")
		(tags "LED SMD 0603 Green")
		(property "Reference" "D5"
			(at -1 -0.8 90)
			(layer "F.SilkS")
			(effects
				(font
					(size 0.7 0.7)
					(thickness 0.15)
				)
				(justify left bottom)
			)
		)
		(property "Value" "LED_G_0603_KP-1608CGCK"
			(at -0.001 1.599 90)
			(layer "F.Fab")
			(effects
				(font
					(size 0.7 0.7)
					(thickness 0.15)
				)
				(justify left bottom)
			)
		)
		(property "Datasheet" "http://www.kingbright.com/attachments/file/psearch//000/00/00/KP-1608CGCK(Ver.23B).pdf"
			(at 0 0 90)
			(layer "F.Fab")
			(hide yes)
			(effects
				(font
					(size 1.27 1.27)
					(thickness 0.15)
				)
			)
		)
		(property "Description" "LED, Green, SMD, 0603, 20 mA, 2.1 V, 570 nm"
			(at 0 0 90)
			(layer "F.Fab")
			(hide yes)
			(effects
				(font
					(size 1.27 1.27)
					(thickness 0.15)
				)
			)
		)
		(property "MPN" "KP-1608CGCK"
			(at 0 0 90)
			(unlocked yes)
			(layer "F.Fab")
			(hide yes)
			(effects
				(font
					(size 1 1)
					(thickness 0.15)
				)
			)
		)
		(property "Manufacturer" "Kingbright"
			(at 0 0 90)
			(unlocked yes)
			(layer "F.Fab")
			(hide yes)
			(effects
				(font
					(size 1 1)
					(thickness 0.15)
				)
			)
		)
		(property "License" "Apache-2.0"
			(at 0 0 90)
			(unlocked yes)
			(layer "F.Fab")
			(hide yes)
			(effects
				(font
					(size 1 1)
					(thickness 0.15)
				)
			)
		)
		(property "Author" "Antmicro"
			(at 0 0 90)
			(unlocked yes)
			(layer "F.Fab")
			(hide yes)
			(effects
				(font
					(size 1 1)
					(thickness 0.15)
				)
			)
		)
		(property "Color" "Green"
			(at 0 0 90)
			(unlocked yes)
			(layer "F.Fab")
			(hide yes)
			(effects
				(font
					(size 1 1)
					(thickness 0.15)
				)
			)
		)
		(sheetname "/TB Controller - Power/")
		(sheetfile "tb-power.kicad_sch")
		(attr smd)
		(fp_line
			(start 0.22 -0.35)
			(end -0.22 -0.35)
			(stroke
				(width 0.15)
				(type solid)
			)
			(layer "F.SilkS")
		)
		(fp_line
			(start -1.18 -0.319)
			(end -1.18 0.321)
			(stroke
				(width 0.15)
				(type solid)
			)
			(layer "F.SilkS")
		)
		(fp_line
			(start 0.105328 0.001008)
			(end 0.24 0.001)
			(stroke
				(width 0.1)
				(type solid)
			)
			(layer "F.SilkS")
		)
		(fp_line
			(start -0.094672 0.001008)
			(end 0.105328 -0.198992)
			(stroke
				(width 0.1)
				(type solid)
			)
			(layer "F.SilkS")
		)
		(fp_line
			(start -0.094672 0.001008)
			(end -0.24 0.001008)
			(stroke
				(width 0.1)
				(type solid)
			)
			(layer "F.SilkS")
		)
		(fp_line
			(start 0.105328 0.201008)
			(end 0.105328 -0.198992)
			(stroke
				(width 0.1)
				(type solid)
			)
			(layer "F.SilkS")
		)
		(fp_line
			(start 0.105328 0.201008)
			(end -0.094672 0.001008)
			(stroke
				(width 0.1)
				(type solid)
			)
			(layer "F.SilkS")
		)
		(fp_line
			(start -0.094672 0.201008)
			(end -0.094672 -0.198992)
			(stroke
				(width 0.1)
				(type solid)
			)
			(layer "F.SilkS")
		)
		(fp_line
			(start 0.22 0.35)
			(end -0.22 0.35)
			(stroke
				(width 0.15)
				(type solid)
			)
			(layer "F.SilkS")
		)
		(fp_rect
			(start 1.25 0.65)
			(end -1.25 -0.65)
			(stroke
				(width 0.05)
				(type solid)
			)
			(fill no)
			(layer "F.CrtYd")
		)
		(fp_line
			(start 0.201 -0.202)
			(end -0.101 0)
			(stroke
				(width 0.15)
				(type solid)
			)
			(layer "F.Fab")
		)
		(fp_line
			(start -0.199 -0.202)
			(end -0.199 0.1)
			(stroke
				(width 0.15)
				(type solid)
			)
			(layer "F.Fab")
		)
		(fp_line
			(start 0.599 0)
			(end 0.201 0)
			(stroke
				(width 0.15)
				(type solid)
			)
			(layer "F.Fab")
		)
		(fp_line
			(start 0.201 0)
			(end 0.201 -0.202)
			(stroke
				(width 0.15)
				(type solid)
			)
			(layer "F.Fab")
		)
		(fp_line
			(start -0.101 0)
			(end 0.201 0.2)
			(stroke
				(width 0.15)
				(type solid)
			)
			(layer "F.Fab")
		)
		(fp_line
			(start -0.199 0)
			(end -0.597 0)
			(stroke
				(width 0.15)
				(type solid)
			)
			(layer "F.Fab")
		)
		(fp_line
			(start 0.201 0.2)
			(end 0.201 0)
			(stroke
				(width 0.15)
				(type solid)
			)
			(layer "F.Fab")
		)
		(fp_line
			(start -0.199 0.2)
			(end -0.199 0.1)
			(stroke
				(width 0.15)
				(type solid)
			)
			(layer "F.Fab")
		)
		(fp_rect
			(start 0.848 0.4)
			(end -0.85 -0.402)
			(stroke
				(width 0.15)
				(type solid)
			)
			(fill no)
			(layer "F.Fab")
		)
		(fp_text user "Author: Antmicro"
			(at -1.4224 4.799 90)
			(layer "F.Fab")
			(effects
				(font
					(size 0.7 0.7)
					(thickness 0.15)
				)
				(justify left bottom)
			)
		)
		(fp_text user "${REFERENCE}"
			(at -1.4224 5.999 90)
			(layer "F.Fab")
			(effects
				(font
					(size 0.7 0.7)
					(thickness 0.15)
				)
				(justify left bottom)
			)
		)
		(fp_text user "License: Apache-2.0"
			(at -1.4224 3.599 90)
			(layer "F.Fab")
			(effects
				(font
					(size 0.7 0.7)
					(thickness 0.15)
				)
				(justify left bottom)
			)
		)
		(pad "1" smd roundrect
			(at -0.7 0 270)
			(size 0.8 1)
			(layers "F.Cu" "F.Mask" "F.Paste")
			(roundrect_rratio 0.2)
			(net 19 "Net-(D5-C)")
			(pinfunction "C")
			(pintype "passive")
		)
		(pad "2" smd roundrect
			(at 0.7 0 270)
			(size 0.8 1)
			(layers "F.Cu" "F.Mask" "F.Paste")
			(roundrect_rratio 0.2)
			(net 57 "+3V3_TB")
			(pinfunction "A")
			(pintype "passive")
		)
	)
	(footprint "antmicro-footprints:C_0603_1608Metric_EIA"
		(layer "F.Cu")
		(at 129.6 96.25 -90)
		(descr "Capacitor SMD 0603, IPC-7351 Density Level A")
		(tags "Capacitor 0603")
		(property "Reference" "C104"
			(at -9.199999 -38.034999 270)
			(layer "F.SilkS")
			(effects
				(font
					(size 0.7 0.7)
					(thickness 0.15)
				)
			)
		)
		(property "Value" "C_22u_16V_0603"
			(at -1.42757 1.770288 270)
			(layer "F.Fab")
			(effects
				(font
					(size 0.7 0.7)
					(thickness 0.15)
				)
				(justify left bottom)
			)
		)
		(property "Datasheet" "https://product.samsungsem.com/mlcc/CL10A226MO7JZN.do"
			(at 0 0 270)
			(layer "F.Fab")
			(hide yes)
			(effects
				(font
					(size 1.27 1.27)
					(thickness 0.15)
				)
			)
		)
		(property "Description" "SMD Multilayer Ceramic Capacitor"
			(at 0 0 270)
			(layer "F.Fab")
			(hide yes)
			(effects
				(font
					(size 1.27 1.27)
					(thickness 0.15)
				)
			)
		)
		(property "MPN" "CL10A226MO7JZNC"
			(at 0 0 270)
			(unlocked yes)
			(layer "F.Fab")
			(hide yes)
			(effects
				(font
					(size 1 1)
					(thickness 0.15)
				)
			)
		)
		(property "Manufacturer" "Samsung Electro-Mechanics"
			(at 0 0 270)
			(unlocked yes)
			(layer "F.Fab")
			(hide yes)
			(effects
				(font
					(size 1 1)
					(thickness 0.15)
				)
			)
		)
		(property "License" "Apache-2.0"
			(at 0 0 270)
			(unlocked yes)
			(layer "F.Fab")
			(hide yes)
			(effects
				(font
					(size 1 1)
					(thickness 0.15)
				)
			)
		)
		(property "Author" "Antmicro"
			(at 0 0 270)
			(unlocked yes)
			(layer "F.Fab")
			(hide yes)
			(effects
				(font
					(size 1 1)
					(thickness 0.15)
				)
			)
		)
		(property "Val" "22u"
			(at 0 0 270)
			(unlocked yes)
			(layer "F.Fab")
			(hide yes)
			(effects
				(font
					(size 1 1)
					(thickness 0.15)
				)
			)
		)
		(property "Voltage" "16V"
			(at 0 0 270)
			(unlocked yes)
			(layer "F.Fab")
			(hide yes)
			(effects
				(font
					(size 1 1)
					(thickness 0.15)
				)
			)
		)
		(property "Dielectric" ""
			(at 0 0 270)
			(unlocked yes)
			(layer "F.Fab")
			(hide yes)
			(effects
				(font
					(size 1 1)
					(thickness 0.15)
				)
			)
		)
		(sheetname "/X710 DCDC converters/")
		(sheetfile "DCDC_converters_X710.kicad_sch")
		(attr smd)
		(fp_line
			(start -0.15 0.55)
			(end 0.15 0.55)
			(stroke
				(width 0.15)
				(type solid)
			)
			(layer "F.SilkS")
		)
		(fp_line
			(start -0.15 -0.55)
			(end 0.15 -0.55)
			(stroke
				(width 0.15)
				(type solid)
			)
			(layer "F.SilkS")
		)
		(fp_rect
			(start -1.25 -0.65)
			(end 1.25 0.65)
			(stroke
				(width 0.05)
				(type solid)
			)
			(fill no)
			(layer "F.CrtYd")
		)
		(fp_rect
			(start -0.8 -0.45)
			(end 0.8 0.45)
			(stroke
				(width 0.15)
				(type solid)
			)
			(fill no)
			(layer "F.Fab")
		)
		(fp_text user "License: Apache-2.0"
			(at -1.682 5.895 270)
			(layer "F.Fab")
			(effects
				(font
					(size 0.7 0.7)
					(thickness 0.15)
				)
				(justify left bottom)
			)
		)
		(fp_text user "Author: Antmicro"
			(at -1.682 4.894 270)
			(layer "F.Fab")
			(effects
				(font
					(size 0.7 0.7)
					(thickness 0.15)
				)
				(justify left bottom)
			)
		)
		(fp_text user "${REFERENCE}"
			(at -1.682 3.895 270)
			(layer "F.Fab")
			(effects
				(font
					(size 0.7 0.7)
					(thickness 0.15)
				)
				(justify left bottom)
			)
		)
		(pad "1" smd roundrect
			(at -0.7 0 270)
			(size 0.8 1.1)
			(layers "F.Cu" "F.Mask" "F.Paste")
			(roundrect_rratio 0.2)
			(net 23 "GND")
			(pintype "passive")
		)
		(pad "2" smd roundrect
			(at 0.7 0 270)
			(size 0.8 1.1)
			(layers "F.Cu" "F.Mask" "F.Paste")
			(roundrect_rratio 0.2)
			(net 40 "+5V")
			(pintype "passive")
		)
	)
	(footprint "antmicro-footprints:Resonator_SMD_Abracon_ABM8G_3.2x2.5mm"
		(layer "F.Cu")
		(at 130.1 100.9 180)
		(property "Reference" "Y1"
			(at -2.9 -3.1 0)
			(layer "F.SilkS")
			(effects
				(font
					(size 0.7 0.7)
					(thickness 0.15)
				)
			)
		)
		(property "Value" "Resonator_25MHz_ABM8G"
			(at -1.75 2.548 180)
			(layer "F.Fab")
			(effects
				(font
					(size 0.7 0.7)
					(thickness 0.15)
				)
				(justify left bottom)
			)
		)
		(property "Datasheet" "https://abracon.com/Resonators/ABM8G.pdf"
			(at 0 0 180)
			(layer "F.Fab")
			(hide yes)
			(effects
				(font
					(size 1.27 1.27)
					(thickness 0.15)
				)
			)
		)
		(property "Description" "Crystal, 25 MHz, SMD, 3.2mm x 2.5mm, 30 ppm, 18 pF, 20 ppm, ABM8G"
			(at 0 0 180)
			(layer "F.Fab")
			(hide yes)
			(effects
				(font
					(size 1.27 1.27)
					(thickness 0.15)
				)
			)
		)
		(property "MPN" "ABM8G-25.000MHZ-18-D2Y-T3"
			(at 0 0 180)
			(unlocked yes)
			(layer "F.Fab")
			(hide yes)
			(effects
				(font
					(size 1 1)
					(thickness 0.15)
				)
			)
		)
		(property "Manufacturer" "Abracon"
			(at 0 0 180)
			(unlocked yes)
			(layer "F.Fab")
			(hide yes)
			(effects
				(font
					(size 1 1)
					(thickness 0.15)
				)
			)
		)
		(property "License" "Apache-2.0"
			(at 0 0 180)
			(unlocked yes)
			(layer "F.Fab")
			(hide yes)
			(effects
				(font
					(size 1 1)
					(thickness 0.15)
				)
			)
		)
		(property "Author" "Antmicro"
			(at 0 0 180)
			(unlocked yes)
			(layer "F.Fab")
			(hide yes)
			(effects
				(font
					(size 1 1)
					(thickness 0.15)
				)
			)
		)
		(property "Val" "25 MHz"
			(at 0 0 180)
			(unlocked yes)
			(layer "F.Fab")
			(hide yes)
			(effects
				(font
					(size 1 1)
					(thickness 0.15)
				)
			)
		)
		(sheetname "/TB Controller/")
		(sheetfile "tb.kicad_sch")
		(attr smd)
		(fp_line
			(start 1.6 0.3)
			(end 1.6 -0.2)
			(stroke
				(width 0.15)
				(type solid)
			)
			(layer "F.SilkS")
		)
		(fp_line
			(start -0.35 1.25)
			(end 0.45 1.25)
			(stroke
				(width 0.15)
				(type solid)
			)
			(layer "F.SilkS")
		)
		(fp_line
			(start -0.35 -1.25)
			(end 0.45 -1.25)
			(stroke
				(width 0.15)
				(type solid)
			)
			(layer "F.SilkS")
		)
		(fp_line
			(start -1.6 0.3)
			(end -1.6 -0.2)
			(stroke
				(width 0.15)
				(type solid)
			)
			(layer "F.SilkS")
		)
		(fp_circle
			(center -1.75 1.5)
			(end -1.7 1.5)
			(stroke
				(width 0.15)
				(type solid)
			)
			(fill no)
			(layer "F.SilkS")
		)
		(fp_rect
			(start -1.907 -1.55)
			(end 2.006 1.649)
			(stroke
				(width 0.05)
				(type solid)
			)
			(fill no)
			(layer "F.CrtYd")
		)
		(fp_text user "License: Apache-2.0"
			(at -1.75 6.5 180)
			(layer "F.Fab")
			(effects
				(font
					(size 0.7 0.7)
					(thickness 0.15)
				)
				(justify left bottom)
			)
		)
		(fp_text user "${REFERENCE}"
			(at -1.75 3.75 180)
			(layer "F.Fab")
			(effects
				(font
					(size 0.7 0.7)
					(thickness 0.15)
				)
				(justify left bottom)
			)
		)
		(fp_text user "Author: Antmicro"
			(at -1.75 5 180)
			(layer "F.Fab")
			(effects
				(font
					(size 0.7 0.7)
					(thickness 0.15)
				)
				(justify left bottom)
			)
		)
		(pad "1" smd roundrect
			(at -1.101 0.949 180)
			(size 1.3 1.1)
			(layers "F.Cu" "F.Mask" "F.Paste")
			(roundrect_rratio 0)
			(chamfer_ratio 0.2)
			(chamfer bottom_left)
			(net 400 "Net-(U5-XOUT)")
			(pintype "passive")
		)
		(pad "2" smd rect
			(at 1.199 0.949 180)
			(size 1.3 1.1)
			(layers "F.Cu" "F.Mask" "F.Paste")
			(net 23 "GND")
			(pinfunction "SH")
			(pintype "passive")
		)
		(pad "3" smd rect
			(at 1.199 -0.85 180)
			(size 1.3 1.1)
			(layers "F.Cu" "F.Mask" "F.Paste")
			(net 401 "Net-(U5-XIN{slash}CLKIN)")
			(pintype "passive")
		)
		(pad "4" smd rect
			(at -1.101 -0.85 180)
			(size 1.3 1.1)
			(layers "F.Cu" "F.Mask" "F.Paste")
			(net 23 "GND")
			(pinfunction "SH")
			(pintype "passive")
		)
	)
	(footprint "antmicro-footprints:R_0402_1005Metric"
		(layer "F.Cu")
		(at 135 86.25 -90)
		(descr "Resistor SMD 0402")
		(tags "resistor SMD 0402")
		(property "Reference" "R137"
			(at 1.8 4.2 270)
			(layer "F.SilkS")
			(effects
				(font
					(size 0.7 0.7)
					(thickness 0.15)
				)
				(justify left bottom)
			)
		)
		(property "Value" "R_0R_0402"
			(at -1.011843 1.772047 270)
			(layer "F.Fab")
			(effects
				(font
					(size 0.7 0.7)
					(thickness 0.15)
				)
				(justify left bottom)
			)
		)
		(property "Datasheet" "https://industrial.panasonic.com/cdbs/www-data/pdf/RDA0000/AOA0000C301.pdf"
			(at 0 0 270)
			(layer "F.Fab")
			(hide yes)
			(effects
				(font
					(size 1.27 1.27)
					(thickness 0.15)
				)
			)
		)
		(property "Description" "SMD Chip Resistor, Jumper, 0 ohm, 100 mW, 0402 [1005 Metric], Thick Film, General Purpose"
			(at 0 0 270)
			(layer "F.Fab")
			(hide yes)
			(effects
				(font
					(size 1.27 1.27)
					(thickness 0.15)
				)
			)
		)
		(property "MPN" "ERJ2GE0R00X"
			(at 0 0 270)
			(unlocked yes)
			(layer "F.Fab")
			(hide yes)
			(effects
				(font
					(size 1 1)
					(thickness 0.15)
				)
			)
		)
		(property "Manufacturer" "Panasonic"
			(at 0 0 270)
			(unlocked yes)
			(layer "F.Fab")
			(hide yes)
			(effects
				(font
					(size 1 1)
					(thickness 0.15)
				)
			)
		)
		(property "License" "Apache-2.0"
			(at 0 0 270)
			(unlocked yes)
			(layer "F.Fab")
			(hide yes)
			(effects
				(font
					(size 1 1)
					(thickness 0.15)
				)
			)
		)
		(property "Author" "Antmicro"
			(at 0 0 270)
			(unlocked yes)
			(layer "F.Fab")
			(hide yes)
			(effects
				(font
					(size 1 1)
					(thickness 0.15)
				)
			)
		)
		(property "Val" "0R"
			(at 0 0 270)
			(unlocked yes)
			(layer "F.Fab")
			(hide yes)
			(effects
				(font
					(size 1 1)
					(thickness 0.15)
				)
			)
		)
		(property "Tolerance" "~"
			(at 0 0 270)
			(unlocked yes)
			(layer "F.Fab")
			(hide yes)
			(effects
				(font
					(size 1 1)
					(thickness 0.15)
				)
			)
		)
		(property "Current" "1A"
			(at 0 0 270)
			(unlocked yes)
			(layer "F.Fab")
			(hide yes)
			(effects
				(font
					(size 1 1)
					(thickness 0.15)
				)
			)
		)
		(sheetname "/X710-AT2 Misc/")
		(sheetfile "x710-at2-mics.kicad_sch")
		(attr smd)
		(fp_rect
			(start -0.925 -0.47)
			(end 0.925 0.47)
			(stroke
				(width 0.05)
				(type default)
			)
			(fill no)
			(layer "F.CrtYd")
		)
		(fp_rect
			(start -0.5 -0.25)
			(end 0.5 0.25)
			(stroke
				(width 0.15)
				(type solid)
			)
			(fill no)
			(layer "F.Fab")
		)
		(fp_text user "License: Apache-2.0"
			(at -0.95 5.169 270)
			(layer "F.Fab")
			(effects
				(font
					(size 0.7 0.7)
					(thickness 0.15)
				)
				(justify left bottom)
			)
		)
		(fp_text user "${REFERENCE}"
			(at -0.95 3.168 270)
			(layer "F.Fab")
			(effects
				(font
					(size 0.7 0.7)
					(thickness 0.15)
				)
				(justify left bottom)
			)
		)
		(fp_text user "Author: Antmicro"
			(at -0.95 4.169 270)
			(layer "F.Fab")
			(effects
				(font
					(size 0.7 0.7)
					(thickness 0.15)
				)
				(justify left bottom)
			)
		)
		(pad "1" smd roundrect
			(at -0.48 0 270)
			(size 0.59 0.64)
			(layers "F.Cu" "F.Mask" "F.Paste")
			(roundrect_rratio 0.25)
			(net 392 "/TB Controller/~{PE_RST}")
			(pintype "passive")
		)
		(pad "2" smd roundrect
			(at 0.48 0 270)
			(size 0.59 0.64)
			(layers "F.Cu" "F.Mask" "F.Paste")
			(roundrect_rratio 0.25)
			(net 437 "Net-(U15-A)")
			(pintype "passive")
		)
	)
	(footprint "antmicro-footprints:Mech_Lightpipe_Mentor_1271.1001"
		(layer "F.Cu")
		(at 125 52.25)
		(descr "1x1  Horizontal Light Guide with transparent pipe")
		(tags "Horizontal, THT, MECHANICAL, MODULE")
		(property "Reference" "H5"
			(at -1.25 -2.45 0)
			(unlocked yes)
			(layer "F.SilkS")
			(effects
				(font
					(size 0.7 0.7)
					(thickness 0.15)
				)
				(justify left bottom)
			)
		)
		(property "Value" "Lightpipe_Mentor_1271.1001"
			(at 0 9 0)
			(unlocked yes)
			(layer "F.Fab")
			(effects
				(font
					(size 0.7 0.7)
					(thickness 0.15)
				)
				(justify left bottom)
			)
		)
		(property "Datasheet" "https://www.mentor.de.com/productpdfs/ll/ll14-20.pdf"
			(at 0 0 0)
			(layer "F.Fab")
			(hide yes)
			(effects
				(font
					(size 1.27 1.27)
					(thickness 0.15)
				)
			)
		)
		(property "Description" "Light Pipe, 14.45 mm, 1 Pipe, Circular, PC Board, Transparent"
			(at 0 0 0)
			(layer "F.Fab")
			(hide yes)
			(effects
				(font
					(size 1.27 1.27)
					(thickness 0.15)
				)
			)
		)
		(property "MPN" "1271.1001"
			(at 0 0 0)
			(unlocked yes)
			(layer "F.Fab")
			(hide yes)
			(effects
				(font
					(size 1 1)
					(thickness 0.15)
				)
			)
		)
		(property "Manufacturer" "Mentor Worldwide"
			(at 0 0 0)
			(unlocked yes)
			(layer "F.Fab")
			(hide yes)
			(effects
				(font
					(size 1 1)
					(thickness 0.15)
				)
			)
		)
		(property "Author" "Antmicro"
			(at 0 0 0)
			(unlocked yes)
			(layer "F.Fab")
			(hide yes)
			(effects
				(font
					(size 1 1)
					(thickness 0.15)
				)
			)
		)
		(property "License" "Apache-2.0"
			(at 0 0 0)
			(unlocked yes)
			(layer "F.Fab")
			(hide yes)
			(effects
				(font
					(size 1 1)
					(thickness 0.15)
				)
			)
		)
		(sheetname "/")
		(sheetfile "thunderbolt-to-10gbe-adapter.kicad_sch")
		(attr through_hole dnp)
		(fp_rect
			(start -1.55 -2.1)
			(end 1.55 1.3)
			(stroke
				(width 0.05)
				(type solid)
			)
			(fill no)
			(layer "F.SilkS")
		)
		(fp_rect
			(start -1.75 -2.3)
			(end 1.75 1.475)
			(stroke
				(width 0.05)
				(type solid)
			)
			(fill no)
			(layer "F.CrtYd")
		)
		(fp_rect
			(start -1.4732 -8.128)
			(end 1.4732 6.2484)
			(stroke
				(width 0.15)
				(type solid)
			)
			(fill no)
			(layer "F.Fab")
		)
		(fp_text user "License: Apache-2.0"
			(at -1.8 11.7 0)
			(layer "F.Fab")
			(effects
				(font
					(size 0.7 0.7)
					(thickness 0.15)
				)
				(justify left bottom)
			)
		)
		(fp_text user "${REFERENCE}"
			(at -1.8 12.9 0)
			(layer "F.Fab")
			(effects
				(font
					(size 0.7 0.7)
					(thickness 0.15)
				)
				(justify left bottom)
			)
		)
		(fp_text user "Author: Antmicro"
			(at -1.8 10.5 0)
			(layer "F.Fab")
			(effects
				(font
					(size 0.7 0.7)
					(thickness 0.15)
				)
				(justify left bottom)
			)
		)
		(pad "" np_thru_hole circle
			(at 0 0)
			(size 2.3 2.3)
			(drill 2.3)
			(layers "*.Cu" "*.Mask")
		)
	)
	(footprint "antmicro-footprints:R_0402_1005Metric"
		(layer "F.Cu")
		(at 125.02 91.579 180)
		(descr "Resistor SMD 0402")
		(tags "resistor SMD 0402")
		(property "Reference" "R115"
			(at 1.82 0.509 180)
			(layer "F.SilkS")
			(effects
				(font
					(size 0.7 0.7)
					(thickness 0.15)
				)
				(justify left bottom)
			)
		)
		(property "Value" "R_3k3_0402"
			(at -1.011843 1.772047 180)
			(layer "F.Fab")
			(effects
				(font
					(size 0.7 0.7)
					(thickness 0.15)
				)
				(justify left bottom)
			)
		)
		(property "Datasheet" "https://www.bourns.com/docs/product-datasheets/cr.pdf"
			(at 0 0 180)
			(layer "F.Fab")
			(hide yes)
			(effects
				(font
					(size 1.27 1.27)
					(thickness 0.15)
				)
			)
		)
		(property "Description" "SMD Chip Resistor, 3.3 kohm, ± 1%, 63 mW, 0402 [1005 Metric], Thick Film, General Purpose"
			(at 0 0 180)
			(layer "F.Fab")
			(hide yes)
			(effects
				(font
					(size 1.27 1.27)
					(thickness 0.15)
				)
			)
		)
		(property "MPN" "CR0402-FX-3301GLF"
			(at 0 0 180)
			(unlocked yes)
			(layer "F.Fab")
			(hide yes)
			(effects
				(font
					(size 1 1)
					(thickness 0.15)
				)
			)
		)
		(property "Manufacturer" "Bourns"
			(at 0 0 180)
			(unlocked yes)
			(layer "F.Fab")
			(hide yes)
			(effects
				(font
					(size 1 1)
					(thickness 0.15)
				)
			)
		)
		(property "License" "Apache-2.0"
			(at 0 0 180)
			(unlocked yes)
			(layer "F.Fab")
			(hide yes)
			(effects
				(font
					(size 1 1)
					(thickness 0.15)
				)
			)
		)
		(property "Author" "Antmicro"
			(at 0 0 180)
			(unlocked yes)
			(layer "F.Fab")
			(hide yes)
			(effects
				(font
					(size 1 1)
					(thickness 0.15)
				)
			)
		)
		(property "Val" "3k3"
			(at 0 0 180)
			(unlocked yes)
			(layer "F.Fab")
			(hide yes)
			(effects
				(font
					(size 1 1)
					(thickness 0.15)
				)
			)
		)
		(property "Tolerance" "1%"
			(at 0 0 180)
			(unlocked yes)
			(layer "F.Fab")
			(hide yes)
			(effects
				(font
					(size 1 1)
					(thickness 0.15)
				)
			)
		)
		(sheetname "/X710-AT2 PCIe/")
		(sheetfile "x710-at2-pcie.kicad_sch")
		(attr smd)
		(fp_rect
			(start -0.925 -0.47)
			(end 0.925 0.47)
			(stroke
				(width 0.05)
				(type default)
			)
			(fill no)
			(layer "F.CrtYd")
		)
		(fp_rect
			(start -0.5 -0.25)
			(end 0.5 0.25)
			(stroke
				(width 0.15)
				(type solid)
			)
			(fill no)
			(layer "F.Fab")
		)
		(fp_text user "License: Apache-2.0"
			(at -0.95 5.169 180)
			(layer "F.Fab")
			(effects
				(font
					(size 0.7 0.7)
					(thickness 0.15)
				)
				(justify left bottom)
			)
		)
		(fp_text user "Author: Antmicro"
			(at -0.95 4.169 180)
			(layer "F.Fab")
			(effects
				(font
					(size 0.7 0.7)
					(thickness 0.15)
				)
				(justify left bottom)
			)
		)
		(fp_text user "${REFERENCE}"
			(at -0.95 3.168 180)
			(layer "F.Fab")
			(effects
				(font
					(size 0.7 0.7)
					(thickness 0.15)
				)
				(justify left bottom)
			)
		)
		(pad "1" smd roundrect
			(at -0.48 0 180)
			(size 0.59 0.64)
			(layers "F.Cu" "F.Mask" "F.Paste")
			(roundrect_rratio 0.25)
			(net 8 "/X710-AT2 PCIe/PCIe_JTAG.JTDO")
			(pintype "passive")
		)
		(pad "2" smd roundrect
			(at 0.48 0 180)
			(size 0.59 0.64)
			(layers "F.Cu" "F.Mask" "F.Paste")
			(roundrect_rratio 0.25)
			(net 7 "+3V3")
			(pintype "passive")
		)
	)
	(footprint "antmicro-footprints:R_0402_1005Metric"
		(layer "F.Cu")
		(at 143.3 55.3)
		(descr "Resistor SMD 0402")
		(tags "resistor SMD 0402")
		(property "Reference" "R235"
			(at -3.7 0.4 0)
			(layer "F.SilkS")
			(effects
				(font
					(size 0.7 0.7)
					(thickness 0.15)
				)
				(justify left bottom)
			)
		)
		(property "Value" "R_1k_0402"
			(at -1.011843 1.772047 0)
			(layer "F.Fab")
			(effects
				(font
					(size 0.7 0.7)
					(thickness 0.15)
				)
				(justify left bottom)
			)
		)
		(property "Datasheet" "https://www.bourns.com/docs/product-datasheets/cr.pdf"
			(at 0 0 0)
			(layer "F.Fab")
			(hide yes)
			(effects
				(font
					(size 1.27 1.27)
					(thickness 0.15)
				)
			)
		)
		(property "Description" "SMD Chip Resistor, 1 kohm, ± 1%, 63 mW, 0402 [1005 Metric], Thick Film, General Purpose"
			(at 0 0 0)
			(layer "F.Fab")
			(hide yes)
			(effects
				(font
					(size 1.27 1.27)
					(thickness 0.15)
				)
			)
		)
		(property "MPN" "CR0402-FX-1001GLF"
			(at 0 0 0)
			(unlocked yes)
			(layer "F.Fab")
			(hide yes)
			(effects
				(font
					(size 1 1)
					(thickness 0.15)
				)
			)
		)
		(property "Manufacturer" "Bourns"
			(at 0 0 0)
			(unlocked yes)
			(layer "F.Fab")
			(hide yes)
			(effects
				(font
					(size 1 1)
					(thickness 0.15)
				)
			)
		)
		(property "License" "Apache-2.0"
			(at 0 0 0)
			(unlocked yes)
			(layer "F.Fab")
			(hide yes)
			(effects
				(font
					(size 1 1)
					(thickness 0.15)
				)
			)
		)
		(property "Author" "Antmicro"
			(at 0 0 0)
			(unlocked yes)
			(layer "F.Fab")
			(hide yes)
			(effects
				(font
					(size 1 1)
					(thickness 0.15)
				)
			)
		)
		(property "Val" "1k"
			(at 0 0 0)
			(unlocked yes)
			(layer "F.Fab")
			(hide yes)
			(effects
				(font
					(size 1 1)
					(thickness 0.15)
				)
			)
		)
		(property "Tolerance" "1%"
			(at 0 0 0)
			(unlocked yes)
			(layer "F.Fab")
			(hide yes)
			(effects
				(font
					(size 1 1)
					(thickness 0.15)
				)
			)
		)
		(sheetname "/Power input/")
		(sheetfile "power_input.kicad_sch")
		(attr smd)
		(fp_rect
			(start -0.925 -0.47)
			(end 0.925 0.47)
			(stroke
				(width 0.05)
				(type default)
			)
			(fill no)
			(layer "F.CrtYd")
		)
		(fp_rect
			(start -0.5 -0.25)
			(end 0.5 0.25)
			(stroke
				(width 0.15)
				(type solid)
			)
			(fill no)
			(layer "F.Fab")
		)
		(fp_text user "Author: Antmicro"
			(at -0.95 4.169 0)
			(layer "F.Fab")
			(effects
				(font
					(size 0.7 0.7)
					(thickness 0.15)
				)
				(justify left bottom)
			)
		)
		(fp_text user "${REFERENCE}"
			(at -0.95 3.168 0)
			(layer "F.Fab")
			(effects
				(font
					(size 0.7 0.7)
					(thickness 0.15)
				)
				(justify left bottom)
			)
		)
		(fp_text user "License: Apache-2.0"
			(at -0.95 5.169 0)
			(layer "F.Fab")
			(effects
				(font
					(size 0.7 0.7)
					(thickness 0.15)
				)
				(justify left bottom)
			)
		)
		(pad "1" smd roundrect
			(at -0.48 0)
			(size 0.59 0.64)
			(layers "F.Cu" "F.Mask" "F.Paste")
			(roundrect_rratio 0.25)
			(net 23 "GND")
			(pintype "passive")
		)
		(pad "2" smd roundrect
			(at 0.48 0)
			(size 0.59 0.64)
			(layers "F.Cu" "F.Mask" "F.Paste")
			(roundrect_rratio 0.25)
			(net 13 "/Power input/5V_JACK")
			(pintype "passive")
		)
	)
	(footprint "antmicro-footprints:C_0402_1005Metric"
		(layer "F.Cu")
		(at 116.6 132.4)
		(descr "Capacitor SMD 0402")
		(tags "capacitor SMD 0402")
		(property "Reference" "C42"
			(at -1.4 1.4 0)
			(layer "F.SilkS")
			(effects
				(font
					(size 0.7 0.7)
					(thickness 0.15)
				)
				(justify left bottom)
			)
		)
		(property "Value" "C_10p_0402"
			(at -1.022927 2.155213 0)
			(layer "F.Fab")
			(effects
				(font
					(size 0.7 0.7)
					(thickness 0.15)
				)
				(justify left bottom)
			)
		)
		(property "Datasheet" "https://www.murata.com/products/productdetail?partno=GCM1555C1H100GA16%23"
			(at 0 0 0)
			(layer "F.Fab")
			(hide yes)
			(effects
				(font
					(size 1.27 1.27)
					(thickness 0.15)
				)
			)
		)
		(property "Description" "SMD Multilayer Ceramic Capacitor, 10 pF, 50 V, 0402 [1005 Metric], ± 2%, C0G / NP0, GCM"
			(at 0 0 0)
			(layer "F.Fab")
			(hide yes)
			(effects
				(font
					(size 1.27 1.27)
					(thickness 0.15)
				)
			)
		)
		(property "MPN" "GCM1555C1H100GA16D"
			(at 0 0 0)
			(unlocked yes)
			(layer "F.Fab")
			(hide yes)
			(effects
				(font
					(size 1 1)
					(thickness 0.15)
				)
			)
		)
		(property "Manufacturer" "Murata"
			(at 0 0 0)
			(unlocked yes)
			(layer "F.Fab")
			(hide yes)
			(effects
				(font
					(size 1 1)
					(thickness 0.15)
				)
			)
		)
		(property "License" "Apache-2.0"
			(at 0 0 0)
			(unlocked yes)
			(layer "F.Fab")
			(hide yes)
			(effects
				(font
					(size 1 1)
					(thickness 0.15)
				)
			)
		)
		(property "Val" "10p"
			(at 0 0 0)
			(unlocked yes)
			(layer "F.Fab")
			(hide yes)
			(effects
				(font
					(size 1 1)
					(thickness 0.15)
				)
			)
		)
		(property "Voltage" "50V"
			(at 0 0 0)
			(unlocked yes)
			(layer "F.Fab")
			(hide yes)
			(effects
				(font
					(size 1 1)
					(thickness 0.15)
				)
			)
		)
		(property "Dielectric" "C0G"
			(at 0 0 0)
			(unlocked yes)
			(layer "F.Fab")
			(hide yes)
			(effects
				(font
					(size 1 1)
					(thickness 0.15)
				)
			)
		)
		(property "Author" "Antmicro"
			(at 0 0 0)
			(unlocked yes)
			(layer "F.Fab")
			(hide yes)
			(effects
				(font
					(size 1 1)
					(thickness 0.15)
				)
			)
		)
		(sheetname "/TB Controller/")
		(sheetfile "tb.kicad_sch")
		(attr smd)
		(fp_rect
			(start -0.925 -0.47)
			(end 0.925 0.47)
			(stroke
				(width 0.05)
				(type default)
			)
			(fill no)
			(layer "F.CrtYd")
		)
		(fp_line
			(start -0.494 -0.25)
			(end 0.504 -0.25)
			(stroke
				(width 0.15)
				(type solid)
			)
			(layer "F.Fab")
		)
		(fp_line
			(start -0.494 0.248)
			(end -0.494 -0.25)
			(stroke
				(width 0.15)
				(type solid)
			)
			(layer "F.Fab")
		)
		(fp_line
			(start 0.504 -0.25)
			(end 0.504 0.248)
			(stroke
				(width 0.15)
				(type solid)
			)
			(layer "F.Fab")
		)
		(fp_line
			(start 0.504 0.248)
			(end -0.494 0.248)
			(stroke
				(width 0.15)
				(type solid)
			)
			(layer "F.Fab")
		)
		(fp_text user "License: Apache-2.0"
			(at -0.939 5.799 0)
			(layer "F.Fab")
			(effects
				(font
					(size 0.7 0.7)
					(thickness 0.15)
				)
				(justify left bottom)
			)
		)
		(fp_text user "${REFERENCE}"
			(at -0.939 4.599 0)
			(layer "F.Fab")
			(effects
				(font
					(size 0.7 0.7)
					(thickness 0.15)
				)
				(justify left bottom)
			)
		)
		(fp_text user "Author: Antmicro"
			(at -0.939 3.399 0)
			(layer "F.Fab")
			(effects
				(font
					(size 0.7 0.7)
					(thickness 0.15)
				)
				(justify left bottom)
			)
		)
		(pad "1" smd roundrect
			(at -0.48 0)
			(size 0.59 0.64)
			(layers "F.Cu" "F.Mask" "F.Paste")
			(roundrect_rratio 0.25)
			(net 330 "/TB Controller/XTAL_25_IN")
			(pintype "passive")
		)
		(pad "2" smd roundrect
			(at 0.48 0)
			(size 0.59 0.64)
			(layers "F.Cu" "F.Mask" "F.Paste")
			(roundrect_rratio 0.25)
			(net 23 "GND")
			(pintype "passive")
		)
	)
	(footprint "antmicro-footprints:R_0402_1005Metric"
		(layer "F.Cu")
		(at 153.8 45.9)
		(descr "Resistor SMD 0402")
		(tags "resistor SMD 0402")
		(property "Reference" "R227"
			(at -3.8 0.2 0)
			(layer "F.SilkS")
			(effects
				(font
					(size 0.7 0.7)
					(thickness 0.15)
				)
				(justify left bottom)
			)
		)
		(property "Value" "R_3k24_0402"
			(at -1.011843 1.772047 0)
			(layer "F.Fab")
			(effects
				(font
					(size 0.7 0.7)
					(thickness 0.15)
				)
				(justify left bottom)
			)
		)
		(property "Datasheet" "https://www.farnell.com/datasheets/3795017.pdf"
			(at 0 0 0)
			(layer "F.Fab")
			(hide yes)
			(effects
				(font
					(size 1.27 1.27)
					(thickness 0.15)
				)
			)
		)
		(property "Description" "SMD Chip Resistor, 3.24 kohm, ± 1%, 62.5 mW, 0402 [1005 Metric], Thick Film, General Purpose"
			(at 0 0 0)
			(layer "F.Fab")
			(hide yes)
			(effects
				(font
					(size 1.27 1.27)
					(thickness 0.15)
				)
			)
		)
		(property "MPN" "RMCF0402FT3K24"
			(at 0 0 0)
			(unlocked yes)
			(layer "F.Fab")
			(hide yes)
			(effects
				(font
					(size 1 1)
					(thickness 0.15)
				)
			)
		)
		(property "Manufacturer" "Stackpole Electronics"
			(at 0 0 0)
			(unlocked yes)
			(layer "F.Fab")
			(hide yes)
			(effects
				(font
					(size 1 1)
					(thickness 0.15)
				)
			)
		)
		(property "License" "Apache-2.0"
			(at 0 0 0)
			(unlocked yes)
			(layer "F.Fab")
			(hide yes)
			(effects
				(font
					(size 1 1)
					(thickness 0.15)
				)
			)
		)
		(property "Author" "Antmicro"
			(at 0 0 0)
			(unlocked yes)
			(layer "F.Fab")
			(hide yes)
			(effects
				(font
					(size 1 1)
					(thickness 0.15)
				)
			)
		)
		(property "Val" "3k24"
			(at 0 0 0)
			(unlocked yes)
			(layer "F.Fab")
			(hide yes)
			(effects
				(font
					(size 1 1)
					(thickness 0.15)
				)
			)
		)
		(property "Tolerance" "1%"
			(at 0 0 0)
			(unlocked yes)
			(layer "F.Fab")
			(hide yes)
			(effects
				(font
					(size 1 1)
					(thickness 0.15)
				)
			)
		)
		(sheetname "/Power input/")
		(sheetfile "power_input.kicad_sch")
		(attr smd)
		(fp_rect
			(start -0.925 -0.47)
			(end 0.925 0.47)
			(stroke
				(width 0.05)
				(type default)
			)
			(fill no)
			(layer "F.CrtYd")
		)
		(fp_rect
			(start -0.5 -0.25)
			(end 0.5 0.25)
			(stroke
				(width 0.15)
				(type solid)
			)
			(fill no)
			(layer "F.Fab")
		)
		(fp_text user "Author: Antmicro"
			(at -0.95 4.169 0)
			(layer "F.Fab")
			(effects
				(font
					(size 0.7 0.7)
					(thickness 0.15)
				)
				(justify left bottom)
			)
		)
		(fp_text user "License: Apache-2.0"
			(at -0.95 5.169 0)
			(layer "F.Fab")
			(effects
				(font
					(size 0.7 0.7)
					(thickness 0.15)
				)
				(justify left bottom)
			)
		)
		(fp_text user "${REFERENCE}"
			(at -0.95 3.168 0)
			(layer "F.Fab")
			(effects
				(font
					(size 0.7 0.7)
					(thickness 0.15)
				)
				(justify left bottom)
			)
		)
		(pad "1" smd roundrect
			(at -0.48 0)
			(size 0.59 0.64)
			(layers "F.Cu" "F.Mask" "F.Paste")
			(roundrect_rratio 0.25)
			(net 23 "GND")
			(pintype "passive")
		)
		(pad "2" smd roundrect
			(at 0.48 0)
			(size 0.59 0.64)
			(layers "F.Cu" "F.Mask" "F.Paste")
			(roundrect_rratio 0.25)
			(net 344 "/Power input/5V_EN")
			(pintype "passive")
		)
	)
	(footprint "antmicro-footprints:C_0402_1005Metric"
		(layer "F.Cu")
		(at 141.4 63.4 180)
		(descr "Capacitor SMD 0402")
		(tags "capacitor SMD 0402")
		(property "Reference" "C324"
			(at 1.4 -1.6 180)
			(layer "F.SilkS")
			(effects
				(font
					(size 0.7 0.7)
					(thickness 0.15)
				)
				(justify left bottom)
			)
		)
		(property "Value" "C_1u_25V_0402"
			(at -1.022927 2.155213 180)
			(layer "F.Fab")
			(effects
				(font
					(size 0.7 0.7)
					(thickness 0.15)
				)
				(justify left bottom)
			)
		)
		(property "Datasheet" "https://www.murata.com/products/productdetail?partno=GRM155R61E105KE11%23"
			(at 0 0 180)
			(layer "F.Fab")
			(hide yes)
			(effects
				(font
					(size 1.27 1.27)
					(thickness 0.15)
				)
			)
		)
		(property "Description" "SMD Multilayer Ceramic Capacitor, 1 µF, 25 V, 0402 [1005 Metric], ± 10%, X5R, GRM Series"
			(at 0 0 180)
			(layer "F.Fab")
			(hide yes)
			(effects
				(font
					(size 1.27 1.27)
					(thickness 0.15)
				)
			)
		)
		(property "MPN" "GRM155R61E105KE11J"
			(at 0 0 180)
			(unlocked yes)
			(layer "F.Fab")
			(hide yes)
			(effects
				(font
					(size 1 1)
					(thickness 0.15)
				)
			)
		)
		(property "Manufacturer" "Murata"
			(at 0 0 180)
			(unlocked yes)
			(layer "F.Fab")
			(hide yes)
			(effects
				(font
					(size 1 1)
					(thickness 0.15)
				)
			)
		)
		(property "License" "Apache-2.0"
			(at 0 0 180)
			(unlocked yes)
			(layer "F.Fab")
			(hide yes)
			(effects
				(font
					(size 1 1)
					(thickness 0.15)
				)
			)
		)
		(property "Author" "Antmicro"
			(at 0 0 180)
			(unlocked yes)
			(layer "F.Fab")
			(hide yes)
			(effects
				(font
					(size 1 1)
					(thickness 0.15)
				)
			)
		)
		(property "Val" "1u"
			(at 0 0 180)
			(unlocked yes)
			(layer "F.Fab")
			(hide yes)
			(effects
				(font
					(size 1 1)
					(thickness 0.15)
				)
			)
		)
		(property "Voltage" "25V"
			(at 0 0 180)
			(unlocked yes)
			(layer "F.Fab")
			(hide yes)
			(effects
				(font
					(size 1 1)
					(thickness 0.15)
				)
			)
		)
		(property "Dielectric" "X5R"
			(at 0 0 180)
			(unlocked yes)
			(layer "F.Fab")
			(hide yes)
			(effects
				(font
					(size 1 1)
					(thickness 0.15)
				)
			)
		)
		(sheetname "/Power input/")
		(sheetfile "power_input.kicad_sch")
		(attr smd)
		(fp_rect
			(start -0.925 -0.47)
			(end 0.925 0.47)
			(stroke
				(width 0.05)
				(type default)
			)
			(fill no)
			(layer "F.CrtYd")
		)
		(fp_line
			(start 0.504 0.248)
			(end -0.494 0.248)
			(stroke
				(width 0.15)
				(type solid)
			)
			(layer "F.Fab")
		)
		(fp_line
			(start 0.504 -0.25)
			(end 0.504 0.248)
			(stroke
				(width 0.15)
				(type solid)
			)
			(layer "F.Fab")
		)
		(fp_line
			(start -0.494 0.248)
			(end -0.494 -0.25)
			(stroke
				(width 0.15)
				(type solid)
			)
			(layer "F.Fab")
		)
		(fp_line
			(start -0.494 -0.25)
			(end 0.504 -0.25)
			(stroke
				(width 0.15)
				(type solid)
			)
			(layer "F.Fab")
		)
		(fp_text user "${REFERENCE}"
			(at -0.939 4.599 180)
			(layer "F.Fab")
			(effects
				(font
					(size 0.7 0.7)
					(thickness 0.15)
				)
				(justify left bottom)
			)
		)
		(fp_text user "Author: Antmicro"
			(at -0.939 3.399 180)
			(layer "F.Fab")
			(effects
				(font
					(size 0.7 0.7)
					(thickness 0.15)
				)
				(justify left bottom)
			)
		)
		(fp_text user "License: Apache-2.0"
			(at -0.939 5.799 180)
			(layer "F.Fab")
			(effects
				(font
					(size 0.7 0.7)
					(thickness 0.15)
				)
				(justify left bottom)
			)
		)
		(pad "1" smd roundrect
			(at -0.48 0 180)
			(size 0.59 0.64)
			(layers "F.Cu" "F.Mask" "F.Paste")
			(roundrect_rratio 0.25)
			(net 23 "GND")
			(pintype "passive")
		)
		(pad "2" smd roundrect
			(at 0.48 0 180)
			(size 0.59 0.64)
			(layers "F.Cu" "F.Mask" "F.Paste")
			(roundrect_rratio 0.25)
			(net 40 "+5V")
			(pintype "passive")
		)
	)
	(footprint "antmicro-footprints:FB_0603_1608Metric"
		(layer "F.Cu")
		(at 160.155 99.224999 90)
		(property "Reference" "FB6"
			(at 0 7.695 90)
			(layer "F.SilkS")
			(effects
				(font
					(size 0.7 0.7)
					(thickness 0.15)
				)
			)
		)
		(property "Value" "FB_33Z_3A_Murata-BLM18PG_0603"
			(at 0 1.5 90)
			(layer "F.Fab")
			(effects
				(font
					(size 0.7 0.7)
					(thickness 0.15)
				)
				(justify left bottom)
			)
		)
		(property "Datasheet" "https://www.murata.com/products/productdata/8796737273886/QNFA9101.pdf?1649080818000"
			(at 0 0 90)
			(layer "F.Fab")
			(hide yes)
			(effects
				(font
					(size 1.27 1.27)
					(thickness 0.15)
				)
			)
		)
		(property "Description" "Ferrite Bead, 0603 [1608 Metric], 33 ohm, 3 A, BLM18PG, 0.025 ohm, ± 25%, DC power line"
			(at 0 0 90)
			(layer "F.Fab")
			(hide yes)
			(effects
				(font
					(size 1.27 1.27)
					(thickness 0.15)
				)
			)
		)
		(property "Val" "33Z/3A"
			(at 0 0 90)
			(unlocked yes)
			(layer "F.Fab")
			(hide yes)
			(effects
				(font
					(size 1 1)
					(thickness 0.15)
				)
			)
		)
		(property "MPN" "BLM18PG330SH1D"
			(at 0 0 90)
			(unlocked yes)
			(layer "F.Fab")
			(hide yes)
			(effects
				(font
					(size 1 1)
					(thickness 0.15)
				)
			)
		)
		(property "Manufacturer" "Murata"
			(at 0 0 90)
			(unlocked yes)
			(layer "F.Fab")
			(hide yes)
			(effects
				(font
					(size 1 1)
					(thickness 0.15)
				)
			)
		)
		(property "Current" ""
			(at 0 0 90)
			(unlocked yes)
			(layer "F.Fab")
			(hide yes)
			(effects
				(font
					(size 1 1)
					(thickness 0.15)
				)
			)
		)
		(property "Author" "Antmicro"
			(at 0 0 90)
			(unlocked yes)
			(layer "F.Fab")
			(hide yes)
			(effects
				(font
					(size 1 1)
					(thickness 0.15)
				)
			)
		)
		(property "License" "Apache-2.0"
			(at 0 0 90)
			(unlocked yes)
			(layer "F.Fab")
			(hide yes)
			(effects
				(font
					(size 1 1)
					(thickness 0.15)
				)
			)
		)
		(sheetname "/X710-AT2 power/")
		(sheetfile "x710-at2-power.kicad_sch")
		(attr smd)
		(fp_line
			(start -0.15 -0.4)
			(end 0.15 -0.4)
			(stroke
				(width 0.15)
				(type solid)
			)
			(layer "F.SilkS")
		)
		(fp_line
			(start -0.15 0.4)
			(end 0.15 0.4)
			(stroke
				(width 0.15)
				(type solid)
			)
			(layer "F.SilkS")
		)
		(fp_rect
			(start -1.25 -0.65)
			(end 1.25 0.65)
			(stroke
				(width 0.05)
				(type solid)
			)
			(fill no)
			(layer "F.CrtYd")
		)
		(fp_line
			(start 0.8 -0.408)
			(end -0.803 -0.408)
			(stroke
				(width 0.15)
				(type solid)
			)
			(layer "F.Fab")
		)
		(fp_line
			(start 0.8 -0.408)
			(end 0.8 0.406)
			(stroke
				(width 0.15)
				(type solid)
			)
			(layer "F.Fab")
		)
		(fp_line
			(start 0.8 0.406)
			(end -0.803 0.406)
			(stroke
				(width 0.15)
				(type solid)
			)
			(layer "F.Fab")
		)
		(fp_line
			(start -0.803 0.406)
			(end -0.803 -0.408)
			(stroke
				(width 0.15)
				(type solid)
			)
			(layer "F.Fab")
		)
		(fp_text user "${REFERENCE}"
			(at -1.653 4.6 90)
			(layer "F.Fab")
			(effects
				(font
					(size 0.7 0.7)
					(thickness 0.15)
				)
				(justify left bottom)
			)
		)
		(fp_text user "Author: Antmicro"
			(at -1.653 3.162 90)
			(layer "F.Fab")
			(effects
				(font
					(size 0.7 0.7)
					(thickness 0.15)
				)
				(justify left bottom)
			)
		)
		(fp_text user "License: Apache-2.0"
			(at -1.653 5.9 90)
			(layer "F.Fab")
			(effects
				(font
					(size 0.7 0.7)
					(thickness 0.15)
				)
				(justify left bottom)
			)
		)
		(pad "1" smd roundrect
			(at -0.7 0 90)
			(size 0.8 1)
			(layers "F.Cu" "F.Mask" "F.Paste")
			(roundrect_rratio 0.2)
			(net 136 "+1V0")
			(pintype "passive")
		)
		(pad "2" smd roundrect
			(at 0.7 0 90)
			(size 0.8 1)
			(layers "F.Cu" "F.Mask" "F.Paste")
			(roundrect_rratio 0.2)
			(net 5 "P0_AVDDL")
			(pintype "passive")
		)
	)
	(footprint "antmicro-footprints:R_0402_1005Metric"
		(layer "F.Cu")
		(at 167.4 67.8 180)
		(descr "Resistor SMD 0402")
		(tags "resistor SMD 0402")
		(property "Reference" "R140"
			(at 0.2 -1.4 180)
			(layer "F.SilkS")
			(effects
				(font
					(size 0.7 0.7)
					(thickness 0.15)
				)
				(justify left bottom)
			)
		)
		(property "Value" "R_100R_0402"
			(at -1.011843 1.772047 180)
			(layer "F.Fab")
			(effects
				(font
					(size 0.7 0.7)
					(thickness 0.15)
				)
				(justify left bottom)
			)
		)
		(property "Datasheet" "https://www.bourns.com/docs/product-datasheets/cr.pdf"
			(at 0 0 180)
			(layer "F.Fab")
			(hide yes)
			(effects
				(font
					(size 1.27 1.27)
					(thickness 0.15)
				)
			)
		)
		(property "Description" "SMD Chip Resistor, 100 ohm, ± 1%, 62.5 mW, 0402 [1005 Metric], Thick Film, General Purpose"
			(at 0 0 180)
			(layer "F.Fab")
			(hide yes)
			(effects
				(font
					(size 1.27 1.27)
					(thickness 0.15)
				)
			)
		)
		(property "MPN" "CR0402-FX-1000GLF"
			(at 0 0 180)
			(unlocked yes)
			(layer "F.Fab")
			(hide yes)
			(effects
				(font
					(size 1 1)
					(thickness 0.15)
				)
			)
		)
		(property "Manufacturer" "Bourns"
			(at 0 0 180)
			(unlocked yes)
			(layer "F.Fab")
			(hide yes)
			(effects
				(font
					(size 1 1)
					(thickness 0.15)
				)
			)
		)
		(property "License" "Apache-2.0"
			(at 0 0 180)
			(unlocked yes)
			(layer "F.Fab")
			(hide yes)
			(effects
				(font
					(size 1 1)
					(thickness 0.15)
				)
			)
		)
		(property "Author" "Antmicro"
			(at 0 0 180)
			(unlocked yes)
			(layer "F.Fab")
			(hide yes)
			(effects
				(font
					(size 1 1)
					(thickness 0.15)
				)
			)
		)
		(property "Val" "100R"
			(at 0 0 180)
			(unlocked yes)
			(layer "F.Fab")
			(hide yes)
			(effects
				(font
					(size 1 1)
					(thickness 0.15)
				)
			)
		)
		(property "Tolerance" "1%"
			(at 0 0 180)
			(unlocked yes)
			(layer "F.Fab")
			(hide yes)
			(effects
				(font
					(size 1 1)
					(thickness 0.15)
				)
			)
		)
		(sheetname "/X710-AT2 Misc/")
		(sheetfile "x710-at2-mics.kicad_sch")
		(attr smd)
		(fp_rect
			(start -0.925 -0.47)
			(end 0.925 0.47)
			(stroke
				(width 0.05)
				(type default)
			)
			(fill no)
			(layer "F.CrtYd")
		)
		(fp_rect
			(start -0.5 -0.25)
			(end 0.5 0.25)
			(stroke
				(width 0.15)
				(type solid)
			)
			(fill no)
			(layer "F.Fab")
		)
		(fp_text user "Author: Antmicro"
			(at -0.95 4.169 180)
			(layer "F.Fab")
			(effects
				(font
					(size 0.7 0.7)
					(thickness 0.15)
				)
				(justify left bottom)
			)
		)
		(fp_text user "License: Apache-2.0"
			(at -0.95 5.169 180)
			(layer "F.Fab")
			(effects
				(font
					(size 0.7 0.7)
					(thickness 0.15)
				)
				(justify left bottom)
			)
		)
		(fp_text user "${REFERENCE}"
			(at -0.95 3.168 180)
			(layer "F.Fab")
			(effects
				(font
					(size 0.7 0.7)
					(thickness 0.15)
				)
				(justify left bottom)
			)
		)
		(pad "1" smd roundrect
			(at -0.48 0 180)
			(size 0.59 0.64)
			(layers "F.Cu" "F.Mask" "F.Paste")
			(roundrect_rratio 0.25)
			(net 23 "GND")
			(pintype "passive")
		)
		(pad "2" smd roundrect
			(at 0.48 0 180)
			(size 0.59 0.64)
			(layers "F.Cu" "F.Mask" "F.Paste")
			(roundrect_rratio 0.25)
			(net 438 "Net-(U17-B_{2})")
			(pintype "passive")
		)
	)
	(footprint "antmicro-footprints:Oscillator_SMD_Skyworks_SI511_5x3.2x1.17mm"
		(layer "F.Cu")
		(at 162 63 -90)
		(property "Reference" "Y4"
			(at -2.4 -2.4 90)
			(layer "F.SilkS")
			(effects
				(font
					(size 0.7 0.7)
					(thickness 0.15)
				)
				(justify left bottom)
			)
		)
		(property "Value" "Oscillator_25MHz_511ABA25M0000BAGR"
			(at -2.75 3.85 270)
			(layer "F.Fab")
			(effects
				(font
					(size 0.7 0.7)
					(thickness 0.15)
				)
				(justify left bottom)
			)
		)
		(property "Datasheet" "https://www.mouser.com/datasheet/2/472/si510_11-2507765.pdf"
			(at 0 0 270)
			(layer "F.Fab")
			(effects
				(font
					(size 0.7 0.7)
					(thickness 0.15)
				)
				(justify left bottom)
			)
		)
		(property "Description" "25 MHz XO (Standard) LVPECL Oscillator 3.3V Enable/Disable 6-SMD, No Lead"
			(at 0 0 270)
			(layer "F.Fab")
			(effects
				(font
					(size 0.7 0.7)
					(thickness 0.15)
				)
				(justify left bottom)
			)
		)
		(property "Manufacturer" "Skyworks Solutions"
			(at 0 0 270)
			(unlocked yes)
			(layer "F.Fab")
			(hide yes)
			(effects
				(font
					(size 1 1)
					(thickness 0.15)
				)
			)
		)
		(property "MPN" "511ABA25M0000BAGR"
			(at 0 0 270)
			(unlocked yes)
			(layer "F.Fab")
			(hide yes)
			(effects
				(font
					(size 1 1)
					(thickness 0.15)
				)
			)
		)
		(property "Val" "25 MHz"
			(at 0 0 270)
			(unlocked yes)
			(layer "F.Fab")
			(hide yes)
			(effects
				(font
					(size 1 1)
					(thickness 0.15)
				)
			)
		)
		(property "Author" "Antmicro"
			(at 0 0 270)
			(unlocked yes)
			(layer "F.Fab")
			(hide yes)
			(effects
				(font
					(size 1 1)
					(thickness 0.15)
				)
			)
		)
		(property "License" "Apache-2.0"
			(at 0 0 270)
			(unlocked yes)
			(layer "F.Fab")
			(hide yes)
			(effects
				(font
					(size 1 1)
					(thickness 0.15)
				)
			)
		)
		(sheetname "/X710-AT2 10GbE/")
		(sheetfile "x710-at2-10gbe.kicad_sch")
		(attr smd)
		(fp_line
			(start -1.6 2.5)
			(end 1.6 2.5)
			(stroke
				(width 0.15)
				(type solid)
			)
			(layer "F.SilkS")
		)
		(fp_line
			(start -1.6 2.5)
			(end -1.6 1.95)
			(stroke
				(width 0.15)
				(type solid)
			)
			(layer "F.SilkS")
		)
		(fp_line
			(start 1.6 2.5)
			(end 1.6 1.95)
			(stroke
				(width 0.15)
				(type solid)
			)
			(layer "F.SilkS")
		)
		(fp_line
			(start -1.6 -2.5)
			(end -1.6 -1.95)
			(stroke
				(width 0.15)
				(type solid)
			)
			(layer "F.SilkS")
		)
		(fp_line
			(start 1.6 -2.5)
			(end 1.6 -1.95)
			(stroke
				(width 0.15)
				(type solid)
			)
			(layer "F.SilkS")
		)
		(fp_line
			(start 1.6 -2.5)
			(end -1.6 -2.5)
			(stroke
				(width 0.15)
				(type solid)
			)
			(layer "F.SilkS")
		)
		(fp_circle
			(center -1.95 -1.875)
			(end -1.9 -1.875)
			(stroke
				(width 0.15)
				(type solid)
			)
			(fill yes)
			(layer "F.SilkS")
		)
		(fp_rect
			(start -2.25 -2.75)
			(end 2.25 2.75)
			(stroke
				(width 0.05)
				(type solid)
			)
			(fill no)
			(layer "F.CrtYd")
		)
		(fp_line
			(start -0.9 -2.5)
			(end -1.6 -1.8)
			(stroke
				(width 0.15)
				(type solid)
			)
			(layer "F.Fab")
		)
		(fp_rect
			(start -1.6 -2.5)
			(end 1.6 2.5)
			(stroke
				(width 0.15)
				(type solid)
			)
			(fill no)
			(layer "F.Fab")
		)
		(fp_text user "Author: Antmicro"
			(at -2.75 6.25 270)
			(layer "F.Fab")
			(effects
				(font
					(size 0.7 0.7)
					(thickness 0.15)
				)
				(justify left bottom)
			)
		)
		(fp_text user "${REFERENCE}"
			(at -2.75 7.45 270)
			(layer "F.Fab")
			(effects
				(font
					(size 0.7 0.7)
					(thickness 0.15)
				)
				(justify left bottom)
			)
		)
		(fp_text user "License: Apache-2.0"
			(at -2.75 5.05 270)
			(layer "F.Fab")
			(effects
				(font
					(size 0.7 0.7)
					(thickness 0.15)
				)
				(justify left bottom)
			)
		)
		(pad "1" smd rect
			(at -1.3 -1.27 270)
			(size 1.7 0.8)
			(layers "F.Cu" "F.Mask" "F.Paste")
			(net 113 "/X710-AT2 10GbE/EN_OSC")
			(pinfunction "EN")
			(pintype "input")
		)
		(pad "2" smd rect
			(at -1.3 0 270)
			(size 1.7 0.8)
			(layers "F.Cu" "F.Mask" "F.Paste")
			(net 594 "unconnected-(Y4-NC-Pad2)")
			(pinfunction "NC")
			(pintype "no_connect")
		)
		(pad "3" smd rect
			(at -1.3 1.27 270)
			(size 1.7 0.8)
			(layers "F.Cu" "F.Mask" "F.Paste")
			(net 23 "GND")
			(pinfunction "GND")
			(pintype "power_in")
		)
		(pad "4" smd rect
			(at 1.3 1.27 270)
			(size 1.7 0.8)
			(layers "F.Cu" "F.Mask" "F.Paste")
			(net 112 "/X710-AT2 10GbE/25MHZ_OSC_R.+")
			(pinfunction "OUT+")
			(pintype "output")
		)
		(pad "5" smd rect
			(at 1.3 0 270)
			(size 1.7 0.8)
			(layers "F.Cu" "F.Mask" "F.Paste")
			(net 114 "/X710-AT2 10GbE/25MHZ_OSC_R.-")
			(pinfunction "OUT-")
			(pintype "output")
		)
		(pad "6" smd rect
			(at 1.3 -1.27 270)
			(size 1.7 0.8)
			(layers "F.Cu" "F.Mask" "F.Paste")
			(net 56 "/X710-AT2 10GbE/3V3_OSC")
			(pinfunction "VCC")
			(pintype "power_in")
		)
	)
	(footprint "antmicro-footprints:C_0603_1608Metric_EIA"
		(layer "F.Cu")
		(at 136.005 89.274999 -90)
		(descr "Capacitor SMD 0603, IPC-7351 Density Level A")
		(tags "Capacitor 0603")
		(property "Reference" "C249"
			(at 4.225001 16.7 270)
			(layer "F.SilkS")
			(effects
				(font
					(size 0.7 0.7)
					(thickness 0.15)
				)
				(justify left bottom)
			)
		)
		(property "Value" "C_22u_16V_0603"
			(at -1.42757 1.770288 270)
			(layer "F.Fab")
			(effects
				(font
					(size 0.7 0.7)
					(thickness 0.15)
				)
				(justify left bottom)
			)
		)
		(property "Datasheet" "https://product.samsungsem.com/mlcc/CL10A226MO7JZN.do"
			(at 0 0 270)
			(layer "F.Fab")
			(hide yes)
			(effects
				(font
					(size 1.27 1.27)
					(thickness 0.15)
				)
			)
		)
		(property "Description" "SMD Multilayer Ceramic Capacitor"
			(at 0 0 270)
			(layer "F.Fab")
			(hide yes)
			(effects
				(font
					(size 1.27 1.27)
					(thickness 0.15)
				)
			)
		)
		(property "MPN" "CL10A226MO7JZNC"
			(at 0 0 270)
			(unlocked yes)
			(layer "F.Fab")
			(hide yes)
			(effects
				(font
					(size 1 1)
					(thickness 0.15)
				)
			)
		)
		(property "Manufacturer" "Samsung Electro-Mechanics"
			(at 0 0 270)
			(unlocked yes)
			(layer "F.Fab")
			(hide yes)
			(effects
				(font
					(size 1 1)
					(thickness 0.15)
				)
			)
		)
		(property "License" "Apache-2.0"
			(at 0 0 270)
			(unlocked yes)
			(layer "F.Fab")
			(hide yes)
			(effects
				(font
					(size 1 1)
					(thickness 0.15)
				)
			)
		)
		(property "Author" "Antmicro"
			(at 0 0 270)
			(unlocked yes)
			(layer "F.Fab")
			(hide yes)
			(effects
				(font
					(size 1 1)
					(thickness 0.15)
				)
			)
		)
		(property "Val" "22u"
			(at 0 0 270)
			(unlocked yes)
			(layer "F.Fab")
			(hide yes)
			(effects
				(font
					(size 1 1)
					(thickness 0.15)
				)
			)
		)
		(property "Voltage" "16V"
			(at 0 0 270)
			(unlocked yes)
			(layer "F.Fab")
			(hide yes)
			(effects
				(font
					(size 1 1)
					(thickness 0.15)
				)
			)
		)
		(property "Dielectric" ""
			(at 0 0 270)
			(unlocked yes)
			(layer "F.Fab")
			(hide yes)
			(effects
				(font
					(size 1 1)
					(thickness 0.15)
				)
			)
		)
		(sheetname "/X710-AT2 power/")
		(sheetfile "x710-at2-power.kicad_sch")
		(attr smd)
		(fp_line
			(start -0.15 0.55)
			(end 0.15 0.55)
			(stroke
				(width 0.15)
				(type solid)
			)
			(layer "F.SilkS")
		)
		(fp_line
			(start -0.15 -0.55)
			(end 0.15 -0.55)
			(stroke
				(width 0.15)
				(type solid)
			)
			(layer "F.SilkS")
		)
		(fp_rect
			(start -1.25 -0.65)
			(end 1.25 0.65)
			(stroke
				(width 0.05)
				(type solid)
			)
			(fill no)
			(layer "F.CrtYd")
		)
		(fp_rect
			(start -0.8 -0.45)
			(end 0.8 0.45)
			(stroke
				(width 0.15)
				(type solid)
			)
			(fill no)
			(layer "F.Fab")
		)
		(fp_text user "Author: Antmicro"
			(at -1.682 4.894 270)
			(layer "F.Fab")
			(effects
				(font
					(size 0.7 0.7)
					(thickness 0.15)
				)
				(justify left bottom)
			)
		)
		(fp_text user "License: Apache-2.0"
			(at -1.682 5.895 270)
			(layer "F.Fab")
			(effects
				(font
					(size 0.7 0.7)
					(thickness 0.15)
				)
				(justify left bottom)
			)
		)
		(fp_text user "${REFERENCE}"
			(at -1.682 3.895 270)
			(layer "F.Fab")
			(effects
				(font
					(size 0.7 0.7)
					(thickness 0.15)
				)
				(justify left bottom)
			)
		)
		(pad "1" smd roundrect
			(at -0.7 0 270)
			(size 0.8 1.1)
			(layers "F.Cu" "F.Mask" "F.Paste")
			(roundrect_rratio 0.2)
			(net 23 "GND")
			(pintype "passive")
		)
		(pad "2" smd roundrect
			(at 0.7 0 270)
			(size 0.8 1.1)
			(layers "F.Cu" "F.Mask" "F.Paste")
			(roundrect_rratio 0.2)
			(net 7 "+3V3")
			(pintype "passive")
		)
	)
	(footprint "antmicro-footprints:SOD-523"
		(layer "F.Cu")
		(at 134 59.2 180)
		(property "Reference" "D17"
			(at 3.6 -0.4 180)
			(layer "F.SilkS")
			(effects
				(font
					(size 0.7 0.7)
					(thickness 0.15)
				)
				(justify left bottom)
			)
		)
		(property "Value" "PESD5Z5.0F"
			(at 0 1.499 180)
			(layer "F.Fab")
			(effects
				(font
					(size 0.7 0.7)
					(thickness 0.15)
				)
				(justify left bottom)
			)
		)
		(property "Datasheet" "https://assets.nexperia.com/documents/data-sheet/PESD5Z5_0.pdf"
			(at 0 0 180)
			(layer "F.Fab")
			(hide yes)
			(effects
				(font
					(size 1.27 1.27)
					(thickness 0.15)
				)
			)
		)
		(property "Description" "Unidirectional TVS, 30 kV,  SOD-523, 5 V, 89 pF"
			(at 0 0 180)
			(layer "F.Fab")
			(hide yes)
			(effects
				(font
					(size 1.27 1.27)
					(thickness 0.15)
				)
			)
		)
		(property "Manufacturer" "Nexperia"
			(at 0 0 180)
			(unlocked yes)
			(layer "F.Fab")
			(hide yes)
			(effects
				(font
					(size 1 1)
					(thickness 0.15)
				)
			)
		)
		(property "MPN" "PESD5Z5.0F"
			(at 0 0 180)
			(unlocked yes)
			(layer "F.Fab")
			(hide yes)
			(effects
				(font
					(size 1 1)
					(thickness 0.15)
				)
			)
		)
		(property "Author" "Antmicro"
			(at 0 0 180)
			(unlocked yes)
			(layer "F.Fab")
			(hide yes)
			(effects
				(font
					(size 1 1)
					(thickness 0.15)
				)
			)
		)
		(property "License" "Apache-2.0"
			(at 0 0 180)
			(unlocked yes)
			(layer "F.Fab")
			(hide yes)
			(effects
				(font
					(size 1 1)
					(thickness 0.15)
				)
			)
		)
		(sheetname "/Power input/")
		(sheetfile "power_input.kicad_sch")
		(attr smd)
		(fp_line
			(start -0.35 -0.5)
			(end -0.35 0.5)
			(stroke
				(width 0.15)
				(type solid)
			)
			(layer "F.SilkS")
		)
		(fp_rect
			(start -1 -0.6)
			(end 1 0.6)
			(stroke
				(width 0.05)
				(type solid)
			)
			(fill no)
			(layer "F.CrtYd")
		)
		(fp_line
			(start 0.65 -0.425)
			(end 0.65 0.423)
			(stroke
				(width 0.15)
				(type solid)
			)
			(layer "F.Fab")
		)
		(fp_line
			(start -0.35 -0.4)
			(end -0.35 0.4)
			(stroke
				(width 0.15)
				(type solid)
			)
			(layer "F.Fab")
		)
		(fp_line
			(start -0.652 0.423)
			(end 0.65 0.423)
			(stroke
				(width 0.15)
				(type solid)
			)
			(layer "F.Fab")
		)
		(fp_line
			(start -0.652 0.423)
			(end -0.652 -0.425)
			(stroke
				(width 0.15)
				(type solid)
			)
			(layer "F.Fab")
		)
		(fp_line
			(start -0.652 -0.425)
			(end 0.65 -0.425)
			(stroke
				(width 0.15)
				(type solid)
			)
			(layer "F.Fab")
		)
		(fp_text user "Author: Antmicro"
			(at -1.276 4.7 180)
			(layer "F.Fab")
			(effects
				(font
					(size 0.7 0.7)
					(thickness 0.15)
				)
				(justify left bottom)
			)
		)
		(fp_text user "${REFERENCE}"
			(at -1.276 3.499 180)
			(layer "F.Fab")
			(effects
				(font
					(size 0.7 0.7)
					(thickness 0.15)
				)
				(justify left bottom)
			)
		)
		(fp_text user "License: Apache-2.0"
			(at -1.276 5.9 180)
			(layer "F.Fab")
			(effects
				(font
					(size 0.7 0.7)
					(thickness 0.15)
				)
				(justify left bottom)
			)
		)
		(pad "1" smd roundrect
			(at -0.701 0 180)
			(size 0.5 0.6)
			(layers "F.Cu" "F.Mask" "F.Paste")
			(roundrect_rratio 0.25)
			(net 40 "+5V")
			(pinfunction "C")
			(pintype "passive")
		)
		(pad "2" smd roundrect
			(at 0.699 0 180)
			(size 0.5 0.6)
			(layers "F.Cu" "F.Mask" "F.Paste")
			(roundrect_rratio 0.25)
			(net 23 "GND")
			(pinfunction "A")
			(pintype "passive")
		)
	)
	(footprint "antmicro-footprints:C_0402_1005Metric"
		(layer "F.Cu")
		(at 136.850001 129.15 -90)
		(descr "Capacitor SMD 0402")
		(tags "capacitor SMD 0402")
		(property "Reference" "C100"
			(at -0.450004 -7.15 270)
			(layer "F.SilkS")
			(effects
				(font
					(size 0.7 0.7)
					(thickness 0.15)
				)
				(justify left bottom)
			)
		)
		(property "Value" "C_10u_0402"
			(at -1.022927 2.155213 270)
			(layer "F.Fab")
			(effects
				(font
					(size 0.7 0.7)
					(thickness 0.15)
				)
				(justify left bottom)
			)
		)
		(property "Datasheet" "https://www.yageo.com/en/Chart/Download/pdf/CC0402MRX5R5BB106"
			(at 0 0 270)
			(layer "F.Fab")
			(hide yes)
			(effects
				(font
					(size 1.27 1.27)
					(thickness 0.15)
				)
			)
		)
		(property "Description" "SMD Multilayer Ceramic Capacitor, 10 µF, 6.3 V, 0402 [1005 Metric], ± 20%, X5R, CC Series"
			(at 0 0 270)
			(layer "F.Fab")
			(hide yes)
			(effects
				(font
					(size 1.27 1.27)
					(thickness 0.15)
				)
			)
		)
		(property "MPN" "CC0402MRX5R5BB106"
			(at 0 0 270)
			(unlocked yes)
			(layer "F.Fab")
			(hide yes)
			(effects
				(font
					(size 1 1)
					(thickness 0.15)
				)
			)
		)
		(property "Manufacturer" "YAGEO"
			(at 0 0 270)
			(unlocked yes)
			(layer "F.Fab")
			(hide yes)
			(effects
				(font
					(size 1 1)
					(thickness 0.15)
				)
			)
		)
		(property "License" "Apache-2.0"
			(at 0 0 270)
			(unlocked yes)
			(layer "F.Fab")
			(hide yes)
			(effects
				(font
					(size 1 1)
					(thickness 0.15)
				)
			)
		)
		(property "Val" "10u"
			(at 0 0 270)
			(unlocked yes)
			(layer "F.Fab")
			(hide yes)
			(effects
				(font
					(size 1 1)
					(thickness 0.15)
				)
			)
		)
		(property "Voltage" ""
			(at 0 0 270)
			(unlocked yes)
			(layer "F.Fab")
			(hide yes)
			(effects
				(font
					(size 1 1)
					(thickness 0.15)
				)
			)
		)
		(property "Dielectric" ""
			(at 0 0 270)
			(unlocked yes)
			(layer "F.Fab")
			(hide yes)
			(effects
				(font
					(size 1 1)
					(thickness 0.15)
				)
			)
		)
		(property "Author" "Antmicro"
			(at 0 0 270)
			(unlocked yes)
			(layer "F.Fab")
			(hide yes)
			(effects
				(font
					(size 1 1)
					(thickness 0.15)
				)
			)
		)
		(sheetname "/TB Controller - Power/")
		(sheetfile "tb-power.kicad_sch")
		(attr smd)
		(fp_rect
			(start -0.925 -0.47)
			(end 0.925 0.47)
			(stroke
				(width 0.05)
				(type default)
			)
			(fill no)
			(layer "F.CrtYd")
		)
		(fp_line
			(start -0.494 0.248)
			(end -0.494 -0.25)
			(stroke
				(width 0.15)
				(type solid)
			)
			(layer "F.Fab")
		)
		(fp_line
			(start 0.504 0.248)
			(end -0.494 0.248)
			(stroke
				(width 0.15)
				(type solid)
			)
			(layer "F.Fab")
		)
		(fp_line
			(start -0.494 -0.25)
			(end 0.504 -0.25)
			(stroke
				(width 0.15)
				(type solid)
			)
			(layer "F.Fab")
		)
		(fp_line
			(start 0.504 -0.25)
			(end 0.504 0.248)
			(stroke
				(width 0.15)
				(type solid)
			)
			(layer "F.Fab")
		)
		(fp_text user "License: Apache-2.0"
			(at -0.939 5.799 270)
			(layer "F.Fab")
			(effects
				(font
					(size 0.7 0.7)
					(thickness 0.15)
				)
				(justify left bottom)
			)
		)
		(fp_text user "${REFERENCE}"
			(at -0.939 4.599 270)
			(layer "F.Fab")
			(effects
				(font
					(size 0.7 0.7)
					(thickness 0.15)
				)
				(justify left bottom)
			)
		)
		(fp_text user "Author: Antmicro"
			(at -0.939 3.399 270)
			(layer "F.Fab")
			(effects
				(font
					(size 0.7 0.7)
					(thickness 0.15)
				)
				(justify left bottom)
			)
		)
		(pad "1" smd roundrect
			(at -0.48 0 270)
			(size 0.59 0.64)
			(layers "F.Cu" "F.Mask" "F.Paste")
			(roundrect_rratio 0.25)
			(net 23 "GND")
			(pintype "passive")
		)
		(pad "2" smd roundrect
			(at 0.48 0 270)
			(size 0.59 0.64)
			(layers "F.Cu" "F.Mask" "F.Paste")
			(roundrect_rratio 0.25)
			(net 57 "+3V3_TB")
			(pintype "passive")
		)
	)
	(footprint "antmicro-footprints:C_0402_1005Metric"
		(layer "F.Cu")
		(at 156.5 46.9)
		(descr "Capacitor SMD 0402")
		(tags "capacitor SMD 0402")
		(property "Reference" "C317"
			(at -1.7 -0.5 0)
			(layer "F.SilkS")
			(effects
				(font
					(size 0.7 0.7)
					(thickness 0.15)
				)
				(justify left bottom)
			)
		)
		(property "Value" "C_100n_0402"
			(at -1.022927 2.155213 0)
			(layer "F.Fab")
			(effects
				(font
					(size 0.7 0.7)
					(thickness 0.15)
				)
				(justify left bottom)
			)
		)
		(property "Datasheet" "https://www.murata.com/products/productdetail?partno=GRM155R61H104KE14%23"
			(at 0 0 0)
			(layer "F.Fab")
			(hide yes)
			(effects
				(font
					(size 1.27 1.27)
					(thickness 0.15)
				)
			)
		)
		(property "Description" "SMD Multilayer Ceramic Capacitor, 0.1 µF, 50 V, 0402 [1005 Metric], ± 10%, X5R, GRM Series"
			(at 0 0 0)
			(layer "F.Fab")
			(hide yes)
			(effects
				(font
					(size 1.27 1.27)
					(thickness 0.15)
				)
			)
		)
		(property "Manufacturer" "Murata"
			(at 0 0 0)
			(unlocked yes)
			(layer "F.Fab")
			(hide yes)
			(effects
				(font
					(size 1 1)
					(thickness 0.15)
				)
			)
		)
		(property "MPN" "GRM155R61H104KE14D"
			(at 0 0 0)
			(unlocked yes)
			(layer "F.Fab")
			(hide yes)
			(effects
				(font
					(size 1 1)
					(thickness 0.15)
				)
			)
		)
		(property "Val" "100n"
			(at 0 0 0)
			(unlocked yes)
			(layer "F.Fab")
			(hide yes)
			(effects
				(font
					(size 1 1)
					(thickness 0.15)
				)
			)
		)
		(property "License" "Apache-2.0"
			(at 0 0 0)
			(unlocked yes)
			(layer "F.Fab")
			(hide yes)
			(effects
				(font
					(size 1 1)
					(thickness 0.15)
				)
			)
		)
		(property "Author" "Antmicro"
			(at 0 0 0)
			(unlocked yes)
			(layer "F.Fab")
			(hide yes)
			(effects
				(font
					(size 1 1)
					(thickness 0.15)
				)
			)
		)
		(property "Voltage" "50V"
			(at 0 0 0)
			(unlocked yes)
			(layer "F.Fab")
			(hide yes)
			(effects
				(font
					(size 1 1)
					(thickness 0.15)
				)
			)
		)
		(property "Dielectric" "X5R"
			(at 0 0 0)
			(unlocked yes)
			(layer "F.Fab")
			(hide yes)
			(effects
				(font
					(size 1 1)
					(thickness 0.15)
				)
			)
		)
		(sheetname "/Power input/")
		(sheetfile "power_input.kicad_sch")
		(attr smd)
		(fp_rect
			(start -0.925 -0.47)
			(end 0.925 0.47)
			(stroke
				(width 0.05)
				(type default)
			)
			(fill no)
			(layer "F.CrtYd")
		)
		(fp_line
			(start -0.494 -0.25)
			(end 0.504 -0.25)
			(stroke
				(width 0.15)
				(type solid)
			)
			(layer "F.Fab")
		)
		(fp_line
			(start -0.494 0.248)
			(end -0.494 -0.25)
			(stroke
				(width 0.15)
				(type solid)
			)
			(layer "F.Fab")
		)
		(fp_line
			(start 0.504 -0.25)
			(end 0.504 0.248)
			(stroke
				(width 0.15)
				(type solid)
			)
			(layer "F.Fab")
		)
		(fp_line
			(start 0.504 0.248)
			(end -0.494 0.248)
			(stroke
				(width 0.15)
				(type solid)
			)
			(layer "F.Fab")
		)
		(fp_text user "${REFERENCE}"
			(at -0.939 4.599 0)
			(layer "F.Fab")
			(effects
				(font
					(size 0.7 0.7)
					(thickness 0.15)
				)
				(justify left bottom)
			)
		)
		(fp_text user "License: Apache-2.0"
			(at -0.939 5.799 0)
			(layer "F.Fab")
			(effects
				(font
					(size 0.7 0.7)
					(thickness 0.15)
				)
				(justify left bottom)
			)
		)
		(fp_text user "Author: Antmicro"
			(at -0.939 3.399 0)
			(layer "F.Fab")
			(effects
				(font
					(size 0.7 0.7)
					(thickness 0.15)
				)
				(justify left bottom)
			)
		)
		(pad "1" smd roundrect
			(at -0.48 0)
			(size 0.59 0.64)
			(layers "F.Cu" "F.Mask" "F.Paste")
			(roundrect_rratio 0.25)
			(net 348 "/Power input/5V_PHASE")
			(pintype "passive")
		)
		(pad "2" smd roundrect
			(at 0.48 0)
			(size 0.59 0.64)
			(layers "F.Cu" "F.Mask" "F.Paste")
			(roundrect_rratio 0.25)
			(net 347 "/Power input/5V_BOOT")
			(pintype "passive")
		)
	)
	(footprint "antmicro-footprints:VQFN-HR-9_2x1.5mm"
		(layer "F.Cu")
		(at 154.450001 110.15)
		(property "Reference" "U11"
			(at 13.650003 17.049998 0)
			(layer "F.SilkS")
			(effects
				(font
					(size 0.7 0.7)
					(thickness 0.15)
				)
			)
		)
		(property "Value" "TPS566231P"
			(at -1.65 2.15 0)
			(layer "F.Fab")
			(effects
				(font
					(size 0.7 0.7)
					(thickness 0.15)
				)
				(justify left bottom)
			)
		)
		(property "Datasheet" "https://www.ti.com/lit/ds/symlink/tps566231.pdf"
			(at 0 -0.045 0)
			(layer "F.Fab")
			(effects
				(font
					(size 0.7 0.7)
					(thickness 0.15)
				)
				(justify left bottom)
			)
		)
		(property "Description" "Switching Voltage Regulators 3-V to 18-V, 6-A synchronous buck converter"
			(at -1.45 3.65 0)
			(layer "F.Fab")
			(effects
				(font
					(size 0.7 0.7)
					(thickness 0.15)
				)
				(justify left bottom)
			)
		)
		(property "Manufacturer" "Texas Instruments"
			(at 0 0 0)
			(unlocked yes)
			(layer "F.Fab")
			(hide yes)
			(effects
				(font
					(size 1 1)
					(thickness 0.15)
				)
			)
		)
		(property "MPN" "TPS566231PRQFR"
			(at 0 0 0)
			(unlocked yes)
			(layer "F.Fab")
			(hide yes)
			(effects
				(font
					(size 1 1)
					(thickness 0.15)
				)
			)
		)
		(property "Author" "Antmicro"
			(at 0 0 0)
			(unlocked yes)
			(layer "F.Fab")
			(hide yes)
			(effects
				(font
					(size 1 1)
					(thickness 0.15)
				)
			)
		)
		(property "License" "Apache-2.0"
			(at 0 0 0)
			(unlocked yes)
			(layer "F.Fab")
			(hide yes)
			(effects
				(font
					(size 1 1)
					(thickness 0.15)
				)
			)
		)
		(sheetname "/X710 DCDC converters/")
		(sheetfile "DCDC_converters_X710.kicad_sch")
		(attr smd)
		(fp_line
			(start -1 -0.945)
			(end -0.695 -0.945)
			(stroke
				(width 0.15)
				(type solid)
			)
			(layer "F.SilkS")
		)
		(fp_line
			(start -1 0.945)
			(end -0.695 0.945)
			(stroke
				(width 0.15)
				(type solid)
			)
			(layer "F.SilkS")
		)
		(fp_line
			(start 1 -0.945)
			(end 0.695 -0.945)
			(stroke
				(width 0.15)
				(type solid)
			)
			(layer "F.SilkS")
		)
		(fp_line
			(start 1 0.945)
			(end 0.2 0.945)
			(stroke
				(width 0.15)
				(type solid)
			)
			(layer "F.SilkS")
		)
		(fp_circle
			(center -1.18 -0.77)
			(end -1.13 -0.77)
			(stroke
				(width 0.15)
				(type solid)
			)
			(fill yes)
			(layer "F.SilkS")
		)
		(fp_rect
			(start -1.3 -1.05)
			(end 1.3 1.05)
			(stroke
				(width 0.05)
				(type solid)
			)
			(fill no)
			(layer "F.CrtYd")
		)
		(fp_rect
			(start -1 -0.75)
			(end 1 0.75)
			(stroke
				(width 0.15)
				(type solid)
			)
			(fill no)
			(layer "F.Fab")
		)
		(fp_text user "License: Apache-2.0"
			(at -1.65 5.75 0)
			(layer "F.Fab")
			(effects
				(font
					(size 0.7 0.7)
					(thickness 0.15)
				)
				(justify left bottom)
			)
		)
		(fp_text user "${REFERENCE}"
			(at -1.65 3.35 0)
			(layer "F.Fab")
			(effects
				(font
					(size 0.7 0.7)
					(thickness 0.15)
				)
				(justify left bottom)
			)
		)
		(fp_text user "Author: Antmicro"
			(at -1.65 4.55 0)
			(layer "F.Fab")
			(effects
				(font
					(size 0.7 0.7)
					(thickness 0.15)
				)
				(justify left bottom)
			)
		)
		(pad "1" smd roundrect
			(at -0.925 -0.5)
			(size 0.55 0.25)
			(layers "F.Cu" "F.Mask" "F.Paste")
			(roundrect_rratio 0.125)
			(net 108 "/X710 DCDC converters/1V88_VCC")
			(pinfunction "V_{CC}")
			(pintype "passive")
		)
		(pad "2" smd roundrect
			(at -0.925 0)
			(size 0.55 0.25)
			(layers "F.Cu" "F.Mask" "F.Paste")
			(roundrect_rratio 0.125)
			(net 337 "/X710 DCDC converters/1V88_FB")
			(pinfunction "FB")
			(pintype "input")
		)
		(pad "3" smd roundrect
			(at -0.925 0.5)
			(size 0.55 0.25)
			(layers "F.Cu" "F.Mask" "F.Paste")
			(roundrect_rratio 0.125)
			(net 384 "/X710 DCDC converters/1V88_EN")
			(pinfunction "EN")
			(pintype "input")
		)
		(pad "4" smd roundrect
			(at -0.25 0.45)
			(size 0.25 1)
			(layers "F.Cu" "F.Mask" "F.Paste")
			(roundrect_rratio 0.125)
			(net 23 "GND")
			(pinfunction "PGND")
			(pintype "power_in")
		)
		(pad "5" smd roundrect
			(at 0.925 0.5)
			(size 0.55 0.25)
			(layers "F.Cu" "F.Mask" "F.Paste")
			(roundrect_rratio 0.125)
			(net 40 "+5V")
			(pinfunction "V_{IN}")
			(pintype "power_in")
		)
		(pad "6" smd roundrect
			(at 0.925 0)
			(size 0.55 0.25)
			(layers "F.Cu" "F.Mask" "F.Paste")
			(roundrect_rratio 0.125)
			(net 40 "+5V")
			(pinfunction "V_{IN}")
			(pintype "passive")
		)
		(pad "7" smd roundrect
			(at 0.925 -0.5)
			(size 0.55 0.25)
			(layers "F.Cu" "F.Mask" "F.Paste")
			(roundrect_rratio 0.125)
			(net 302 "/X710 DCDC converters/1V88_BST")
			(pinfunction "BST")
			(pintype "passive")
		)
		(pad "8" smd roundrect
			(at 0.25 -0.3)
			(size 0.25 1.3)
			(layers "F.Cu" "F.Mask" "F.Paste")
			(roundrect_rratio 0.125)
			(net 241 "/X710 DCDC converters/1V88_SW")
			(pinfunction "SW")
			(pintype "power_out")
		)
		(pad "9" smd roundrect
			(at -0.25 -0.675)
			(size 0.25 0.55)
			(layers "F.Cu" "F.Mask" "F.Paste")
			(roundrect_rratio 0.125)
			(net 380 "/X710 DCDC converters/1V88_PG")
			(pinfunction "PG")
			(pintype "passive")
		)
	)
	(footprint "antmicro-footprints:C_0603_1608Metric_EIA"
		(layer "F.Cu")
		(at 151.850001 105.600002 90)
		(descr "Capacitor SMD 0603, IPC-7351 Density Level A")
		(tags "Capacitor 0603")
		(property "Reference" "C146"
			(at -17.849995 14.449998 90)
			(layer "F.SilkS")
			(effects
				(font
					(size 0.7 0.7)
					(thickness 0.15)
				)
			)
		)
		(property "Value" "C_22u_16V_0603"
			(at -1.42757 1.770288 90)
			(layer "F.Fab")
			(effects
				(font
					(size 0.7 0.7)
					(thickness 0.15)
				)
				(justify left bottom)
			)
		)
		(property "Datasheet" "https://product.samsungsem.com/mlcc/CL10A226MO7JZN.do"
			(at 0 0 90)
			(layer "F.Fab")
			(hide yes)
			(effects
				(font
					(size 1.27 1.27)
					(thickness 0.15)
				)
			)
		)
		(property "Description" "SMD Multilayer Ceramic Capacitor"
			(at 0 0 90)
			(layer "F.Fab")
			(hide yes)
			(effects
				(font
					(size 1.27 1.27)
					(thickness 0.15)
				)
			)
		)
		(property "MPN" "CL10A226MO7JZNC"
			(at 0 0 90)
			(unlocked yes)
			(layer "F.Fab")
			(hide yes)
			(effects
				(font
					(size 1 1)
					(thickness 0.15)
				)
			)
		)
		(property "Manufacturer" "Samsung Electro-Mechanics"
			(at 0 0 90)
			(unlocked yes)
			(layer "F.Fab")
			(hide yes)
			(effects
				(font
					(size 1 1)
					(thickness 0.15)
				)
			)
		)
		(property "License" "Apache-2.0"
			(at 0 0 90)
			(unlocked yes)
			(layer "F.Fab")
			(hide yes)
			(effects
				(font
					(size 1 1)
					(thickness 0.15)
				)
			)
		)
		(property "Author" "Antmicro"
			(at 0 0 90)
			(unlocked yes)
			(layer "F.Fab")
			(hide yes)
			(effects
				(font
					(size 1 1)
					(thickness 0.15)
				)
			)
		)
		(property "Val" "22u"
			(at 0 0 90)
			(unlocked yes)
			(layer "F.Fab")
			(hide yes)
			(effects
				(font
					(size 1 1)
					(thickness 0.15)
				)
			)
		)
		(property "Voltage" "16V"
			(at 0 0 90)
			(unlocked yes)
			(layer "F.Fab")
			(hide yes)
			(effects
				(font
					(size 1 1)
					(thickness 0.15)
				)
			)
		)
		(property "Dielectric" ""
			(at 0 0 90)
			(unlocked yes)
			(layer "F.Fab")
			(hide yes)
			(effects
				(font
					(size 1 1)
					(thickness 0.15)
				)
			)
		)
		(sheetname "/X710 DCDC converters/")
		(sheetfile "DCDC_converters_X710.kicad_sch")
		(attr smd)
		(fp_line
			(start -0.15 -0.55)
			(end 0.15 -0.55)
			(stroke
				(width 0.15)
				(type solid)
			)
			(layer "F.SilkS")
		)
		(fp_line
			(start -0.15 0.55)
			(end 0.15 0.55)
			(stroke
				(width 0.15)
				(type solid)
			)
			(layer "F.SilkS")
		)
		(fp_rect
			(start -1.25 -0.65)
			(end 1.25 0.65)
			(stroke
				(width 0.05)
				(type solid)
			)
			(fill no)
			(layer "F.CrtYd")
		)
		(fp_rect
			(start -0.8 -0.45)
			(end 0.8 0.45)
			(stroke
				(width 0.15)
				(type solid)
			)
			(fill no)
			(layer "F.Fab")
		)
		(fp_text user "${REFERENCE}"
			(at -1.682 3.895 90)
			(layer "F.Fab")
			(effects
				(font
					(size 0.7 0.7)
					(thickness 0.15)
				)
				(justify left bottom)
			)
		)
		(fp_text user "License: Apache-2.0"
			(at -1.682 5.895 90)
			(layer "F.Fab")
			(effects
				(font
					(size 0.7 0.7)
					(thickness 0.15)
				)
				(justify left bottom)
			)
		)
		(fp_text user "Author: Antmicro"
			(at -1.682 4.894 90)
			(layer "F.Fab")
			(effects
				(font
					(size 0.7 0.7)
					(thickness 0.15)
				)
				(justify left bottom)
			)
		)
		(pad "1" smd roundrect
			(at -0.7 0 90)
			(size 0.8 1.1)
			(layers "F.Cu" "F.Mask" "F.Paste")
			(roundrect_rratio 0.2)
			(net 23 "GND")
			(pintype "passive")
		)
		(pad "2" smd roundrect
			(at 0.7 0 90)
			(size 0.8 1.1)
			(layers "F.Cu" "F.Mask" "F.Paste")
			(roundrect_rratio 0.2)
			(net 338 "/X710 DCDC converters/+1V88_OUT")
			(pintype "passive")
		)
	)
	(footprint "antmicro-footprints:C_0603_1608Metric_EIA"
		(layer "F.Cu")
		(at 136.450002 105.600001 90)
		(descr "Capacitor SMD 0603, IPC-7351 Density Level A")
		(tags "Capacitor 0603")
		(property "Reference" "C145"
			(at -17.849995 16.849997 90)
			(layer "F.SilkS")
			(effects
				(font
					(size 0.7 0.7)
					(thickness 0.15)
				)
			)
		)
		(property "Value" "C_22u_16V_0603"
			(at -1.42757 1.770288 90)
			(layer "F.Fab")
			(effects
				(font
					(size 0.7 0.7)
					(thickness 0.15)
				)
				(justify left bottom)
			)
		)
		(property "Datasheet" "https://product.samsungsem.com/mlcc/CL10A226MO7JZN.do"
			(at 0 0 90)
			(layer "F.Fab")
			(hide yes)
			(effects
				(font
					(size 1.27 1.27)
					(thickness 0.15)
				)
			)
		)
		(property "Description" "SMD Multilayer Ceramic Capacitor"
			(at 0 0 90)
			(layer "F.Fab")
			(hide yes)
			(effects
				(font
					(size 1.27 1.27)
					(thickness 0.15)
				)
			)
		)
		(property "MPN" "CL10A226MO7JZNC"
			(at 0 0 90)
			(unlocked yes)
			(layer "F.Fab")
			(hide yes)
			(effects
				(font
					(size 1 1)
					(thickness 0.15)
				)
			)
		)
		(property "Manufacturer" "Samsung Electro-Mechanics"
			(at 0 0 90)
			(unlocked yes)
			(layer "F.Fab")
			(hide yes)
			(effects
				(font
					(size 1 1)
					(thickness 0.15)
				)
			)
		)
		(property "License" "Apache-2.0"
			(at 0 0 90)
			(unlocked yes)
			(layer "F.Fab")
			(hide yes)
			(effects
				(font
					(size 1 1)
					(thickness 0.15)
				)
			)
		)
		(property "Author" "Antmicro"
			(at 0 0 90)
			(unlocked yes)
			(layer "F.Fab")
			(hide yes)
			(effects
				(font
					(size 1 1)
					(thickness 0.15)
				)
			)
		)
		(property "Val" "22u"
			(at 0 0 90)
			(unlocked yes)
			(layer "F.Fab")
			(hide yes)
			(effects
				(font
					(size 1 1)
					(thickness 0.15)
				)
			)
		)
		(property "Voltage" "16V"
			(at 0 0 90)
			(unlocked yes)
			(layer "F.Fab")
			(hide yes)
			(effects
				(font
					(size 1 1)
					(thickness 0.15)
				)
			)
		)
		(property "Dielectric" ""
			(at 0 0 90)
			(unlocked yes)
			(layer "F.Fab")
			(hide yes)
			(effects
				(font
					(size 1 1)
					(thickness 0.15)
				)
			)
		)
		(sheetname "/X710 DCDC converters/")
		(sheetfile "DCDC_converters_X710.kicad_sch")
		(attr smd)
		(fp_line
			(start -0.15 -0.55)
			(end 0.15 -0.55)
			(stroke
				(width 0.15)
				(type solid)
			)
			(layer "F.SilkS")
		)
		(fp_line
			(start -0.15 0.55)
			(end 0.15 0.55)
			(stroke
				(width 0.15)
				(type solid)
			)
			(layer "F.SilkS")
		)
		(fp_rect
			(start -1.25 -0.65)
			(end 1.25 0.65)
			(stroke
				(width 0.05)
				(type solid)
			)
			(fill no)
			(layer "F.CrtYd")
		)
		(fp_rect
			(start -0.8 -0.45)
			(end 0.8 0.45)
			(stroke
				(width 0.15)
				(type solid)
			)
			(fill no)
			(layer "F.Fab")
		)
		(fp_text user "License: Apache-2.0"
			(at -1.682 5.895 90)
			(layer "F.Fab")
			(effects
				(font
					(size 0.7 0.7)
					(thickness 0.15)
				)
				(justify left bottom)
			)
		)
		(fp_text user "Author: Antmicro"
			(at -1.682 4.894 90)
			(layer "F.Fab")
			(effects
				(font
					(size 0.7 0.7)
					(thickness 0.15)
				)
				(justify left bottom)
			)
		)
		(fp_text user "${REFERENCE}"
			(at -1.682 3.895 90)
			(layer "F.Fab")
			(effects
				(font
					(size 0.7 0.7)
					(thickness 0.15)
				)
				(justify left bottom)
			)
		)
		(pad "1" smd roundrect
			(at -0.7 0 90)
			(size 0.8 1.1)
			(layers "F.Cu" "F.Mask" "F.Paste")
			(roundrect_rratio 0.2)
			(net 23 "GND")
			(pintype "passive")
		)
		(pad "2" smd roundrect
			(at 0.7 0 90)
			(size 0.8 1.1)
			(layers "F.Cu" "F.Mask" "F.Paste")
			(roundrect_rratio 0.2)
			(net 335 "/X710 DCDC converters/+VCCD_OUT")
			(pintype "passive")
		)
	)
	(footprint "antmicro-footprints:R_0603_1608Metric"
		(layer "F.Cu")
		(at 142.8 103.050002 90)
		(descr "Resistor SMD 0603")
		(tags "resistor SMD 0603")
		(property "Reference" "R112"
			(at -17.649996 15.649999 90)
			(layer "F.SilkS")
			(effects
				(font
					(size 0.7 0.7)
					(thickness 0.15)
				)
			)
		)
		(property "Value" "R_0R_22.4A_0603"
			(at 0 1.6 90)
			(layer "F.Fab")
			(effects
				(font
					(size 0.7 0.7)
					(thickness 0.15)
				)
				(justify left bottom)
			)
		)
		(property "Datasheet" "https://fscdn.rohm.com/en/products/databook/datasheet/passive/resistor/chip_resistor/pmr-jpw-e.pdf"
			(at 0 0 90)
			(layer "F.Fab")
			(hide yes)
			(effects
				(font
					(size 1.27 1.27)
					(thickness 0.15)
				)
			)
		)
		(property "Description" "SMD Chip Resistor"
			(at 0 0 90)
			(layer "F.Fab")
			(hide yes)
			(effects
				(font
					(size 1.27 1.27)
					(thickness 0.15)
				)
			)
		)
		(property "MPN" "PMR03EZPJ000"
			(at 0 0 90)
			(unlocked yes)
			(layer "F.Fab")
			(hide yes)
			(effects
				(font
					(size 1 1)
					(thickness 0.15)
				)
			)
		)
		(property "Manufacturer" "ROHM Semiconductor"
			(at 0 0 90)
			(unlocked yes)
			(layer "F.Fab")
			(hide yes)
			(effects
				(font
					(size 1 1)
					(thickness 0.15)
				)
			)
		)
		(property "Val" "0R"
			(at 0 0 90)
			(unlocked yes)
			(layer "F.Fab")
			(hide yes)
			(effects
				(font
					(size 1 1)
					(thickness 0.15)
				)
			)
		)
		(property "Max. Curr." "22.4A"
			(at 0 0 90)
			(unlocked yes)
			(layer "F.Fab")
			(hide yes)
			(effects
				(font
					(size 1 1)
					(thickness 0.15)
				)
			)
		)
		(property "Author" "Antmicro"
			(at 0 0 90)
			(unlocked yes)
			(layer "F.Fab")
			(hide yes)
			(effects
				(font
					(size 1 1)
					(thickness 0.15)
				)
			)
		)
		(property "License" "Apache-2.0"
			(at 0 0 90)
			(unlocked yes)
			(layer "F.Fab")
			(hide yes)
			(effects
				(font
					(size 1 1)
					(thickness 0.15)
				)
			)
		)
		(property "Tolerance" "template_tolerance"
			(at 0 0 90)
			(unlocked yes)
			(layer "F.Fab")
			(hide yes)
			(effects
				(font
					(size 1 1)
					(thickness 0.15)
				)
			)
		)
		(sheetname "/X710 DCDC converters/")
		(sheetfile "DCDC_converters_X710.kicad_sch")
		(attr smd)
		(fp_line
			(start -0.15 -0.4)
			(end 0.15 -0.4)
			(stroke
				(width 0.15)
				(type solid)
			)
			(layer "F.SilkS")
		)
		(fp_line
			(start -0.15 0.4)
			(end 0.15 0.4)
			(stroke
				(width 0.15)
				(type solid)
			)
			(layer "F.SilkS")
		)
		(fp_rect
			(start -1.25 -0.65)
			(end 1.25 0.65)
			(stroke
				(width 0.05)
				(type solid)
			)
			(fill no)
			(layer "F.CrtYd")
		)
		(fp_rect
			(start -0.8 -0.4)
			(end 0.8 0.4)
			(stroke
				(width 0.15)
				(type solid)
			)
			(fill no)
			(layer "F.Fab")
		)
		(fp_text user "${REFERENCE}"
			(at -1.25 3.898 90)
			(layer "F.Fab")
			(effects
				(font
					(size 0.7 0.7)
					(thickness 0.15)
				)
				(justify left bottom)
			)
		)
		(fp_text user "License: Apache-2.0"
			(at -1.25 5.9 90)
			(layer "F.Fab")
			(effects
				(font
					(size 0.7 0.7)
					(thickness 0.15)
				)
				(justify left bottom)
			)
		)
		(fp_text user "Author: Antmicro"
			(at -1.25 4.9 90)
			(layer "F.Fab")
			(effects
				(font
					(size 0.7 0.7)
					(thickness 0.15)
				)
				(justify left bottom)
			)
		)
		(pad "1" smd roundrect
			(at -0.7 0 90)
			(size 0.8 1)
			(layers "F.Cu" "F.Mask" "F.Paste")
			(roundrect_rratio 0.2)
			(net 341 "/X710 DCDC converters/+DVDD_OUT")
			(pintype "passive")
		)
		(pad "2" smd roundrect
			(at 0.7 0 90)
			(size 0.8 1)
			(layers "F.Cu" "F.Mask" "F.Paste")
			(roundrect_rratio 0.2)
			(net 6 "DVDD")
			(pintype "passive")
		)
	)
	(footprint "antmicro-footprints:SOIC-8_5.3x5.3x2mm_P1.27mm"
		(layer "F.Cu")
		(at 131.75 77 90)
		(descr "8-Pin SOIC 208-mil")
		(property "Reference" "U19"
			(at 2.6 -3.15 90)
			(layer "F.SilkS")
			(effects
				(font
					(size 0.7 0.7)
					(thickness 0.15)
				)
				(justify left bottom)
			)
		)
		(property "Value" "AT25DF641A-SH"
			(at 0 3.8 90)
			(layer "F.Fab")
			(effects
				(font
					(size 0.7 0.7)
					(thickness 0.15)
				)
				(justify left bottom)
			)
		)
		(property "Datasheet" "https://eu.mouser.com/datasheet/3/1166/1/REN_DS-AT25DF641A-8693G-022022_unsecure_DST_20220220_1.pdf"
			(at 0 0 90)
			(layer "F.Fab")
			(hide yes)
			(effects
				(font
					(size 1.27 1.27)
					(thickness 0.15)
				)
			)
		)
		(property "Description" "NOR Flash 64 Mbit, 3.0V (2.7V to 3.6V), -40C to 85C, SOIC-W 208mil (Tape & Reel), Single, Dual SPI NOR flash"
			(at 0 0 90)
			(layer "F.Fab")
			(hide yes)
			(effects
				(font
					(size 1.27 1.27)
					(thickness 0.15)
				)
			)
		)
		(property "MPN" "AT25DF641A-SH-T "
			(at 0 0 90)
			(unlocked yes)
			(layer "F.Fab")
			(hide yes)
			(effects
				(font
					(size 1 1)
					(thickness 0.15)
				)
			)
		)
		(property "Manufacturer" "Renesas"
			(at 0 0 90)
			(unlocked yes)
			(layer "F.Fab")
			(hide yes)
			(effects
				(font
					(size 1 1)
					(thickness 0.15)
				)
			)
		)
		(property "Author" "Antmicro"
			(at 0 0 90)
			(unlocked yes)
			(layer "F.Fab")
			(hide yes)
			(effects
				(font
					(size 1 1)
					(thickness 0.15)
				)
			)
		)
		(property "License" "Apache-2.0"
			(at 0 0 90)
			(unlocked yes)
			(layer "F.Fab")
			(hide yes)
			(effects
				(font
					(size 1 1)
					(thickness 0.15)
				)
			)
		)
		(sheetname "/X710 flash memory/")
		(sheetfile "flash_x710.kicad_sch")
		(attr smd)
		(fp_line
			(start -2.8 -2.641)
			(end -4.4 -2.641)
			(stroke
				(width 0.15)
				(type solid)
			)
			(layer "F.SilkS")
		)
		(fp_circle
			(center -4.85 -1.905)
			(end -4.8 -1.855)
			(stroke
				(width 0.15)
				(type solid)
			)
			(fill yes)
			(layer "F.SilkS")
		)
		(fp_rect
			(start 4.675 -3)
			(end -4.675 3)
			(stroke
				(width 0.05)
				(type solid)
			)
			(fill no)
			(layer "F.CrtYd")
		)
		(fp_line
			(start 2.64 -2.641)
			(end 2.64 2.64)
			(stroke
				(width 0.15)
				(type solid)
			)
			(layer "F.Fab")
		)
		(fp_line
			(start -2.641 -2.641)
			(end 2.64 -2.641)
			(stroke
				(width 0.15)
				(type solid)
			)
			(layer "F.Fab")
		)
		(fp_line
			(start -2.641 -1.371)
			(end -1.371 -2.641)
			(stroke
				(width 0.15)
				(type solid)
			)
			(layer "F.Fab")
		)
		(fp_line
			(start 2.64 2.64)
			(end -2.641 2.64)
			(stroke
				(width 0.15)
				(type solid)
			)
			(layer "F.Fab")
		)
		(fp_line
			(start -2.641 2.64)
			(end -2.641 -2.641)
			(stroke
				(width 0.15)
				(type solid)
			)
			(layer "F.Fab")
		)
		(fp_text user "${REFERENCE}"
			(at -4.675 4.938 90)
			(layer "F.Fab")
			(effects
				(font
					(size 0.7 0.7)
					(thickness 0.15)
				)
				(justify left bottom)
			)
		)
		(fp_text user "License: Apache-2.0"
			(at -4.675 6.938 90)
			(layer "F.Fab")
			(effects
				(font
					(size 0.7 0.7)
					(thickness 0.15)
				)
				(justify left bottom)
			)
		)
		(fp_text user "Author: Antmicro"
			(at -4.675 5.938 90)
			(layer "F.Fab")
			(effects
				(font
					(size 0.7 0.7)
					(thickness 0.15)
				)
				(justify left bottom)
			)
		)
		(pad "1" smd roundrect
			(at -3.601 -1.905 180)
			(size 0.65 1.65)
			(layers "F.Cu" "F.Mask" "F.Paste")
			(roundrect_rratio 0.25)
			(net 350 "/X710 flash memory/FLASH.~{CE}")
			(pinfunction "~{CS}")
			(pintype "input")
		)
		(pad "2" smd roundrect
			(at -3.601 -0.635 180)
			(size 0.65 1.65)
			(layers "F.Cu" "F.Mask" "F.Paste")
			(roundrect_rratio 0.25)
			(net 351 "/X710 flash memory/FLASH.MISO")
			(pinfunction "SO")
			(pintype "bidirectional")
		)
		(pad "3" smd roundrect
			(at -3.601 0.633 180)
			(size 0.65 1.65)
			(layers "F.Cu" "F.Mask" "F.Paste")
			(roundrect_rratio 0.25)
			(net 388 "/X710 flash memory/~{WP}")
			(pinfunction "~{WP}")
			(pintype "bidirectional")
		)
		(pad "4" smd roundrect
			(at -3.601 1.904 180)
			(size 0.65 1.65)
			(layers "F.Cu" "F.Mask" "F.Paste")
			(roundrect_rratio 0.25)
			(net 23 "GND")
			(pinfunction "GND")
			(pintype "power_in")
		)
		(pad "5" smd roundrect
			(at 3.6 1.904 180)
			(size 0.65 1.65)
			(layers "F.Cu" "F.Mask" "F.Paste")
			(roundrect_rratio 0.25)
			(net 352 "/X710 flash memory/FLASH.MOSI")
			(pinfunction "SI")
			(pintype "bidirectional")
		)
		(pad "6" smd roundrect
			(at 3.6 0.633 180)
			(size 0.65 1.65)
			(layers "F.Cu" "F.Mask" "F.Paste")
			(roundrect_rratio 0.25)
			(net 353 "/X710 flash memory/FLASH.CLK")
			(pinfunction "SCK")
			(pintype "input")
		)
		(pad "7" smd roundrect
			(at 3.6 -0.635 180)
			(size 0.65 1.65)
			(layers "F.Cu" "F.Mask" "F.Paste")
			(roundrect_rratio 0.25)
			(net 387 "/X710 flash memory/~{HOLD}")
			(pinfunction "~{HOLD}")
			(pintype "bidirectional")
		)
		(pad "8" smd roundrect
			(at 3.6 -1.905 180)
			(size 0.65 1.65)
			(layers "F.Cu" "F.Mask" "F.Paste")
			(roundrect_rratio 0.25)
			(net 343 "/X710 flash memory/+3V3_FLASH")
			(pinfunction "VCC")
			(pintype "power_in")
		)
	)
	(footprint "antmicro-footprints:Heatsink_ATS-61500R-C2-R0"
		(layer "F.Cu")
		(at 150.039651 85.998391 180)
		(property "Reference" "H1"
			(at -1.995 -2.5 180)
			(unlocked yes)
			(layer "F.SilkS")
			(hide yes)
			(effects
				(font
					(size 0.7 0.7)
					(thickness 0.15)
				)
				(justify left bottom)
			)
		)
		(property "Value" "Heatsink_ATS-61500R-C2-R0"
			(at 0.003 27.94 180)
			(unlocked yes)
			(layer "F.Fab")
			(effects
				(font
					(size 0.7 0.7)
					(thickness 0.15)
				)
				(justify left bottom)
			)
		)
		(property "Datasheet" "https://www.qats.com/DataSheet/ATS-61500-Series-C2-R0"
			(at 0 0 180)
			(layer "F.Fab")
			(hide yes)
			(effects
				(font
					(size 1.27 1.27)
					(thickness 0.15)
				)
			)
		)
		(property "Description" "Heat Sinks fanSINK Assembly with Mounting Hardware"
			(at 0 0 180)
			(layer "F.Fab")
			(hide yes)
			(effects
				(font
					(size 1.27 1.27)
					(thickness 0.15)
				)
			)
		)
		(property "MPN" "ATS-61500R-C2-R0"
			(at 0 0 180)
			(unlocked yes)
			(layer "F.Fab")
			(hide yes)
			(effects
				(font
					(size 1 1)
					(thickness 0.15)
				)
			)
		)
		(property "Manufacturer" "Advanced Thermal Solutions"
			(at 0 0 180)
			(unlocked yes)
			(layer "F.Fab")
			(hide yes)
			(effects
				(font
					(size 1 1)
					(thickness 0.15)
				)
			)
		)
		(property "Author" "Antmicro"
			(at 0 0 180)
			(unlocked yes)
			(layer "F.Fab")
			(hide yes)
			(effects
				(font
					(size 1 1)
					(thickness 0.15)
				)
			)
		)
		(property "License" "Apache-2.0"
			(at 0 0 180)
			(unlocked yes)
			(layer "F.Fab")
			(hide yes)
			(effects
				(font
					(size 1 1)
					(thickness 0.15)
				)
			)
		)
		(property ki_fp_filters "Heatsink_*")
		(sheetname "/")
		(sheetfile "thunderbolt-to-10gbe-adapter.kicad_sch")
		(attr exclude_from_pos_files)
		(fp_circle
			(center 22 22)
			(end 26.22 22)
			(stroke
				(width 0.05)
				(type solid)
			)
			(fill no)
			(layer "F.CrtYd")
		)
		(fp_circle
			(center 22 -22)
			(end 26.22 -22)
			(stroke
				(width 0.05)
				(type solid)
			)
			(fill no)
			(layer "F.CrtYd")
		)
		(fp_circle
			(center -22 22)
			(end -17.78 22)
			(stroke
				(width 0.05)
				(type solid)
			)
			(fill no)
			(layer "F.CrtYd")
		)
		(fp_circle
			(center -22 -22)
			(end -17.78 -22)
			(stroke
				(width 0.05)
				(type solid)
			)
			(fill no)
			(layer "F.CrtYd")
		)
		(fp_text user "${REFERENCE}"
			(at -27.32 30.52 180)
			(layer "F.Fab")
			(effects
				(font
					(size 0.7 0.7)
					(thickness 0.15)
				)
				(justify left bottom)
			)
		)
		(fp_text user "Suggested mounting holes diameter: 3.18 mm"
			(at -9.07 -0.18 180)
			(layer "F.Fab")
			(effects
				(font
					(size 0.7 0.7)
					(thickness 0.15)
				)
				(justify left bottom)
			)
		)
		(fp_text user "License: Apache-2.0"
			(at -27.32 29.32 180)
			(layer "F.Fab")
			(effects
				(font
					(size 0.7 0.7)
					(thickness 0.15)
				)
				(justify left bottom)
			)
		)
		(fp_text user "Author: Antmicro"
			(at -27.32 31.72 180)
			(layer "F.Fab")
			(effects
				(font
					(size 0.7 0.7)
					(thickness 0.15)
				)
				(justify left bottom)
			)
		)
		(zone
			(net 0)
			(net_name "")
			(layers "F.Cu" "B.Cu" "In1.Cu" "In2.Cu" "In3.Cu" "In4.Cu" "In5.Cu" "In6.Cu")
			(hatch edge 0.5)
			(connect_pads
				(clearance 0)
			)
			(min_thickness 0.25)
			(filled_areas_thickness no)
			(keepout
				(tracks not_allowed)
				(vias not_allowed)
				(pads allowed)
				(copperpour not_allowed)
				(footprints allowed)
			)
			(placement
				(enabled no)
				(sheetname "")
			)
			(fill
				(thermal_gap 0.5)
				(thermal_bridge_width 0.5)
			)
			(polygon
				(pts
					(xy 126.019294 108.013761) (xy 126.039651 108.298391) (xy 126.100308 108.577226) (xy 126.20003 108.844591)
					(xy 126.336787 109.095043) (xy 126.507795 109.323482) (xy 126.709573 109.52526) (xy 126.938012 109.696268)
					(xy 127.188464 109.833025) (xy 127.455829 109.932747) (xy 127.734664 109.993404) (xy 128.019294 110.013761)
					(xy 128.303924 109.993404) (xy 128.582759 109.932747) (xy 128.850124 109.833025) (xy 129.100576 109.696268)
					(xy 129.329015 109.52526) (xy 129.530793 109.323482) (xy 129.701801 109.095043) (xy 129.838558 108.844591)
					(xy 129.93828 108.577226) (xy 129.998937 108.298391) (xy 130.019294 108.013761) (xy 129.998937 107.729131)
					(xy 129.93828 107.450296) (xy 129.838558 107.182931) (xy 129.701801 106.932479) (xy 129.530793 106.70404)
					(xy 129.329015 106.502262) (xy 129.100576 106.331254) (xy 128.850124 106.194497) (xy 128.582759 106.094775)
					(xy 128.303924 106.034118) (xy 128.019294 106.013761) (xy 127.734664 106.034118) (xy 127.455829 106.094775)
					(xy 127.188464 106.194497) (xy 126.938012 106.331254) (xy 126.709573 106.502262) (xy 126.507795 106.70404)
					(xy 126.336787 106.932479) (xy 126.20003 107.182931) (xy 126.100308 107.450296) (xy 126.039651 107.729131)
				)
			)
		)
		(zone
			(net 0)
			(net_name "")
			(layers "F.Cu" "B.Cu" "In1.Cu" "In2.Cu" "In3.Cu" "In4.Cu" "In5.Cu" "In6.Cu")
			(hatch edge 0.5)
			(connect_pads
				(clearance 0)
			)
			(min_thickness 0.25)
			(filled_areas_thickness no)
			(keepout
				(tracks not_allowed)
				(vias not_allowed)
				(pads allowed)
				(copperpour not_allowed)
				(footprints allowed)
			)
			(placement
				(enabled no)
				(sheetname "")
			)
			(fill
				(thermal_gap 0.5)
				(thermal_bridge_width 0.5)
			)
			(polygon
				(pts
					(xy 126.022158 64.017377) (xy 126.042515 64.302007) (xy 126.103172 64.580842) (xy 126.202894 64.848207)
					(xy 126.339651 65.098659) (xy 126.510659 65.327098) (xy 126.712437 65.528876) (xy 126.940876 65.699884)
					(xy 127.191328 65.836641) (xy 127.458693 65.936363) (xy 127.737528 65.99702) (xy 128.022158 66.017377)
					(xy 128.306788 65.99702) (xy 128.585623 65.936363) (xy 128.852988 65.836641) (xy 129.10344 65.699884)
					(xy 129.331879 65.528876) (xy 129.533657 65.327098) (xy 129.704665 65.098659) (xy 129.841422 64.848207)
					(xy 129.941144 64.580842) (xy 130.001801 64.302007) (xy 130.022158 64.017377) (xy 130.001801 63.732747)
					(xy 129.941144 63.453912) (xy 129.841422 63.186547) (xy 129.704665 62.936095) (xy 129.533657 62.707656)
					(xy 129.331879 62.505878) (xy 129.10344 62.33487) (xy 128.852988 62.198113) (xy 128.585623 62.098391)
					(xy 128.306788 62.037734) (xy 128.022158 62.017377) (xy 127.737528 62.037734) (xy 127.458693 62.098391)
					(xy 127.191328 62.198113) (xy 126.940876 62.33487) (xy 126.712437 62.505878) (xy 126.510659 62.707656)
					(xy 126.339651 62.936095) (xy 126.202894 63.186547) (xy 126.103172 63.453912) (xy 126.042515 63.732747)
				)
			)
		)
		(zone
			(net 0)
			(net_name "")
			(layers "F.Cu" "B.Cu" "In1.Cu" "In2.Cu" "In3.Cu" "In4.Cu" "In5.Cu" "In6.Cu")
			(hatch edge 0.5)
			(connect_pads
				(clearance 0)
			)
			(min_thickness 0.25)
			(filled_areas_thickness no)
			(keepout
				(tracks not_allowed)
				(vias not_allowed)
				(pads allowed)
				(copperpour not_allowed)
				(footprints allowed)
			)
			(placement
				(enabled no)
				(sheetname "")
			)
			(fill
				(thermal_gap 0.5)
				(thermal_bridge_width 0.5)
			)
			(polygon
				(pts
					(xy 170.039651 64.017377) (xy 170.060008 64.302007) (xy 170.120665 64.580842) (xy 170.220387 64.848207)
					(xy 170.357144 65.098659) (xy 170.528152 65.327098) (xy 170.72993 65.528876) (xy 170.958369 65.699884)
					(xy 171.208821 65.836641) (xy 171.476186 65.936363) (xy 171.755021 65.99702) (xy 172.039651 66.017377)
					(xy 172.324281 65.99702) (xy 172.603116 65.936363) (xy 172.870481 65.836641) (xy 173.120933 65.699884)
					(xy 173.349372 65.528876) (xy 173.55115 65.327098) (xy 173.722158 65.098659) (xy 173.858915 64.848207)
					(xy 173.958637 64.580842) (xy 174.019294 64.302007) (xy 174.039651 64.017377) (xy 174.019294 63.732747)
					(xy 173.958637 63.453912) (xy 173.858915 63.186547) (xy 173.722158 62.936095) (xy 173.55115 62.707656)
					(xy 173.349372 62.505878) (xy 173.120933 62.33487) (xy 172.870481 62.198113) (xy 172.603116 62.098391)
					(xy 172.324281 62.037734) (xy 172.039651 62.017377) (xy 171.755021 62.037734) (xy 171.476186 62.098391)
					(xy 171.208821 62.198113) (xy 170.958369 62.33487) (xy 170.72993 62.505878) (xy 170.528152 62.707656)
					(xy 170.357144 62.936095) (xy 170.220387 63.186547) (xy 170.120665 63.453912) (xy 170.060008 63.732747)
				)
			)
		)
		(zone
			(net 0)
			(net_name "")
			(layers "F.Cu" "B.Cu" "In1.Cu" "In2.Cu" "In3.Cu" "In4.Cu" "In5.Cu" "In6.Cu")
			(hatch edge 0.5)
			(connect_pads
				(clearance 0)
			)
			(min_thickness 0.25)
			(filled_areas_thickness no)
			(keepout
				(tracks not_allowed)
				(vias not_allowed)
				(pads allowed)
				(copperpour not_allowed)
				(footprints allowed)
			)
			(placement
				(enabled no)
				(sheetname "")
			)
			(fill
				(thermal_gap 0.5)
				(thermal_bridge_width 0.5)
			)
			(polygon
				(pts
					(xy 170.039651 107.998391) (xy 170.060008 108.283021) (xy 170.120665 108.561856) (xy 170.220387 108.829221)
					(xy 170.357144 109.079673) (xy 170.528152 109.308112) (xy 170.72993 109.50989) (xy 170.958369 109.680898)
					(xy 171.208821 109.817655) (xy 171.476186 109.917377) (xy 171.755021 109.978034) (xy 172.039651 109.998391)
					(xy 172.324281 109.978034) (xy 172.603116 109.917377) (xy 172.870481 109.817655) (xy 173.120933 109.680898)
					(xy 173.349372 109.50989) (xy 173.55115 109.308112) (xy 173.722158 109.079673) (xy 173.858915 108.829221)
					(xy 173.958637 108.561856) (xy 174.019294 108.283021) (xy 174.039651 107.998391) (xy 174.019294 107.713761)
					(xy 173.958637 107.434926) (xy 173.858915 107.167561) (xy 173.722158 106.917109) (xy 173.55115 106.68867)
					(xy 173.349372 106.486892) (xy 173.120933 106.315884) (xy 172.870481 106.179127) (xy 172.603116 106.079405)
					(xy 172.324281 106.018748) (xy 172.039651 105.998391) (xy 171.755021 106.018748) (xy 171.476186 106.079405)
					(xy 171.208821 106.179127) (xy 170.958369 106.315884) (xy 170.72993 106.486892) (xy 170.528152 106.68867)
					(xy 170.357144 106.917109) (xy 170.220387 107.167561) (xy 170.120665 107.434926) (xy 170.060008 107.713761)
				)
			)
		)
	)
	(footprint "antmicro-footprints:FB_0805_2012Metric"
		(layer "F.Cu")
		(at 129 138.4 180)
		(descr "FERRITE BEAD 0805")
		(tags "FERRITE BEAD 0805")
		(property "Reference" "FB1"
			(at 1.2 1 180)
			(layer "F.SilkS")
			(effects
				(font
					(size 0.7 0.7)
					(thickness 0.15)
				)
				(justify left bottom)
			)
		)
		(property "Value" "FB_30Z_8.5A_Murata-BLM21SN_0805"
			(at 0.001 1.801 180)
			(layer "F.Fab")
			(effects
				(font
					(size 0.7 0.7)
					(thickness 0.15)
				)
				(justify left bottom)
			)
		)
		(property "Datasheet" "https://www.murata.com/en-sg/products/productdata/8796738977822/ENFA0005.pdf?1519270210000"
			(at 0 0 180)
			(layer "F.Fab")
			(hide yes)
			(effects
				(font
					(size 1.27 1.27)
					(thickness 0.15)
				)
			)
		)
		(property "Description" "Ferrite Bead, 0805 [2012 Metric], 30 ohm, 8.5 A, BLM21SN, 0.004 ohm, ± 10ohm, DC power line"
			(at 0 0 180)
			(layer "F.Fab")
			(hide yes)
			(effects
				(font
					(size 1.27 1.27)
					(thickness 0.15)
				)
			)
		)
		(property "MPN" "BLM21SN300SZ1D"
			(at 0 0 180)
			(unlocked yes)
			(layer "F.Fab")
			(hide yes)
			(effects
				(font
					(size 1 1)
					(thickness 0.15)
				)
			)
		)
		(property "Manufacturer" "Murata"
			(at 0 0 180)
			(unlocked yes)
			(layer "F.Fab")
			(hide yes)
			(effects
				(font
					(size 1 1)
					(thickness 0.15)
				)
			)
		)
		(property "License" "Apache-2.0"
			(at 0 0 180)
			(unlocked yes)
			(layer "F.Fab")
			(hide yes)
			(effects
				(font
					(size 1 1)
					(thickness 0.15)
				)
			)
		)
		(property "Author" "Antmicro"
			(at 0 0 180)
			(unlocked yes)
			(layer "F.Fab")
			(hide yes)
			(effects
				(font
					(size 1 1)
					(thickness 0.15)
				)
			)
		)
		(property "Val" "30Z/8.5A"
			(at 0 0 180)
			(unlocked yes)
			(layer "F.Fab")
			(hide yes)
			(effects
				(font
					(size 1 1)
					(thickness 0.15)
				)
			)
		)
		(property "Current" ""
			(at 0 0 180)
			(unlocked yes)
			(layer "F.Fab")
			(hide yes)
			(effects
				(font
					(size 1 1)
					(thickness 0.15)
				)
			)
		)
		(sheetname "/PD and TB DC-DC/")
		(sheetfile "PD_and_TB_DC_DC.kicad_sch")
		(attr smd)
		(fp_line
			(start -0.299 -0.698)
			(end 0.299 -0.698)
			(stroke
				(width 0.15)
				(type solid)
			)
			(layer "F.SilkS")
		)
		(fp_line
			(start -0.319 0.698)
			(end 0.281 0.698)
			(stroke
				(width 0.15)
				(type solid)
			)
			(layer "F.SilkS")
		)
		(fp_rect
			(start 1.95 -0.9)
			(end -1.95 0.9)
			(stroke
				(width 0.05)
				(type default)
			)
			(fill no)
			(layer "F.CrtYd")
		)
		(fp_line
			(start 0.948 -0.676)
			(end 0.948 0.676)
			(stroke
				(width 0.15)
				(type solid)
			)
			(layer "F.Fab")
		)
		(fp_line
			(start -0.948 0.681)
			(end 0.948 0.681)
			(stroke
				(width 0.15)
				(type solid)
			)
			(layer "F.Fab")
		)
		(fp_line
			(start -0.948 -0.676)
			(end -0.948 0.676)
			(stroke
				(width 0.15)
				(type solid)
			)
			(layer "F.Fab")
		)
		(fp_line
			(start -0.948 -0.681)
			(end 0.948 -0.681)
			(stroke
				(width 0.15)
				(type solid)
			)
			(layer "F.Fab")
		)
		(fp_text user "Author: Antmicro"
			(at -1.44 5.001 180)
			(layer "F.Fab")
			(effects
				(font
					(size 0.7 0.7)
					(thickness 0.15)
				)
				(justify left bottom)
			)
		)
		(fp_text user "License: Apache-2.0"
			(at -1.44 6.201 180)
			(layer "F.Fab")
			(effects
				(font
					(size 0.7 0.7)
					(thickness 0.15)
				)
				(justify left bottom)
			)
		)
		(fp_text user "${REFERENCE}"
			(at -1.44 3.801 180)
			(layer "F.Fab")
			(effects
				(font
					(size 0.7 0.7)
					(thickness 0.15)
				)
				(justify left bottom)
			)
		)
		(pad "1" smd roundrect
			(at -1.1 0 180)
			(size 1.2 1.3)
			(layers "F.Cu" "F.Mask" "F.Paste")
			(roundrect_rratio 0.25)
			(net 182 "VBUS")
			(pintype "passive")
		)
		(pad "2" smd roundrect
			(at 1.1 0 180)
			(size 1.2 1.3)
			(layers "F.Cu" "F.Mask" "F.Paste")
			(roundrect_rratio 0.25)
			(net 53 "+5V_USB")
			(pintype "passive")
		)
	)
	(footprint "antmicro-footprints:R_0402_1005Metric"
		(layer "F.Cu")
		(at 158.105 69.074999 -90)
		(descr "Resistor SMD 0402")
		(tags "resistor SMD 0402")
		(property "Reference" "R171"
			(at -11.574999 -20.295 270)
			(layer "F.SilkS")
			(effects
				(font
					(size 0.7 0.7)
					(thickness 0.15)
				)
			)
		)
		(property "Value" "R_100R_0402"
			(at -1.011843 1.772047 270)
			(layer "F.Fab")
			(effects
				(font
					(size 0.7 0.7)
					(thickness 0.15)
				)
				(justify left bottom)
			)
		)
		(property "Datasheet" "https://www.bourns.com/docs/product-datasheets/cr.pdf"
			(at 0 0 270)
			(layer "F.Fab")
			(hide yes)
			(effects
				(font
					(size 1.27 1.27)
					(thickness 0.15)
				)
			)
		)
		(property "Description" "SMD Chip Resistor, 100 ohm, ± 1%, 62.5 mW, 0402 [1005 Metric], Thick Film, General Purpose"
			(at 0 0 270)
			(layer "F.Fab")
			(hide yes)
			(effects
				(font
					(size 1.27 1.27)
					(thickness 0.15)
				)
			)
		)
		(property "MPN" "CR0402-FX-1000GLF"
			(at 0 0 270)
			(unlocked yes)
			(layer "F.Fab")
			(hide yes)
			(effects
				(font
					(size 1 1)
					(thickness 0.15)
				)
			)
		)
		(property "Manufacturer" "Bourns"
			(at 0 0 270)
			(unlocked yes)
			(layer "F.Fab")
			(hide yes)
			(effects
				(font
					(size 1 1)
					(thickness 0.15)
				)
			)
		)
		(property "License" "Apache-2.0"
			(at 0 0 270)
			(unlocked yes)
			(layer "F.Fab")
			(hide yes)
			(effects
				(font
					(size 1 1)
					(thickness 0.15)
				)
			)
		)
		(property "Author" "Antmicro"
			(at 0 0 270)
			(unlocked yes)
			(layer "F.Fab")
			(hide yes)
			(effects
				(font
					(size 1 1)
					(thickness 0.15)
				)
			)
		)
		(property "Val" "100R"
			(at 0 0 270)
			(unlocked yes)
			(layer "F.Fab")
			(hide yes)
			(effects
				(font
					(size 1 1)
					(thickness 0.15)
				)
			)
		)
		(property "Tolerance" "1%"
			(at 0 0 270)
			(unlocked yes)
			(layer "F.Fab")
			(hide yes)
			(effects
				(font
					(size 1 1)
					(thickness 0.15)
				)
			)
		)
		(sheetname "/X710-AT2 Misc/")
		(sheetfile "x710-at2-mics.kicad_sch")
		(attr smd dnp)
		(fp_rect
			(start -0.925 -0.47)
			(end 0.925 0.47)
			(stroke
				(width 0.05)
				(type default)
			)
			(fill no)
			(layer "F.CrtYd")
		)
		(fp_rect
			(start -0.5 -0.25)
			(end 0.5 0.25)
			(stroke
				(width 0.15)
				(type solid)
			)
			(fill no)
			(layer "F.Fab")
		)
		(fp_text user "${REFERENCE}"
			(at -0.95 3.168 270)
			(layer "F.Fab")
			(effects
				(font
					(size 0.7 0.7)
					(thickness 0.15)
				)
				(justify left bottom)
			)
		)
		(fp_text user "License: Apache-2.0"
			(at -0.95 5.169 270)
			(layer "F.Fab")
			(effects
				(font
					(size 0.7 0.7)
					(thickness 0.15)
				)
				(justify left bottom)
			)
		)
		(fp_text user "Author: Antmicro"
			(at -0.95 4.169 270)
			(layer "F.Fab")
			(effects
				(font
					(size 0.7 0.7)
					(thickness 0.15)
				)
				(justify left bottom)
			)
		)
		(pad "1" smd roundrect
			(at -0.48 0 270)
			(size 0.59 0.64)
			(layers "F.Cu" "F.Mask" "F.Paste")
			(roundrect_rratio 0.25)
			(net 23 "GND")
			(pintype "passive")
		)
		(pad "2" smd roundrect
			(at 0.48 0 270)
			(size 0.59 0.64)
			(layers "F.Cu" "F.Mask" "F.Paste")
			(roundrect_rratio 0.25)
			(net 127 "/X710-AT2 Misc/~{DEV_DIS}")
			(pintype "passive")
		)
	)
	(footprint "antmicro-footprints:C_0805_2012Metric"
		(layer "F.Cu")
		(at 165.305 97.024999 180)
		(descr "Capacitor SMD 0805")
		(tags "capacitor SMD 0805")
		(property "Reference" "C179"
			(at -7.695 0 180)
			(layer "F.SilkS")
			(effects
				(font
					(size 0.7 0.7)
					(thickness 0.15)
				)
			)
		)
		(property "Value" "C_100u_0805"
			(at -2.055717 1.963152 180)
			(layer "F.Fab")
			(effects
				(font
					(size 0.7 0.7)
					(thickness 0.15)
				)
				(justify left bottom)
			)
		)
		(property "Datasheet" "https://www.murata.com/products/productdetail?partno=GRM21BR60J107ME15%23"
			(at 0 0 180)
			(layer "F.Fab")
			(hide yes)
			(effects
				(font
					(size 1.27 1.27)
					(thickness 0.15)
				)
			)
		)
		(property "Description" "SMD Multilayer Ceramic Capacitor, 100 µF, 6.3 V, 0805 [2012 Metric], ± 20%, X5R, GRM Series"
			(at 0 0 180)
			(layer "F.Fab")
			(hide yes)
			(effects
				(font
					(size 1.27 1.27)
					(thickness 0.15)
				)
			)
		)
		(property "MPN" "GRM21BR60J107ME15L"
			(at 0 0 180)
			(unlocked yes)
			(layer "F.Fab")
			(hide yes)
			(effects
				(font
					(size 1 1)
					(thickness 0.15)
				)
			)
		)
		(property "Manufacturer" "Murata"
			(at 0 0 180)
			(unlocked yes)
			(layer "F.Fab")
			(hide yes)
			(effects
				(font
					(size 1 1)
					(thickness 0.15)
				)
			)
		)
		(property "License" "Apache-2.0"
			(at 0 0 180)
			(unlocked yes)
			(layer "F.Fab")
			(hide yes)
			(effects
				(font
					(size 1 1)
					(thickness 0.15)
				)
			)
		)
		(property "Author" "Antmicro"
			(at 0 0 180)
			(unlocked yes)
			(layer "F.Fab")
			(hide yes)
			(effects
				(font
					(size 1 1)
					(thickness 0.15)
				)
			)
		)
		(property "Val" "100u"
			(at 0 0 180)
			(unlocked yes)
			(layer "F.Fab")
			(hide yes)
			(effects
				(font
					(size 1 1)
					(thickness 0.15)
				)
			)
		)
		(property "Voltage" ""
			(at 0 0 180)
			(unlocked yes)
			(layer "F.Fab")
			(hide yes)
			(effects
				(font
					(size 1 1)
					(thickness 0.15)
				)
			)
		)
		(property "Dielectric" ""
			(at 0 0 180)
			(unlocked yes)
			(layer "F.Fab")
			(hide yes)
			(effects
				(font
					(size 1 1)
					(thickness 0.15)
				)
			)
		)
		(property "Public" "False"
			(at 0 0 180)
			(unlocked yes)
			(layer "F.Fab")
			(hide yes)
			(effects
				(font
					(size 1 1)
					(thickness 0.15)
				)
			)
		)
		(sheetname "/X710-AT2 power/")
		(sheetfile "x710-at2-power.kicad_sch")
		(attr smd)
		(fp_line
			(start -0.3 0.7)
			(end 0.3 0.7)
			(stroke
				(width 0.15)
				(type solid)
			)
			(layer "F.SilkS")
		)
		(fp_line
			(start -0.3 -0.7)
			(end 0.3 -0.7)
			(stroke
				(width 0.15)
				(type solid)
			)
			(layer "F.SilkS")
		)
		(fp_rect
			(start 1.95 -0.9)
			(end -1.95 0.9)
			(stroke
				(width 0.05)
				(type default)
			)
			(fill no)
			(layer "F.CrtYd")
		)
		(fp_rect
			(start -0.95 -0.675)
			(end 0.95 0.675)
			(stroke
				(width 0.15)
				(type solid)
			)
			(fill no)
			(layer "F.Fab")
		)
		(fp_text user "${REFERENCE}"
			(at -1.9 3.947 180)
			(layer "F.Fab")
			(effects
				(font
					(size 0.7 0.7)
					(thickness 0.15)
				)
				(justify left bottom)
			)
		)
		(fp_text user "License: Apache-2.0"
			(at -1.9 4.947 180)
			(layer "F.Fab")
			(effects
				(font
					(size 0.7 0.7)
					(thickness 0.15)
				)
				(justify left bottom)
			)
		)
		(fp_text user "Author: Antmicro"
			(at -1.9 5.947 180)
			(layer "F.Fab")
			(effects
				(font
					(size 0.7 0.7)
					(thickness 0.15)
				)
				(justify left bottom)
			)
		)
		(pad "1" smd roundrect
			(at -1.1 0 180)
			(size 1.2 1.3)
			(layers "F.Cu" "F.Mask" "F.Paste")
			(roundrect_rratio 0.25)
			(net 23 "GND")
			(pintype "passive")
		)
		(pad "2" smd roundrect
			(at 1.1 0 180)
			(size 1.2 1.3)
			(layers "F.Cu" "F.Mask" "F.Paste")
			(roundrect_rratio 0.25)
			(net 14 "P1_AVDDL")
			(pintype "passive")
		)
	)
	(footprint "antmicro-footprints:VQFN-HR-9_2x1.5mm"
		(layer "F.Cu")
		(at 162.15 110.15)
		(property "Reference" "U12"
			(at 12.450003 17.049998 0)
			(layer "F.SilkS")
			(effects
				(font
					(size 0.7 0.7)
					(thickness 0.15)
				)
			)
		)
		(property "Value" "TPS566231P"
			(at -1.65 2.15 0)
			(layer "F.Fab")
			(effects
				(font
					(size 0.7 0.7)
					(thickness 0.15)
				)
				(justify left bottom)
			)
		)
		(property "Datasheet" "https://www.ti.com/lit/ds/symlink/tps566231.pdf"
			(at 0 -0.045 0)
			(layer "F.Fab")
			(effects
				(font
					(size 0.7 0.7)
					(thickness 0.15)
				)
				(justify left bottom)
			)
		)
		(property "Description" "Switching Voltage Regulators 3-V to 18-V, 6-A synchronous buck converter"
			(at -1.45 3.65 0)
			(layer "F.Fab")
			(effects
				(font
					(size 0.7 0.7)
					(thickness 0.15)
				)
				(justify left bottom)
			)
		)
		(property "Manufacturer" "Texas Instruments"
			(at 0 0 0)
			(unlocked yes)
			(layer "F.Fab")
			(hide yes)
			(effects
				(font
					(size 1 1)
					(thickness 0.15)
				)
			)
		)
		(property "MPN" "TPS566231PRQFR"
			(at 0 0 0)
			(unlocked yes)
			(layer "F.Fab")
			(hide yes)
			(effects
				(font
					(size 1 1)
					(thickness 0.15)
				)
			)
		)
		(property "Author" "Antmicro"
			(at 0 0 0)
			(unlocked yes)
			(layer "F.Fab")
			(hide yes)
			(effects
				(font
					(size 1 1)
					(thickness 0.15)
				)
			)
		)
		(property "License" "Apache-2.0"
			(at 0 0 0)
			(unlocked yes)
			(layer "F.Fab")
			(hide yes)
			(effects
				(font
					(size 1 1)
					(thickness 0.15)
				)
			)
		)
		(sheetname "/X710 DCDC converters/")
		(sheetfile "DCDC_converters_X710.kicad_sch")
		(attr smd)
		(fp_line
			(start -1 -0.945)
			(end -0.695 -0.945)
			(stroke
				(width 0.15)
				(type solid)
			)
			(layer "F.SilkS")
		)
		(fp_line
			(start -1 0.945)
			(end -0.695 0.945)
			(stroke
				(width 0.15)
				(type solid)
			)
			(layer "F.SilkS")
		)
		(fp_line
			(start 1 -0.945)
			(end 0.695 -0.945)
			(stroke
				(width 0.15)
				(type solid)
			)
			(layer "F.SilkS")
		)
		(fp_line
			(start 1 0.945)
			(end 0.2 0.945)
			(stroke
				(width 0.15)
				(type solid)
			)
			(layer "F.SilkS")
		)
		(fp_circle
			(center -1.18 -0.77)
			(end -1.13 -0.77)
			(stroke
				(width 0.15)
				(type solid)
			)
			(fill yes)
			(layer "F.SilkS")
		)
		(fp_rect
			(start -1.3 -1.05)
			(end 1.3 1.05)
			(stroke
				(width 0.05)
				(type solid)
			)
			(fill no)
			(layer "F.CrtYd")
		)
		(fp_rect
			(start -1 -0.75)
			(end 1 0.75)
			(stroke
				(width 0.15)
				(type solid)
			)
			(fill no)
			(layer "F.Fab")
		)
		(fp_text user "Author: Antmicro"
			(at -1.65 4.55 0)
			(layer "F.Fab")
			(effects
				(font
					(size 0.7 0.7)
					(thickness 0.15)
				)
				(justify left bottom)
			)
		)
		(fp_text user "${REFERENCE}"
			(at -1.65 3.35 0)
			(layer "F.Fab")
			(effects
				(font
					(size 0.7 0.7)
					(thickness 0.15)
				)
				(justify left bottom)
			)
		)
		(fp_text user "License: Apache-2.0"
			(at -1.65 5.75 0)
			(layer "F.Fab")
			(effects
				(font
					(size 0.7 0.7)
					(thickness 0.15)
				)
				(justify left bottom)
			)
		)
		(pad "1" smd roundrect
			(at -0.925 -0.5)
			(size 0.55 0.25)
			(layers "F.Cu" "F.Mask" "F.Paste")
			(roundrect_rratio 0.125)
			(net 109 "/X710 DCDC converters/1V0_VCC")
			(pinfunction "V_{CC}")
			(pintype "passive")
		)
		(pad "2" smd roundrect
			(at -0.925 0)
			(size 0.55 0.25)
			(layers "F.Cu" "F.Mask" "F.Paste")
			(roundrect_rratio 0.125)
			(net 340 "/X710 DCDC converters/1V0_FB")
			(pinfunction "FB")
			(pintype "input")
		)
		(pad "3" smd roundrect
			(at -0.925 0.5)
			(size 0.55 0.25)
			(layers "F.Cu" "F.Mask" "F.Paste")
			(roundrect_rratio 0.125)
			(net 385 "/X710 DCDC converters/1V0_EN")
			(pinfunction "EN")
			(pintype "input")
		)
		(pad "4" smd roundrect
			(at -0.25 0.45)
			(size 0.25 1)
			(layers "F.Cu" "F.Mask" "F.Paste")
			(roundrect_rratio 0.125)
			(net 23 "GND")
			(pinfunction "PGND")
			(pintype "power_in")
		)
		(pad "5" smd roundrect
			(at 0.925 0.5)
			(size 0.55 0.25)
			(layers "F.Cu" "F.Mask" "F.Paste")
			(roundrect_rratio 0.125)
			(net 40 "+5V")
			(pinfunction "V_{IN}")
			(pintype "power_in")
		)
		(pad "6" smd roundrect
			(at 0.925 0)
			(size 0.55 0.25)
			(layers "F.Cu" "F.Mask" "F.Paste")
			(roundrect_rratio 0.125)
			(net 40 "+5V")
			(pinfunction "V_{IN}")
			(pintype "passive")
		)
		(pad "7" smd roundrect
			(at 0.925 -0.5)
			(size 0.55 0.25)
			(layers "F.Cu" "F.Mask" "F.Paste")
			(roundrect_rratio 0.125)
			(net 307 "/X710 DCDC converters/1V0_BST")
			(pinfunction "BST")
			(pintype "passive")
		)
		(pad "8" smd roundrect
			(at 0.25 -0.3)
			(size 0.25 1.3)
			(layers "F.Cu" "F.Mask" "F.Paste")
			(roundrect_rratio 0.125)
			(net 310 "/X710 DCDC converters/1V0_SW")
			(pinfunction "SW")
			(pintype "power_out")
		)
		(pad "9" smd roundrect
			(at -0.25 -0.675)
			(size 0.25 0.55)
			(layers "F.Cu" "F.Mask" "F.Paste")
			(roundrect_rratio 0.125)
			(net 381 "/X710 DCDC converters/1V0_PG")
			(pinfunction "PG")
			(pintype "passive")
		)
	)
	(footprint "antmicro-footprints:C_0402_1005Metric"
		(layer "F.Cu")
		(at 121.948107 88.554085 90)
		(descr "Capacitor SMD 0402")
		(tags "capacitor SMD 0402")
		(property "Reference" "C63"
			(at -3.245915 0.451893 90)
			(layer "F.SilkS")
			(effects
				(font
					(size 0.7 0.7)
					(thickness 0.15)
				)
				(justify left bottom)
			)
		)
		(property "Value" "C_100n_0402"
			(at -1.022927 2.155213 90)
			(layer "F.Fab")
			(effects
				(font
					(size 0.7 0.7)
					(thickness 0.15)
				)
				(justify left bottom)
			)
		)
		(property "Datasheet" "https://www.murata.com/products/productdetail?partno=GRM155R61H104KE14%23"
			(at 0 0 90)
			(layer "F.Fab")
			(hide yes)
			(effects
				(font
					(size 1.27 1.27)
					(thickness 0.15)
				)
			)
		)
		(property "Description" "SMD Multilayer Ceramic Capacitor, 0.1 µF, 50 V, 0402 [1005 Metric], ± 10%, X5R, GRM Series"
			(at 0 0 90)
			(layer "F.Fab")
			(hide yes)
			(effects
				(font
					(size 1.27 1.27)
					(thickness 0.15)
				)
			)
		)
		(property "MPN" "GRM155R61H104KE14D"
			(at 0 0 90)
			(unlocked yes)
			(layer "F.Fab")
			(hide yes)
			(effects
				(font
					(size 1 1)
					(thickness 0.15)
				)
			)
		)
		(property "Manufacturer" "Murata"
			(at 0 0 90)
			(unlocked yes)
			(layer "F.Fab")
			(hide yes)
			(effects
				(font
					(size 1 1)
					(thickness 0.15)
				)
			)
		)
		(property "License" "Apache-2.0"
			(at 0 0 90)
			(unlocked yes)
			(layer "F.Fab")
			(hide yes)
			(effects
				(font
					(size 1 1)
					(thickness 0.15)
				)
			)
		)
		(property "Val" "100n"
			(at 0 0 90)
			(unlocked yes)
			(layer "F.Fab")
			(hide yes)
			(effects
				(font
					(size 1 1)
					(thickness 0.15)
				)
			)
		)
		(property "Voltage" "50V"
			(at 0 0 90)
			(unlocked yes)
			(layer "F.Fab")
			(hide yes)
			(effects
				(font
					(size 1 1)
					(thickness 0.15)
				)
			)
		)
		(property "Dielectric" "X5R"
			(at 0 0 90)
			(unlocked yes)
			(layer "F.Fab")
			(hide yes)
			(effects
				(font
					(size 1 1)
					(thickness 0.15)
				)
			)
		)
		(property "Author" "Antmicro"
			(at 0 0 90)
			(unlocked yes)
			(layer "F.Fab")
			(hide yes)
			(effects
				(font
					(size 1 1)
					(thickness 0.15)
				)
			)
		)
		(sheetname "/TB Controller - Power/")
		(sheetfile "tb-power.kicad_sch")
		(attr smd)
		(fp_rect
			(start -0.925 -0.47)
			(end 0.925 0.47)
			(stroke
				(width 0.05)
				(type default)
			)
			(fill no)
			(layer "F.CrtYd")
		)
		(fp_line
			(start 0.504 -0.25)
			(end 0.504 0.248)
			(stroke
				(width 0.15)
				(type solid)
			)
			(layer "F.Fab")
		)
		(fp_line
			(start -0.494 -0.25)
			(end 0.504 -0.25)
			(stroke
				(width 0.15)
				(type solid)
			)
			(layer "F.Fab")
		)
		(fp_line
			(start 0.504 0.248)
			(end -0.494 0.248)
			(stroke
				(width 0.15)
				(type solid)
			)
			(layer "F.Fab")
		)
		(fp_line
			(start -0.494 0.248)
			(end -0.494 -0.25)
			(stroke
				(width 0.15)
				(type solid)
			)
			(layer "F.Fab")
		)
		(fp_text user "${REFERENCE}"
			(at -0.939 4.599 90)
			(layer "F.Fab")
			(effects
				(font
					(size 0.7 0.7)
					(thickness 0.15)
				)
				(justify left bottom)
			)
		)
		(fp_text user "Author: Antmicro"
			(at -0.939 3.399 90)
			(layer "F.Fab")
			(effects
				(font
					(size 0.7 0.7)
					(thickness 0.15)
				)
				(justify left bottom)
			)
		)
		(fp_text user "License: Apache-2.0"
			(at -0.939 5.799 90)
			(layer "F.Fab")
			(effects
				(font
					(size 0.7 0.7)
					(thickness 0.15)
				)
				(justify left bottom)
			)
		)
		(pad "1" smd roundrect
			(at -0.48 0 90)
			(size 0.59 0.64)
			(layers "F.Cu" "F.Mask" "F.Paste")
			(roundrect_rratio 0.25)
			(net 23 "GND")
			(pintype "passive")
		)
		(pad "2" smd roundrect
			(at 0.48 0 90)
			(size 0.59 0.64)
			(layers "F.Cu" "F.Mask" "F.Paste")
			(roundrect_rratio 0.25)
			(net 57 "+3V3_TB")
			(pintype "passive")
		)
	)
	(footprint "antmicro-footprints:R_0402_1005Metric"
		(layer "F.Cu")
		(at 151.55 112.150002)
		(descr "Resistor SMD 0402")
		(tags "resistor SMD 0402")
		(property "Reference" "R103"
			(at 14.149998 17.25 0)
			(layer "F.SilkS")
			(effects
				(font
					(size 0.7 0.7)
					(thickness 0.15)
				)
			)
		)
		(property "Value" "R_30k_0402"
			(at -1.011843 1.772047 0)
			(layer "F.Fab")
			(effects
				(font
					(size 0.7 0.7)
					(thickness 0.15)
				)
				(justify left bottom)
			)
		)
		(property "Datasheet" "https://www.bourns.com/docs/product-datasheets/cr.pdf"
			(at 0 0 0)
			(layer "F.Fab")
			(hide yes)
			(effects
				(font
					(size 1.27 1.27)
					(thickness 0.15)
				)
			)
		)
		(property "Description" "SMD Chip Resistor, 30 kohm, ± 1%, 63 mW, 0402 [1005 Metric], Thick Film, General Purpose"
			(at 0 0 0)
			(layer "F.Fab")
			(hide yes)
			(effects
				(font
					(size 1.27 1.27)
					(thickness 0.15)
				)
			)
		)
		(property "MPN" "CR0402-FX-3002GLF"
			(at 0 0 0)
			(unlocked yes)
			(layer "F.Fab")
			(hide yes)
			(effects
				(font
					(size 1 1)
					(thickness 0.15)
				)
			)
		)
		(property "Manufacturer" "Bourns"
			(at 0 0 0)
			(unlocked yes)
			(layer "F.Fab")
			(hide yes)
			(effects
				(font
					(size 1 1)
					(thickness 0.15)
				)
			)
		)
		(property "License" "Apache-2.0"
			(at 0 0 0)
			(unlocked yes)
			(layer "F.Fab")
			(hide yes)
			(effects
				(font
					(size 1 1)
					(thickness 0.15)
				)
			)
		)
		(property "Author" "Antmicro"
			(at 0 0 0)
			(unlocked yes)
			(layer "F.Fab")
			(hide yes)
			(effects
				(font
					(size 1 1)
					(thickness 0.15)
				)
			)
		)
		(property "Val" "30k"
			(at 0 0 0)
			(unlocked yes)
			(layer "F.Fab")
			(hide yes)
			(effects
				(font
					(size 1 1)
					(thickness 0.15)
				)
			)
		)
		(property "Tolerance" "1%"
			(at 0 0 0)
			(unlocked yes)
			(layer "F.Fab")
			(hide yes)
			(effects
				(font
					(size 1 1)
					(thickness 0.15)
				)
			)
		)
		(sheetname "/X710 DCDC converters/")
		(sheetfile "DCDC_converters_X710.kicad_sch")
		(attr smd)
		(fp_rect
			(start -0.925 -0.47)
			(end 0.925 0.47)
			(stroke
				(width 0.05)
				(type default)
			)
			(fill no)
			(layer "F.CrtYd")
		)
		(fp_rect
			(start -0.5 -0.25)
			(end 0.5 0.25)
			(stroke
				(width 0.15)
				(type solid)
			)
			(fill no)
			(layer "F.Fab")
		)
		(fp_text user "Author: Antmicro"
			(at -0.95 4.169 0)
			(layer "F.Fab")
			(effects
				(font
					(size 0.7 0.7)
					(thickness 0.15)
				)
				(justify left bottom)
			)
		)
		(fp_text user "License: Apache-2.0"
			(at -0.95 5.169 0)
			(layer "F.Fab")
			(effects
				(font
					(size 0.7 0.7)
					(thickness 0.15)
				)
				(justify left bottom)
			)
		)
		(fp_text user "${REFERENCE}"
			(at -0.95 3.168 0)
			(layer "F.Fab")
			(effects
				(font
					(size 0.7 0.7)
					(thickness 0.15)
				)
				(justify left bottom)
			)
		)
		(pad "1" smd roundrect
			(at -0.48 0)
			(size 0.59 0.64)
			(layers "F.Cu" "F.Mask" "F.Paste")
			(roundrect_rratio 0.25)
			(net 23 "GND")
			(pintype "passive")
		)
		(pad "2" smd roundrect
			(at 0.48 0)
			(size 0.59 0.64)
			(layers "F.Cu" "F.Mask" "F.Paste")
			(roundrect_rratio 0.25)
			(net 337 "/X710 DCDC converters/1V88_FB")
			(pintype "passive")
		)
	)
	(footprint "antmicro-footprints:C_0603_1608Metric_EIA"
		(layer "F.Cu")
		(at 140.105001 99.774999 -90)
		(descr "Capacitor SMD 0603, IPC-7351 Density Level A")
		(tags "Capacitor 0603")
		(property "Reference" "C257"
			(at -9.274999 -36.144999 270)
			(layer "F.SilkS")
			(effects
				(font
					(size 0.7 0.7)
					(thickness 0.15)
				)
			)
		)
		(property "Value" "C_22u_16V_0603"
			(at -1.42757 1.770288 270)
			(layer "F.Fab")
			(effects
				(font
					(size 0.7 0.7)
					(thickness 0.15)
				)
				(justify left bottom)
			)
		)
		(property "Datasheet" "https://product.samsungsem.com/mlcc/CL10A226MO7JZN.do"
			(at 0 0 270)
			(layer "F.Fab")
			(hide yes)
			(effects
				(font
					(size 1.27 1.27)
					(thickness 0.15)
				)
			)
		)
		(property "Description" "SMD Multilayer Ceramic Capacitor"
			(at 0 0 270)
			(layer "F.Fab")
			(hide yes)
			(effects
				(font
					(size 1.27 1.27)
					(thickness 0.15)
				)
			)
		)
		(property "MPN" "CL10A226MO7JZNC"
			(at 0 0 270)
			(unlocked yes)
			(layer "F.Fab")
			(hide yes)
			(effects
				(font
					(size 1 1)
					(thickness 0.15)
				)
			)
		)
		(property "Manufacturer" "Samsung Electro-Mechanics"
			(at 0 0 270)
			(unlocked yes)
			(layer "F.Fab")
			(hide yes)
			(effects
				(font
					(size 1 1)
					(thickness 0.15)
				)
			)
		)
		(property "License" "Apache-2.0"
			(at 0 0 270)
			(unlocked yes)
			(layer "F.Fab")
			(hide yes)
			(effects
				(font
					(size 1 1)
					(thickness 0.15)
				)
			)
		)
		(property "Author" "Antmicro"
			(at 0 0 270)
			(unlocked yes)
			(layer "F.Fab")
			(hide yes)
			(effects
				(font
					(size 1 1)
					(thickness 0.15)
				)
			)
		)
		(property "Val" "22u"
			(at 0 0 270)
			(unlocked yes)
			(layer "F.Fab")
			(hide yes)
			(effects
				(font
					(size 1 1)
					(thickness 0.15)
				)
			)
		)
		(property "Voltage" "16V"
			(at 0 0 270)
			(unlocked yes)
			(layer "F.Fab")
			(hide yes)
			(effects
				(font
					(size 1 1)
					(thickness 0.15)
				)
			)
		)
		(property "Dielectric" ""
			(at 0 0 270)
			(unlocked yes)
			(layer "F.Fab")
			(hide yes)
			(effects
				(font
					(size 1 1)
					(thickness 0.15)
				)
			)
		)
		(sheetname "/X710-AT2 power/")
		(sheetfile "x710-at2-power.kicad_sch")
		(attr smd)
		(fp_line
			(start -0.15 0.55)
			(end 0.15 0.55)
			(stroke
				(width 0.15)
				(type solid)
			)
			(layer "F.SilkS")
		)
		(fp_line
			(start -0.15 -0.55)
			(end 0.15 -0.55)
			(stroke
				(width 0.15)
				(type solid)
			)
			(layer "F.SilkS")
		)
		(fp_rect
			(start -1.25 -0.65)
			(end 1.25 0.65)
			(stroke
				(width 0.05)
				(type solid)
			)
			(fill no)
			(layer "F.CrtYd")
		)
		(fp_rect
			(start -0.8 -0.45)
			(end 0.8 0.45)
			(stroke
				(width 0.15)
				(type solid)
			)
			(fill no)
			(layer "F.Fab")
		)
		(fp_text user "${REFERENCE}"
			(at -1.682 3.895 270)
			(layer "F.Fab")
			(effects
				(font
					(size 0.7 0.7)
					(thickness 0.15)
				)
				(justify left bottom)
			)
		)
		(fp_text user "License: Apache-2.0"
			(at -1.682 5.895 270)
			(layer "F.Fab")
			(effects
				(font
					(size 0.7 0.7)
					(thickness 0.15)
				)
				(justify left bottom)
			)
		)
		(fp_text user "Author: Antmicro"
			(at -1.682 4.894 270)
			(layer "F.Fab")
			(effects
				(font
					(size 0.7 0.7)
					(thickness 0.15)
				)
				(justify left bottom)
			)
		)
		(pad "1" smd roundrect
			(at -0.7 0 270)
			(size 0.8 1.1)
			(layers "F.Cu" "F.Mask" "F.Paste")
			(roundrect_rratio 0.2)
			(net 23 "GND")
			(pintype "passive")
		)
		(pad "2" smd roundrect
			(at 0.7 0 270)
			(size 0.8 1.1)
			(layers "F.Cu" "F.Mask" "F.Paste")
			(roundrect_rratio 0.2)
			(net 9 "VCCD")
			(pintype "passive")
		)
	)
	(footprint "antmicro-footprints:LED_0603_1608Metric_G"
		(layer "F.Cu")
		(at 125 56.5 90)
		(descr "LED SMD 0603 Green")
		(tags "LED SMD 0603 Green")
		(property "Reference" "D16"
			(at -0.9 -0.8 90)
			(layer "F.SilkS")
			(effects
				(font
					(size 0.7 0.7)
					(thickness 0.15)
				)
				(justify left bottom)
			)
		)
		(property "Value" "LED_G_0603_LTST-C190GKT"
			(at -0.001 1.599 90)
			(layer "F.Fab")
			(effects
				(font
					(size 0.7 0.7)
					(thickness 0.15)
				)
				(justify left bottom)
			)
		)
		(property "Datasheet" "https://media.digikey.com/pdf/Data%20Sheets/Lite-On%20PDFs/LTST-C190GKT.pdf"
			(at 0 0 90)
			(layer "F.Fab")
			(hide yes)
			(effects
				(font
					(size 1.27 1.27)
					(thickness 0.15)
				)
			)
		)
		(property "Description" "LED, Green, SMD, 0603, 20 mA, 2.1 V, 569 nm"
			(at 0 0 90)
			(layer "F.Fab")
			(hide yes)
			(effects
				(font
					(size 1.27 1.27)
					(thickness 0.15)
				)
			)
		)
		(property "MPN" "LTST-C190GKT"
			(at 0 0 90)
			(unlocked yes)
			(layer "F.Fab")
			(hide yes)
			(effects
				(font
					(size 1 1)
					(thickness 0.15)
				)
			)
		)
		(property "Manufacturer" "Lite-On"
			(at 0 0 90)
			(unlocked yes)
			(layer "F.Fab")
			(hide yes)
			(effects
				(font
					(size 1 1)
					(thickness 0.15)
				)
			)
		)
		(property "Author" "Antmicro"
			(at 0 0 90)
			(unlocked yes)
			(layer "F.Fab")
			(hide yes)
			(effects
				(font
					(size 1 1)
					(thickness 0.15)
				)
			)
		)
		(property "License" "Apache-2.0"
			(at 0 0 90)
			(unlocked yes)
			(layer "F.Fab")
			(hide yes)
			(effects
				(font
					(size 1 1)
					(thickness 0.15)
				)
			)
		)
		(property "Color" "Green"
			(at 0 0 90)
			(unlocked yes)
			(layer "F.Fab")
			(hide yes)
			(effects
				(font
					(size 1 1)
					(thickness 0.15)
				)
			)
		)
		(sheetname "/Power input/")
		(sheetfile "power_input.kicad_sch")
		(attr smd)
		(fp_line
			(start 0.22 -0.35)
			(end -0.22 -0.35)
			(stroke
				(width 0.15)
				(type solid)
			)
			(layer "F.SilkS")
		)
		(fp_line
			(start -1.18 -0.319)
			(end -1.18 0.321)
			(stroke
				(width 0.15)
				(type solid)
			)
			(layer "F.SilkS")
		)
		(fp_line
			(start 0.105328 0.001008)
			(end 0.24 0.001)
			(stroke
				(width 0.1)
				(type solid)
			)
			(layer "F.SilkS")
		)
		(fp_line
			(start -0.094672 0.001008)
			(end 0.105328 -0.198992)
			(stroke
				(width 0.1)
				(type solid)
			)
			(layer "F.SilkS")
		)
		(fp_line
			(start -0.094672 0.001008)
			(end -0.24 0.001008)
			(stroke
				(width 0.1)
				(type solid)
			)
			(layer "F.SilkS")
		)
		(fp_line
			(start 0.105328 0.201008)
			(end 0.105328 -0.198992)
			(stroke
				(width 0.1)
				(type solid)
			)
			(layer "F.SilkS")
		)
		(fp_line
			(start 0.105328 0.201008)
			(end -0.094672 0.001008)
			(stroke
				(width 0.1)
				(type solid)
			)
			(layer "F.SilkS")
		)
		(fp_line
			(start -0.094672 0.201008)
			(end -0.094672 -0.198992)
			(stroke
				(width 0.1)
				(type solid)
			)
			(layer "F.SilkS")
		)
		(fp_line
			(start 0.22 0.35)
			(end -0.22 0.35)
			(stroke
				(width 0.15)
				(type solid)
			)
			(layer "F.SilkS")
		)
		(fp_rect
			(start 1.25 0.65)
			(end -1.25 -0.65)
			(stroke
				(width 0.05)
				(type solid)
			)
			(fill no)
			(layer "F.CrtYd")
		)
		(fp_line
			(start 0.201 -0.202)
			(end -0.101 0)
			(stroke
				(width 0.15)
				(type solid)
			)
			(layer "F.Fab")
		)
		(fp_line
			(start -0.199 -0.202)
			(end -0.199 0.1)
			(stroke
				(width 0.15)
				(type solid)
			)
			(layer "F.Fab")
		)
		(fp_line
			(start 0.599 0)
			(end 0.201 0)
			(stroke
				(width 0.15)
				(type solid)
			)
			(layer "F.Fab")
		)
		(fp_line
			(start 0.201 0)
			(end 0.201 -0.202)
			(stroke
				(width 0.15)
				(type solid)
			)
			(layer "F.Fab")
		)
		(fp_line
			(start -0.101 0)
			(end 0.201 0.2)
			(stroke
				(width 0.15)
				(type solid)
			)
			(layer "F.Fab")
		)
		(fp_line
			(start -0.199 0)
			(end -0.597 0)
			(stroke
				(width 0.15)
				(type solid)
			)
			(layer "F.Fab")
		)
		(fp_line
			(start 0.201 0.2)
			(end 0.201 0)
			(stroke
				(width 0.15)
				(type solid)
			)
			(layer "F.Fab")
		)
		(fp_line
			(start -0.199 0.2)
			(end -0.199 0.1)
			(stroke
				(width 0.15)
				(type solid)
			)
			(layer "F.Fab")
		)
		(fp_rect
			(start 0.848 0.4)
			(end -0.85 -0.402)
			(stroke
				(width 0.15)
				(type solid)
			)
			(fill no)
			(layer "F.Fab")
		)
		(fp_text user "${REFERENCE}"
			(at -1.4224 5.999 90)
			(layer "F.Fab")
			(effects
				(font
					(size 0.7 0.7)
					(thickness 0.15)
				)
				(justify left bottom)
			)
		)
		(fp_text user "Author: Antmicro"
			(at -1.4224 4.799 90)
			(layer "F.Fab")
			(effects
				(font
					(size 0.7 0.7)
					(thickness 0.15)
				)
				(justify left bottom)
			)
		)
		(fp_text user "License: Apache-2.0"
			(at -1.4224 3.599 90)
			(layer "F.Fab")
			(effects
				(font
					(size 0.7 0.7)
					(thickness 0.15)
				)
				(justify left bottom)
			)
		)
		(pad "1" smd roundrect
			(at -0.7 0 270)
			(size 0.8 1)
			(layers "F.Cu" "F.Mask" "F.Paste")
			(roundrect_rratio 0.2)
			(net 23 "GND")
			(pinfunction "C")
			(pintype "passive")
		)
		(pad "2" smd roundrect
			(at 0.7 0 270)
			(size 0.8 1)
			(layers "F.Cu" "F.Mask" "F.Paste")
			(roundrect_rratio 0.2)
			(net 420 "Net-(D16-A)")
			(pinfunction "A")
			(pintype "passive")
		)
	)
	(footprint "antmicro-footprints:C_0603_1608Metric_EIA"
		(layer "F.Cu")
		(at 133.304999 89.274998 -90)
		(descr "Capacitor SMD 0603, IPC-7351 Density Level A")
		(tags "Capacitor 0603")
		(property "Reference" "C258"
			(at 4.225001 16.054999 270)
			(layer "F.SilkS")
			(effects
				(font
					(size 0.7 0.7)
					(thickness 0.15)
				)
				(justify left bottom)
			)
		)
		(property "Value" "C_22u_16V_0603"
			(at -1.42757 1.770288 270)
			(layer "F.Fab")
			(effects
				(font
					(size 0.7 0.7)
					(thickness 0.15)
				)
				(justify left bottom)
			)
		)
		(property "Datasheet" "https://product.samsungsem.com/mlcc/CL10A226MO7JZN.do"
			(at 0 0 270)
			(layer "F.Fab")
			(hide yes)
			(effects
				(font
					(size 1.27 1.27)
					(thickness 0.15)
				)
			)
		)
		(property "Description" "SMD Multilayer Ceramic Capacitor"
			(at 0 0 270)
			(layer "F.Fab")
			(hide yes)
			(effects
				(font
					(size 1.27 1.27)
					(thickness 0.15)
				)
			)
		)
		(property "MPN" "CL10A226MO7JZNC"
			(at 0 0 270)
			(unlocked yes)
			(layer "F.Fab")
			(hide yes)
			(effects
				(font
					(size 1 1)
					(thickness 0.15)
				)
			)
		)
		(property "Manufacturer" "Samsung Electro-Mechanics"
			(at 0 0 270)
			(unlocked yes)
			(layer "F.Fab")
			(hide yes)
			(effects
				(font
					(size 1 1)
					(thickness 0.15)
				)
			)
		)
		(property "License" "Apache-2.0"
			(at 0 0 270)
			(unlocked yes)
			(layer "F.Fab")
			(hide yes)
			(effects
				(font
					(size 1 1)
					(thickness 0.15)
				)
			)
		)
		(property "Author" "Antmicro"
			(at 0 0 270)
			(unlocked yes)
			(layer "F.Fab")
			(hide yes)
			(effects
				(font
					(size 1 1)
					(thickness 0.15)
				)
			)
		)
		(property "Val" "22u"
			(at 0 0 270)
			(unlocked yes)
			(layer "F.Fab")
			(hide yes)
			(effects
				(font
					(size 1 1)
					(thickness 0.15)
				)
			)
		)
		(property "Voltage" "16V"
			(at 0 0 270)
			(unlocked yes)
			(layer "F.Fab")
			(hide yes)
			(effects
				(font
					(size 1 1)
					(thickness 0.15)
				)
			)
		)
		(property "Dielectric" ""
			(at 0 0 270)
			(unlocked yes)
			(layer "F.Fab")
			(hide yes)
			(effects
				(font
					(size 1 1)
					(thickness 0.15)
				)
			)
		)
		(sheetname "/X710-AT2 power/")
		(sheetfile "x710-at2-power.kicad_sch")
		(attr smd)
		(fp_line
			(start -0.15 0.55)
			(end 0.15 0.55)
			(stroke
				(width 0.15)
				(type solid)
			)
			(layer "F.SilkS")
		)
		(fp_line
			(start -0.15 -0.55)
			(end 0.15 -0.55)
			(stroke
				(width 0.15)
				(type solid)
			)
			(layer "F.SilkS")
		)
		(fp_rect
			(start -1.25 -0.65)
			(end 1.25 0.65)
			(stroke
				(width 0.05)
				(type solid)
			)
			(fill no)
			(layer "F.CrtYd")
		)
		(fp_rect
			(start -0.8 -0.45)
			(end 0.8 0.45)
			(stroke
				(width 0.15)
				(type solid)
			)
			(fill no)
			(layer "F.Fab")
		)
		(fp_text user "License: Apache-2.0"
			(at -1.682 5.895 270)
			(layer "F.Fab")
			(effects
				(font
					(size 0.7 0.7)
					(thickness 0.15)
				)
				(justify left bottom)
			)
		)
		(fp_text user "Author: Antmicro"
			(at -1.682 4.894 270)
			(layer "F.Fab")
			(effects
				(font
					(size 0.7 0.7)
					(thickness 0.15)
				)
				(justify left bottom)
			)
		)
		(fp_text user "${REFERENCE}"
			(at -1.682 3.895 270)
			(layer "F.Fab")
			(effects
				(font
					(size 0.7 0.7)
					(thickness 0.15)
				)
				(justify left bottom)
			)
		)
		(pad "1" smd roundrect
			(at -0.7 0 270)
			(size 0.8 1.1)
			(layers "F.Cu" "F.Mask" "F.Paste")
			(roundrect_rratio 0.2)
			(net 23 "GND")
			(pintype "passive")
		)
		(pad "2" smd roundrect
			(at 0.7 0 270)
			(size 0.8 1.1)
			(layers "F.Cu" "F.Mask" "F.Paste")
			(roundrect_rratio 0.2)
			(net 7 "+3V3")
			(pintype "passive")
		)
	)
	(footprint "antmicro-footprints:MP_Pad6mm_Drill3.2mm"
		(layer "F.Cu")
		(at 172 64 90)
		(property "Reference" "MP8"
			(at -4.25 -1.25 180)
			(layer "F.SilkS")
			(effects
				(font
					(size 0.7 0.7)
					(thickness 0.15)
				)
				(justify left bottom)
			)
		)
		(property "Value" "MP_Pad6mm_Drill3.2mm"
			(at 0 3.9 90)
			(layer "F.Fab")
			(effects
				(font
					(size 0.7 0.7)
					(thickness 0.15)
				)
				(justify left bottom)
			)
		)
		(property "Description" "Mechanical part"
			(at 0 0 90)
			(layer "F.Fab")
			(hide yes)
			(effects
				(font
					(size 1.27 1.27)
					(thickness 0.15)
				)
			)
		)
		(property "Author" "Antmicro"
			(at 0 0 90)
			(unlocked yes)
			(layer "F.Fab")
			(hide yes)
			(effects
				(font
					(size 1 1)
					(thickness 0.15)
				)
			)
		)
		(property "License" "Apache-2.0"
			(at 0 0 90)
			(unlocked yes)
			(layer "F.Fab")
			(hide yes)
			(effects
				(font
					(size 1 1)
					(thickness 0.15)
				)
			)
		)
		(sheetname "/")
		(sheetfile "thunderbolt-to-10gbe-adapter.kicad_sch")
		(attr exclude_from_pos_files exclude_from_bom)
		(fp_circle
			(center 0 0)
			(end 3.25 0)
			(stroke
				(width 0.05)
				(type default)
			)
			(fill no)
			(layer "F.CrtYd")
		)
		(fp_text user "Author: Antmicro"
			(at -0.178 7.225 90)
			(layer "F.Fab")
			(effects
				(font
					(size 0.7 0.7)
					(thickness 0.15)
				)
				(justify left bottom)
			)
		)
		(fp_text user "License: Apache-2.0"
			(at -0.178 8.425 90)
			(layer "F.Fab")
			(effects
				(font
					(size 0.7 0.7)
					(thickness 0.15)
				)
				(justify left bottom)
			)
		)
		(fp_text user "${REFERENCE}"
			(at -0.178 6.025 90)
			(layer "F.Fab")
			(effects
				(font
					(size 0.7 0.7)
					(thickness 0.15)
				)
				(justify left bottom)
			)
		)
		(pad "1" thru_hole circle
			(at 0 0 90)
			(size 6 6)
			(drill 3.2)
			(layers "*.Cu" "*.Mask")
			(remove_unused_layers no)
			(net 23 "GND")
			(pintype "passive")
		)
	)
	(footprint "antmicro-footprints:R_0402_1005Metric"
		(layer "F.Cu")
		(at 143.849998 108.15 180)
		(descr "Resistor SMD 0402")
		(tags "resistor SMD 0402")
		(property "Reference" "R91"
			(at -15.349999 -17.25 180)
			(layer "F.SilkS")
			(effects
				(font
					(size 0.7 0.7)
					(thickness 0.15)
				)
			)
		)
		(property "Value" "R_100k_0402"
			(at -1.011843 1.772047 180)
			(layer "F.Fab")
			(effects
				(font
					(size 0.7 0.7)
					(thickness 0.15)
				)
				(justify left bottom)
			)
		)
		(property "Datasheet" "https://www.bourns.com/docs/product-datasheets/cr.pdf"
			(at 0 0 180)
			(layer "F.Fab")
			(hide yes)
			(effects
				(font
					(size 1.27 1.27)
					(thickness 0.15)
				)
			)
		)
		(property "Description" "SMD Chip Resistor, 100 kohm, ± 1%, 62.5 mW, 0402 [1005 Metric], Thick Film, General Purpose"
			(at 0 0 180)
			(layer "F.Fab")
			(hide yes)
			(effects
				(font
					(size 1.27 1.27)
					(thickness 0.15)
				)
			)
		)
		(property "MPN" "CR0402-FX-1003GLF"
			(at 0 0 180)
			(unlocked yes)
			(layer "F.Fab")
			(hide yes)
			(effects
				(font
					(size 1 1)
					(thickness 0.15)
				)
			)
		)
		(property "Manufacturer" "Bourns"
			(at 0 0 180)
			(unlocked yes)
			(layer "F.Fab")
			(hide yes)
			(effects
				(font
					(size 1 1)
					(thickness 0.15)
				)
			)
		)
		(property "License" "Apache-2.0"
			(at 0 0 180)
			(unlocked yes)
			(layer "F.Fab")
			(hide yes)
			(effects
				(font
					(size 1 1)
					(thickness 0.15)
				)
			)
		)
		(property "Author" "Antmicro"
			(at 0 0 180)
			(unlocked yes)
			(layer "F.Fab")
			(hide yes)
			(effects
				(font
					(size 1 1)
					(thickness 0.15)
				)
			)
		)
		(property "Val" "100k"
			(at 0 0 180)
			(unlocked yes)
			(layer "F.Fab")
			(hide yes)
			(effects
				(font
					(size 1 1)
					(thickness 0.15)
				)
			)
		)
		(property "Tolerance" "1%"
			(at 0 0 180)
			(unlocked yes)
			(layer "F.Fab")
			(hide yes)
			(effects
				(font
					(size 1 1)
					(thickness 0.15)
				)
			)
		)
		(sheetname "/X710 DCDC converters/")
		(sheetfile "DCDC_converters_X710.kicad_sch")
		(attr smd)
		(fp_rect
			(start -0.925 -0.47)
			(end 0.925 0.47)
			(stroke
				(width 0.05)
				(type default)
			)
			(fill no)
			(layer "F.CrtYd")
		)
		(fp_rect
			(start -0.5 -0.25)
			(end 0.5 0.25)
			(stroke
				(width 0.15)
				(type solid)
			)
			(fill no)
			(layer "F.Fab")
		)
		(fp_text user "License: Apache-2.0"
			(at -0.95 5.169 180)
			(layer "F.Fab")
			(effects
				(font
					(size 0.7 0.7)
					(thickness 0.15)
				)
				(justify left bottom)
			)
		)
		(fp_text user "Author: Antmicro"
			(at -0.95 4.169 180)
			(layer "F.Fab")
			(effects
				(font
					(size 0.7 0.7)
					(thickness 0.15)
				)
				(justify left bottom)
			)
		)
		(fp_text user "${REFERENCE}"
			(at -0.95 3.168 180)
			(layer "F.Fab")
			(effects
				(font
					(size 0.7 0.7)
					(thickness 0.15)
				)
				(justify left bottom)
			)
		)
		(pad "1" smd roundrect
			(at -0.48 0 180)
			(size 0.59 0.64)
			(layers "F.Cu" "F.Mask" "F.Paste")
			(roundrect_rratio 0.25)
			(net 355 "/X710 DCDC converters/DVDD_PG")
			(pintype "passive")
		)
		(pad "2" smd roundrect
			(at 0.48 0 180)
			(size 0.59 0.64)
			(layers "F.Cu" "F.Mask" "F.Paste")
			(roundrect_rratio 0.25)
			(net 116 "/X710 DCDC converters/DVDD_VCC")
			(pintype "passive")
		)
	)
	(footprint "antmicro-footprints:R_0402_1005Metric"
		(layer "F.Cu")
		(at 130.509997 116.5 -90)
		(descr "Resistor SMD 0402")
		(tags "resistor SMD 0402")
		(property "Reference" "R67"
			(at -0.9 -0.290003 270)
			(layer "F.SilkS")
			(effects
				(font
					(size 0.7 0.7)
					(thickness 0.15)
				)
				(justify left bottom)
			)
		)
		(property "Value" "R_10k_0402"
			(at -1.011843 1.772047 270)
			(layer "F.Fab")
			(effects
				(font
					(size 0.7 0.7)
					(thickness 0.15)
				)
				(justify left bottom)
			)
		)
		(property "Datasheet" "https://www.bourns.com/docs/product-datasheets/cr.pdf"
			(at 0 0 270)
			(layer "F.Fab")
			(hide yes)
			(effects
				(font
					(size 1.27 1.27)
					(thickness 0.15)
				)
			)
		)
		(property "Description" "SMD Chip Resistor, 10 kohm, ± 1%, 62.5 mW, 0402 [1005 Metric], Thick Film, General Purpose"
			(at 0 0 270)
			(layer "F.Fab")
			(hide yes)
			(effects
				(font
					(size 1.27 1.27)
					(thickness 0.15)
				)
			)
		)
		(property "MPN" "CR0402-FX-1002GLF"
			(at 0 0 270)
			(unlocked yes)
			(layer "F.Fab")
			(hide yes)
			(effects
				(font
					(size 1 1)
					(thickness 0.15)
				)
			)
		)
		(property "Manufacturer" "Bourns"
			(at 0 0 270)
			(unlocked yes)
			(layer "F.Fab")
			(hide yes)
			(effects
				(font
					(size 1 1)
					(thickness 0.15)
				)
			)
		)
		(property "License" "Apache-2.0"
			(at 0 0 270)
			(unlocked yes)
			(layer "F.Fab")
			(hide yes)
			(effects
				(font
					(size 1 1)
					(thickness 0.15)
				)
			)
		)
		(property "Val" "10k"
			(at 0 0 270)
			(unlocked yes)
			(layer "F.Fab")
			(hide yes)
			(effects
				(font
					(size 1 1)
					(thickness 0.15)
				)
			)
		)
		(property "Tolerance" "1%"
			(at 0 0 270)
			(unlocked yes)
			(layer "F.Fab")
			(hide yes)
			(effects
				(font
					(size 1 1)
					(thickness 0.15)
				)
			)
		)
		(property "Author" "Antmicro"
			(at 0 0 270)
			(unlocked yes)
			(layer "F.Fab")
			(hide yes)
			(effects
				(font
					(size 1 1)
					(thickness 0.15)
				)
			)
		)
		(sheetname "/TB Controller/")
		(sheetfile "tb.kicad_sch")
		(attr smd)
		(fp_rect
			(start -0.925 -0.47)
			(end 0.925 0.47)
			(stroke
				(width 0.05)
				(type default)
			)
			(fill no)
			(layer "F.CrtYd")
		)
		(fp_rect
			(start -0.5 -0.25)
			(end 0.5 0.25)
			(stroke
				(width 0.15)
				(type solid)
			)
			(fill no)
			(layer "F.Fab")
		)
		(fp_text user "License: Apache-2.0"
			(at -0.95 5.169 270)
			(layer "F.Fab")
			(effects
				(font
					(size 0.7 0.7)
					(thickness 0.15)
				)
				(justify left bottom)
			)
		)
		(fp_text user "${REFERENCE}"
			(at -0.95 3.168 270)
			(layer "F.Fab")
			(effects
				(font
					(size 0.7 0.7)
					(thickness 0.15)
				)
				(justify left bottom)
			)
		)
		(fp_text user "Author: Antmicro"
			(at -0.95 4.169 270)
			(layer "F.Fab")
			(effects
				(font
					(size 0.7 0.7)
					(thickness 0.15)
				)
				(justify left bottom)
			)
		)
		(pad "1" smd roundrect
			(at -0.48 0 270)
			(size 0.59 0.64)
			(layers "F.Cu" "F.Mask" "F.Paste")
			(roundrect_rratio 0.25)
			(net 57 "+3V3_TB")
			(pintype "passive")
		)
		(pad "2" smd roundrect
			(at 0.48 0 270)
			(size 0.59 0.64)
			(layers "F.Cu" "F.Mask" "F.Paste")
			(roundrect_rratio 0.25)
			(net 216 "Net-(U4B-PCIE_CLKREQ_N)")
			(pintype "passive")
		)
	)
	(footprint "antmicro-footprints:C_0805_2012Metric"
		(layer "F.Cu")
		(at 149.1 56.8 -90)
		(descr "Capacitor SMD 0805")
		(tags "capacitor SMD 0805")
		(property "Reference" "C319"
			(at 4.6 -0.65 270)
			(layer "F.SilkS")
			(effects
				(font
					(size 0.7 0.7)
					(thickness 0.15)
				)
				(justify left bottom)
			)
		)
		(property "Value" "C_22u_25V_0805"
			(at -2.055717 1.963152 270)
			(layer "F.Fab")
			(effects
				(font
					(size 0.7 0.7)
					(thickness 0.15)
				)
				(justify left bottom)
			)
		)
		(property "Datasheet" "https://product.samsungsem.com/mlcc/CL21A226MAYNNN.do"
			(at 0 0 270)
			(layer "F.Fab")
			(hide yes)
			(effects
				(font
					(size 1.27 1.27)
					(thickness 0.15)
				)
			)
		)
		(property "Description" "SMT Multilayer Ceramic Capacitor, 22uF, +/-20%, 25V, X5R, 0805 [2012 Metric]"
			(at 0 0 270)
			(layer "F.Fab")
			(hide yes)
			(effects
				(font
					(size 1.27 1.27)
					(thickness 0.15)
				)
			)
		)
		(property "MPN" "CL21A226MAYNNNE"
			(at 0 0 270)
			(unlocked yes)
			(layer "F.Fab")
			(hide yes)
			(effects
				(font
					(size 1 1)
					(thickness 0.15)
				)
			)
		)
		(property "Manufacturer" "Samsung Electro-Mechanics"
			(at 0 0 270)
			(unlocked yes)
			(layer "F.Fab")
			(hide yes)
			(effects
				(font
					(size 1 1)
					(thickness 0.15)
				)
			)
		)
		(property "License" "Apache-2.0"
			(at 0 0 270)
			(unlocked yes)
			(layer "F.Fab")
			(hide yes)
			(effects
				(font
					(size 1 1)
					(thickness 0.15)
				)
			)
		)
		(property "Author" "Antmicro"
			(at 0 0 270)
			(unlocked yes)
			(layer "F.Fab")
			(hide yes)
			(effects
				(font
					(size 1 1)
					(thickness 0.15)
				)
			)
		)
		(property "Val" "22u"
			(at 0 0 270)
			(unlocked yes)
			(layer "F.Fab")
			(hide yes)
			(effects
				(font
					(size 1 1)
					(thickness 0.15)
				)
			)
		)
		(property "Voltage" "25V"
			(at 0 0 270)
			(unlocked yes)
			(layer "F.Fab")
			(hide yes)
			(effects
				(font
					(size 1 1)
					(thickness 0.15)
				)
			)
		)
		(property "Dielectric" "X5R"
			(at 0 0 270)
			(unlocked yes)
			(layer "F.Fab")
			(hide yes)
			(effects
				(font
					(size 1 1)
					(thickness 0.15)
				)
			)
		)
		(property "Public" "False"
			(at 0 0 270)
			(unlocked yes)
			(layer "F.Fab")
			(hide yes)
			(effects
				(font
					(size 1 1)
					(thickness 0.15)
				)
			)
		)
		(sheetname "/Power input/")
		(sheetfile "power_input.kicad_sch")
		(attr smd)
		(fp_line
			(start -0.3 0.7)
			(end 0.3 0.7)
			(stroke
				(width 0.15)
				(type solid)
			)
			(layer "F.SilkS")
		)
		(fp_line
			(start -0.3 -0.7)
			(end 0.3 -0.7)
			(stroke
				(width 0.15)
				(type solid)
			)
			(layer "F.SilkS")
		)
		(fp_rect
			(start 1.95 -0.9)
			(end -1.95 0.9)
			(stroke
				(width 0.05)
				(type default)
			)
			(fill no)
			(layer "F.CrtYd")
		)
		(fp_rect
			(start -0.95 -0.675)
			(end 0.95 0.675)
			(stroke
				(width 0.15)
				(type solid)
			)
			(fill no)
			(layer "F.Fab")
		)
		(fp_text user "${REFERENCE}"
			(at -1.9 3.947 270)
			(layer "F.Fab")
			(effects
				(font
					(size 0.7 0.7)
					(thickness 0.15)
				)
				(justify left bottom)
			)
		)
		(fp_text user "License: Apache-2.0"
			(at -1.9 4.947 270)
			(layer "F.Fab")
			(effects
				(font
					(size 0.7 0.7)
					(thickness 0.15)
				)
				(justify left bottom)
			)
		)
		(fp_text user "Author: Antmicro"
			(at -1.9 5.947 270)
			(layer "F.Fab")
			(effects
				(font
					(size 0.7 0.7)
					(thickness 0.15)
				)
				(justify left bottom)
			)
		)
		(pad "1" smd roundrect
			(at -1.1 0 270)
			(size 1.2 1.3)
			(layers "F.Cu" "F.Mask" "F.Paste")
			(roundrect_rratio 0.25)
			(net 23 "GND")
			(pintype "passive")
		)
		(pad "2" smd roundrect
			(at 1.1 0 270)
			(size 1.2 1.3)
			(layers "F.Cu" "F.Mask" "F.Paste")
			(roundrect_rratio 0.25)
			(net 349 "/Power input/5V_OUT")
			(pintype "passive")
		)
	)
	(footprint "antmicro-footprints:R_0402_1005Metric"
		(layer "F.Cu")
		(at 154.305 67.124999 -90)
		(descr "Resistor SMD 0402")
		(tags "resistor SMD 0402")
		(property "Reference" "R151"
			(at -12.324999 -20.295 270)
			(layer "F.SilkS")
			(effects
				(font
					(size 0.7 0.7)
					(thickness 0.15)
				)
			)
		)
		(property "Value" "R_100k_0402"
			(at -1.011843 1.772047 270)
			(layer "F.Fab")
			(effects
				(font
					(size 0.7 0.7)
					(thickness 0.15)
				)
				(justify left bottom)
			)
		)
		(property "Datasheet" "https://www.bourns.com/docs/product-datasheets/cr.pdf"
			(at 0 0 270)
			(layer "F.Fab")
			(hide yes)
			(effects
				(font
					(size 1.27 1.27)
					(thickness 0.15)
				)
			)
		)
		(property "Description" "SMD Chip Resistor, 100 kohm, ± 1%, 62.5 mW, 0402 [1005 Metric], Thick Film, General Purpose"
			(at 0 0 270)
			(layer "F.Fab")
			(hide yes)
			(effects
				(font
					(size 1.27 1.27)
					(thickness 0.15)
				)
			)
		)
		(property "MPN" "CR0402-FX-1003GLF"
			(at 0 0 270)
			(unlocked yes)
			(layer "F.Fab")
			(hide yes)
			(effects
				(font
					(size 1 1)
					(thickness 0.15)
				)
			)
		)
		(property "Manufacturer" "Bourns"
			(at 0 0 270)
			(unlocked yes)
			(layer "F.Fab")
			(hide yes)
			(effects
				(font
					(size 1 1)
					(thickness 0.15)
				)
			)
		)
		(property "License" "Apache-2.0"
			(at 0 0 270)
			(unlocked yes)
			(layer "F.Fab")
			(hide yes)
			(effects
				(font
					(size 1 1)
					(thickness 0.15)
				)
			)
		)
		(property "Author" "Antmicro"
			(at 0 0 270)
			(unlocked yes)
			(layer "F.Fab")
			(hide yes)
			(effects
				(font
					(size 1 1)
					(thickness 0.15)
				)
			)
		)
		(property "Val" "100k"
			(at 0 0 270)
			(unlocked yes)
			(layer "F.Fab")
			(hide yes)
			(effects
				(font
					(size 1 1)
					(thickness 0.15)
				)
			)
		)
		(property "Tolerance" "1%"
			(at 0 0 270)
			(unlocked yes)
			(layer "F.Fab")
			(hide yes)
			(effects
				(font
					(size 1 1)
					(thickness 0.15)
				)
			)
		)
		(sheetname "/X710-AT2 Misc/")
		(sheetfile "x710-at2-mics.kicad_sch")
		(attr smd)
		(fp_rect
			(start -0.925 -0.47)
			(end 0.925 0.47)
			(stroke
				(width 0.05)
				(type default)
			)
			(fill no)
			(layer "F.CrtYd")
		)
		(fp_rect
			(start -0.5 -0.25)
			(end 0.5 0.25)
			(stroke
				(width 0.15)
				(type solid)
			)
			(fill no)
			(layer "F.Fab")
		)
		(fp_text user "${REFERENCE}"
			(at -0.95 3.168 270)
			(layer "F.Fab")
			(effects
				(font
					(size 0.7 0.7)
					(thickness 0.15)
				)
				(justify left bottom)
			)
		)
		(fp_text user "Author: Antmicro"
			(at -0.95 4.169 270)
			(layer "F.Fab")
			(effects
				(font
					(size 0.7 0.7)
					(thickness 0.15)
				)
				(justify left bottom)
			)
		)
		(fp_text user "License: Apache-2.0"
			(at -0.95 5.169 270)
			(layer "F.Fab")
			(effects
				(font
					(size 0.7 0.7)
					(thickness 0.15)
				)
				(justify left bottom)
			)
		)
		(pad "1" smd roundrect
			(at -0.48 0 270)
			(size 0.59 0.64)
			(layers "F.Cu" "F.Mask" "F.Paste")
			(roundrect_rratio 0.25)
			(net 139 "/X710-AT2 Misc/NCSI.RXD_0")
			(pintype "passive")
		)
		(pad "2" smd roundrect
			(at 0.48 0 270)
			(size 0.59 0.64)
			(layers "F.Cu" "F.Mask" "F.Paste")
			(roundrect_rratio 0.25)
			(net 7 "+3V3")
			(pintype "passive")
		)
	)
	(footprint "antmicro-footprints:C_0402_1005Metric"
		(layer "F.Cu")
		(at 143.849999 111.150001 180)
		(descr "Capacitor SMD 0402")
		(tags "capacitor SMD 0402")
		(property "Reference" "C133"
			(at -15.349999 -17.25 180)
			(layer "F.SilkS")
			(effects
				(font
					(size 0.7 0.7)
					(thickness 0.15)
				)
			)
		)
		(property "Value" "C_33p_0402"
			(at -1.022927 2.155213 180)
			(layer "F.Fab")
			(effects
				(font
					(size 0.7 0.7)
					(thickness 0.15)
				)
				(justify left bottom)
			)
		)
		(property "Datasheet" "https://spicat.kyocera-avx.com/product/mlcc/chartview/04025A330FAT2A/"
			(at 0 0 180)
			(layer "F.Fab")
			(hide yes)
			(effects
				(font
					(size 1.27 1.27)
					(thickness 0.15)
				)
			)
		)
		(property "Description" "SMD Multilayer Ceramic Capacitor, 33 pF, 50 V, 0402 [1005 Metric], ± 5%, C0G / NP0, MC"
			(at 0 0 180)
			(layer "F.Fab")
			(hide yes)
			(effects
				(font
					(size 1.27 1.27)
					(thickness 0.15)
				)
			)
		)
		(property "MPN" "04025A330FAT2A"
			(at 0 0 180)
			(unlocked yes)
			(layer "F.Fab")
			(hide yes)
			(effects
				(font
					(size 1 1)
					(thickness 0.15)
				)
			)
		)
		(property "Manufacturer" "KYOCERA AVX"
			(at 0 0 180)
			(unlocked yes)
			(layer "F.Fab")
			(hide yes)
			(effects
				(font
					(size 1 1)
					(thickness 0.15)
				)
			)
		)
		(property "License" "Apache-2.0"
			(at 0 0 180)
			(unlocked yes)
			(layer "F.Fab")
			(hide yes)
			(effects
				(font
					(size 1 1)
					(thickness 0.15)
				)
			)
		)
		(property "Author" "Antmicro"
			(at 0 0 180)
			(unlocked yes)
			(layer "F.Fab")
			(hide yes)
			(effects
				(font
					(size 1 1)
					(thickness 0.15)
				)
			)
		)
		(property "Val" "33p"
			(at 0 0 180)
			(unlocked yes)
			(layer "F.Fab")
			(hide yes)
			(effects
				(font
					(size 1 1)
					(thickness 0.15)
				)
			)
		)
		(property "Voltage" ""
			(at 0 0 180)
			(unlocked yes)
			(layer "F.Fab")
			(hide yes)
			(effects
				(font
					(size 1 1)
					(thickness 0.15)
				)
			)
		)
		(property "Dielectric" ""
			(at 0 0 180)
			(unlocked yes)
			(layer "F.Fab")
			(hide yes)
			(effects
				(font
					(size 1 1)
					(thickness 0.15)
				)
			)
		)
		(sheetname "/X710 DCDC converters/")
		(sheetfile "DCDC_converters_X710.kicad_sch")
		(attr smd dnp)
		(fp_rect
			(start -0.925 -0.47)
			(end 0.925 0.47)
			(stroke
				(width 0.05)
				(type default)
			)
			(fill no)
			(layer "F.CrtYd")
		)
		(fp_line
			(start 0.504 0.248)
			(end -0.494 0.248)
			(stroke
				(width 0.15)
				(type solid)
			)
			(layer "F.Fab")
		)
		(fp_line
			(start 0.504 -0.25)
			(end 0.504 0.248)
			(stroke
				(width 0.15)
				(type solid)
			)
			(layer "F.Fab")
		)
		(fp_line
			(start -0.494 0.248)
			(end -0.494 -0.25)
			(stroke
				(width 0.15)
				(type solid)
			)
			(layer "F.Fab")
		)
		(fp_line
			(start -0.494 -0.25)
			(end 0.504 -0.25)
			(stroke
				(width 0.15)
				(type solid)
			)
			(layer "F.Fab")
		)
		(fp_text user "License: Apache-2.0"
			(at -0.939 5.799 180)
			(layer "F.Fab")
			(effects
				(font
					(size 0.7 0.7)
					(thickness 0.15)
				)
				(justify left bottom)
			)
		)
		(fp_text user "Author: Antmicro"
			(at -0.939 3.399 180)
			(layer "F.Fab")
			(effects
				(font
					(size 0.7 0.7)
					(thickness 0.15)
				)
				(justify left bottom)
			)
		)
		(fp_text user "${REFERENCE}"
			(at -0.939 4.599 180)
			(layer "F.Fab")
			(effects
				(font
					(size 0.7 0.7)
					(thickness 0.15)
				)
				(justify left bottom)
			)
		)
		(pad "1" smd roundrect
			(at -0.48 0 180)
			(size 0.59 0.64)
			(layers "F.Cu" "F.Mask" "F.Paste")
			(roundrect_rratio 0.25)
			(net 342 "/X710 DCDC converters/DVDD_FB")
			(pintype "passive")
		)
		(pad "2" smd roundrect
			(at 0.48 0 180)
			(size 0.59 0.64)
			(layers "F.Cu" "F.Mask" "F.Paste")
			(roundrect_rratio 0.25)
			(net 341 "/X710 DCDC converters/+DVDD_OUT")
			(pintype "passive")
		)
	)
	(footprint "antmicro-footprints:L_WE-PMFI-353220"
		(layer "F.Cu")
		(at 137.5 96.274999)
		(descr "https://www.we-online.com/en/components/products/WE-PMFI#/articles/WE-PMFI-353220")
		(property "Reference" "L4"
			(at 37.714999 -8.974998 0)
			(unlocked yes)
			(layer "F.SilkS")
			(effects
				(font
					(size 0.7 0.7)
					(thickness 0.15)
				)
			)
		)
		(property "Value" "L_2u2_5.8A_WE-PMFI-35329222"
			(at -2.6 3.1 0)
			(unlocked yes)
			(layer "F.Fab")
			(effects
				(font
					(size 0.7 0.7)
					(thickness 0.15)
				)
				(justify left bottom)
			)
		)
		(property "Datasheet" "https://www.we-online.com/components/products/datasheet/74479335329222.pdf"
			(at 0 0 0)
			(layer "F.Fab")
			(effects
				(font
					(size 0.7 0.7)
					(thickness 0.15)
				)
				(justify left bottom)
			)
		)
		(property "Description" "Power Inductors - SMD WE-PMFI 2.2 uH 5.8 A 40 mOhms AEC-Q200"
			(at 0 0 0)
			(layer "F.Fab")
			(effects
				(font
					(size 0.7 0.7)
					(thickness 0.15)
				)
				(justify left bottom)
			)
		)
		(property "Val" "2u2/5.8A"
			(at 0 0 0)
			(unlocked yes)
			(layer "F.Fab")
			(hide yes)
			(effects
				(font
					(size 1 1)
					(thickness 0.15)
				)
			)
		)
		(property "Manufacturer" "Würth Elektronik"
			(at 0 0 0)
			(unlocked yes)
			(layer "F.Fab")
			(hide yes)
			(effects
				(font
					(size 1 1)
					(thickness 0.15)
				)
			)
		)
		(property "MPN" "74479335329222"
			(at 0 0 0)
			(unlocked yes)
			(layer "F.Fab")
			(hide yes)
			(effects
				(font
					(size 1 1)
					(thickness 0.15)
				)
			)
		)
		(property "ISat" "7.8A"
			(at 0 0 0)
			(unlocked yes)
			(layer "F.Fab")
			(hide yes)
			(effects
				(font
					(size 1 1)
					(thickness 0.15)
				)
			)
		)
		(property "IMax" "5.8A"
			(at 0 0 0)
			(unlocked yes)
			(layer "F.Fab")
			(hide yes)
			(effects
				(font
					(size 1 1)
					(thickness 0.15)
				)
			)
		)
		(property "Size" "3.5x3.2x2.0"
			(at 0 0 0)
			(unlocked yes)
			(layer "F.Fab")
			(hide yes)
			(effects
				(font
					(size 1 1)
					(thickness 0.15)
				)
			)
		)
		(property "Author" "Antmicro"
			(at 0 0 0)
			(unlocked yes)
			(layer "F.Fab")
			(hide yes)
			(effects
				(font
					(size 1 1)
					(thickness 0.15)
				)
			)
		)
		(property "License" "Apache-2.0"
			(at 0 0 0)
			(unlocked yes)
			(layer "F.Fab")
			(hide yes)
			(effects
				(font
					(size 1 1)
					(thickness 0.15)
				)
			)
		)
		(sheetname "/X710 DCDC converters/")
		(sheetfile "DCDC_converters_X710.kicad_sch")
		(attr smd)
		(fp_line
			(start -1.75 -1.85)
			(end 1.75 -1.85)
			(stroke
				(width 0.15)
				(type solid)
			)
			(layer "F.SilkS")
		)
		(fp_line
			(start -1.75 1.85)
			(end 1.75 1.85)
			(stroke
				(width 0.15)
				(type solid)
			)
			(layer "F.SilkS")
		)
		(fp_rect
			(start -2.25 -2)
			(end 2.25 2)
			(stroke
				(width 0.05)
				(type solid)
			)
			(fill no)
			(layer "F.CrtYd")
		)
		(fp_rect
			(start -1.75 -1.6)
			(end 1.75 1.6)
			(stroke
				(width 0.15)
				(type solid)
			)
			(fill no)
			(layer "F.Fab")
		)
		(fp_text user "License: Apache-2.0"
			(at -2.5 6.75 0)
			(layer "F.Fab")
			(effects
				(font
					(size 0.7 0.7)
					(thickness 0.15)
				)
				(justify left bottom)
			)
		)
		(fp_text user "${REFERENCE}"
			(at -2.6 4.3 0)
			(unlocked yes)
			(layer "F.Fab")
			(effects
				(font
					(size 0.7 0.7)
					(thickness 0.15)
				)
				(justify left bottom)
			)
		)
		(fp_text user "Author: Antmicro"
			(at -2.5 5.55 0)
			(layer "F.Fab")
			(effects
				(font
					(size 0.7 0.7)
					(thickness 0.15)
				)
				(justify left bottom)
			)
		)
		(pad "1" smd rect
			(at -1.5 0)
			(size 1 3.5)
			(layers "F.Cu" "F.Mask" "F.Paste")
			(net 117 "/X710 DCDC converters/3V3_SW")
			(pintype "passive")
		)
		(pad "2" smd rect
			(at 1.5 0)
			(size 1 3.5)
			(layers "F.Cu" "F.Mask" "F.Paste")
			(net 334 "/X710 DCDC converters/+3V3_OUT")
			(pintype "passive")
		)
	)
	(footprint "antmicro-footprints:C_0603_1608Metric"
		(layer "F.Cu")
		(at 148.955001 66.024999 90)
		(descr "Capacitor SMD 0603")
		(tags "capacitor 0603")
		(property "Reference" "C221"
			(at 12.424999 20.045 90)
			(layer "F.SilkS")
			(effects
				(font
					(size 0.7 0.7)
					(thickness 0.15)
				)
			)
		)
		(property "Value" "C_10u_10V_X7R_0603"
			(at -1.42757 1.770288 90)
			(layer "F.Fab")
			(effects
				(font
					(size 0.7 0.7)
					(thickness 0.15)
				)
				(justify left bottom)
			)
		)
		(property "Datasheet" "https://www.murata.com/products/productdetail?partno=GRM188Z71A106KA73%23"
			(at 0 0 90)
			(layer "F.Fab")
			(hide yes)
			(effects
				(font
					(size 1.27 1.27)
					(thickness 0.15)
				)
			)
		)
		(property "Description" "SMD Multilayer Ceramic Capacitor,  10µF, 10V, 0603, ±10%, X7R"
			(at 0 0 90)
			(layer "F.Fab")
			(hide yes)
			(effects
				(font
					(size 1.27 1.27)
					(thickness 0.15)
				)
			)
		)
		(property "MPN" "GRM188Z71A106KA73D"
			(at 0 0 90)
			(unlocked yes)
			(layer "F.Fab")
			(hide yes)
			(effects
				(font
					(size 1 1)
					(thickness 0.15)
				)
			)
		)
		(property "Val" "10u"
			(at 0 0 90)
			(unlocked yes)
			(layer "F.Fab")
			(hide yes)
			(effects
				(font
					(size 1 1)
					(thickness 0.15)
				)
			)
		)
		(property "Voltage" "10V"
			(at 0 0 90)
			(unlocked yes)
			(layer "F.Fab")
			(hide yes)
			(effects
				(font
					(size 1 1)
					(thickness 0.15)
				)
			)
		)
		(property "Dielectric" "X7R"
			(at 0 0 90)
			(unlocked yes)
			(layer "F.Fab")
			(hide yes)
			(effects
				(font
					(size 1 1)
					(thickness 0.15)
				)
			)
		)
		(property "Manufacturer" "Murata"
			(at 0 0 90)
			(unlocked yes)
			(layer "F.Fab")
			(hide yes)
			(effects
				(font
					(size 1 1)
					(thickness 0.15)
				)
			)
		)
		(property "License" "Apache-2.0"
			(at 0 0 90)
			(unlocked yes)
			(layer "F.Fab")
			(hide yes)
			(effects
				(font
					(size 1 1)
					(thickness 0.15)
				)
			)
		)
		(property "Author" "Antmicro"
			(at 0 0 90)
			(unlocked yes)
			(layer "F.Fab")
			(hide yes)
			(effects
				(font
					(size 1 1)
					(thickness 0.15)
				)
			)
		)
		(sheetname "/X710-AT2 power/")
		(sheetfile "x710-at2-power.kicad_sch")
		(attr smd)
		(fp_line
			(start -0.15 -0.4)
			(end 0.15 -0.4)
			(stroke
				(width 0.15)
				(type solid)
			)
			(layer "F.SilkS")
		)
		(fp_line
			(start -0.15 0.4)
			(end 0.15 0.4)
			(stroke
				(width 0.15)
				(type solid)
			)
			(layer "F.SilkS")
		)
		(fp_rect
			(start -1.25 -0.65)
			(end 1.25 0.65)
			(stroke
				(width 0.05)
				(type solid)
			)
			(fill no)
			(layer "F.CrtYd")
		)
		(fp_rect
			(start -0.8 -0.4)
			(end 0.8 0.4)
			(stroke
				(width 0.15)
				(type solid)
			)
			(fill no)
			(layer "F.Fab")
		)
		(fp_text user "${REFERENCE}"
			(at -1.682 3.895 90)
			(layer "F.Fab")
			(effects
				(font
					(size 0.7 0.7)
					(thickness 0.15)
				)
				(justify left bottom)
			)
		)
		(fp_text user "License: Apache-2.0"
			(at -1.682 5.895 90)
			(layer "F.Fab")
			(effects
				(font
					(size 0.7 0.7)
					(thickness 0.15)
				)
				(justify left bottom)
			)
		)
		(fp_text user "Author: Antmicro"
			(at -1.682 4.894 90)
			(layer "F.Fab")
			(effects
				(font
					(size 0.7 0.7)
					(thickness 0.15)
				)
				(justify left bottom)
			)
		)
		(pad "1" smd roundrect
			(at -0.7 0 90)
			(size 0.8 1)
			(layers "F.Cu" "F.Mask" "F.Paste")
			(roundrect_rratio 0.2)
			(net 23 "GND")
			(pintype "passive")
		)
		(pad "2" smd roundrect
			(at 0.7 0 90)
			(size 0.8 1)
			(layers "F.Cu" "F.Mask" "F.Paste")
			(roundrect_rratio 0.2)
			(net 1 "VCCA")
			(pintype "passive")
		)
	)
	(footprint "antmicro-footprints:TSSOP-8_3x4.4mm_P0.65mm"
		(layer "F.Cu")
		(at 126 98.9 -90)
		(property "Reference" "U5"
			(at -1.9 1.8 270)
			(layer "F.SilkS")
			(effects
				(font
					(size 0.7 0.7)
					(thickness 0.15)
				)
				(justify left bottom)
			)
		)
		(property "Value" "SI52112-B6-GT"
			(at 0 3 270)
			(layer "F.Fab")
			(effects
				(font
					(size 0.7 0.7)
					(thickness 0.15)
				)
				(justify left bottom)
			)
		)
		(property "Datasheet" "https://www.skyworksinc.com/-/media/Skyworks/SL/documents/public/data-sheets/Si52112-B5-B6.pdf"
			(at 0 0 270)
			(layer "F.Fab")
			(hide yes)
			(effects
				(font
					(size 1.27 1.27)
					(thickness 0.15)
				)
			)
		)
		(property "Description" "Clock Generator, 100MHz, 2.97V to 3.63V, 2 Outputs, TSSOP-8"
			(at 0 0 270)
			(layer "F.Fab")
			(hide yes)
			(effects
				(font
					(size 1.27 1.27)
					(thickness 0.15)
				)
			)
		)
		(property "MPN" "SI52112-B6-GT"
			(at 0 0 270)
			(unlocked yes)
			(layer "F.Fab")
			(hide yes)
			(effects
				(font
					(size 1 1)
					(thickness 0.15)
				)
			)
		)
		(property "Manufacturer" "Skyworks Solutions"
			(at 0 0 270)
			(unlocked yes)
			(layer "F.Fab")
			(hide yes)
			(effects
				(font
					(size 1 1)
					(thickness 0.15)
				)
			)
		)
		(property "License" "Apache-2.0"
			(at 0 0 270)
			(unlocked yes)
			(layer "F.Fab")
			(hide yes)
			(effects
				(font
					(size 1 1)
					(thickness 0.15)
				)
			)
		)
		(property "Author" "Antmicro"
			(at 0 0 270)
			(unlocked yes)
			(layer "F.Fab")
			(hide yes)
			(effects
				(font
					(size 1 1)
					(thickness 0.15)
				)
			)
		)
		(sheetname "/TB Controller/")
		(sheetfile "tb.kicad_sch")
		(attr smd)
		(fp_line
			(start -2.3 1.6)
			(end -1.7 1.6)
			(stroke
				(width 0.15)
				(type solid)
			)
			(layer "F.SilkS")
		)
		(fp_line
			(start 2.3 1.6)
			(end 1.8 1.6)
			(stroke
				(width 0.15)
				(type solid)
			)
			(layer "F.SilkS")
		)
		(fp_line
			(start -2.3 1.3)
			(end -2.3 1.6)
			(stroke
				(width 0.15)
				(type solid)
			)
			(layer "F.SilkS")
		)
		(fp_line
			(start 2.3 1.25)
			(end 2.3 1.6)
			(stroke
				(width 0.15)
				(type solid)
			)
			(layer "F.SilkS")
		)
		(fp_line
			(start -2.3 -1.3)
			(end -2.3 -1.6)
			(stroke
				(width 0.15)
				(type solid)
			)
			(layer "F.SilkS")
		)
		(fp_line
			(start 2.3 -1.3)
			(end 2.3 -1.6)
			(stroke
				(width 0.15)
				(type solid)
			)
			(layer "F.SilkS")
		)
		(fp_line
			(start -2.3 -1.6)
			(end -1.7 -1.6)
			(stroke
				(width 0.15)
				(type solid)
			)
			(layer "F.SilkS")
		)
		(fp_line
			(start 2.3 -1.6)
			(end 1.8 -1.6)
			(stroke
				(width 0.15)
				(type solid)
			)
			(layer "F.SilkS")
		)
		(fp_circle
			(center -2.7 -1.51)
			(end -2.65 -1.51)
			(stroke
				(width 0.15)
				(type solid)
			)
			(fill yes)
			(layer "F.SilkS")
		)
		(fp_rect
			(start -3.45 -1.75)
			(end 3.45 1.75)
			(stroke
				(width 0.05)
				(type solid)
			)
			(fill no)
			(layer "F.CrtYd")
		)
		(fp_line
			(start -2.2 1.5)
			(end 2.2 1.5)
			(stroke
				(width 0.15)
				(type solid)
			)
			(layer "F.Fab")
		)
		(fp_line
			(start -2.2 -0.7)
			(end -2.2 1.5)
			(stroke
				(width 0.15)
				(type solid)
			)
			(layer "F.Fab")
		)
		(fp_line
			(start -2.2 -0.7)
			(end -1.4 -1.5)
			(stroke
				(width 0.15)
				(type solid)
			)
			(layer "F.Fab")
		)
		(fp_line
			(start -1.4 -1.5)
			(end 2.2 -1.5)
			(stroke
				(width 0.15)
				(type solid)
			)
			(layer "F.Fab")
		)
		(fp_line
			(start 2.2 -1.5)
			(end 2.2 1.5)
			(stroke
				(width 0.15)
				(type solid)
			)
			(layer "F.Fab")
		)
		(fp_text user "Author: Antmicro"
			(at -3.55 5 270)
			(layer "F.Fab")
			(effects
				(font
					(size 0.7 0.7)
					(thickness 0.15)
				)
				(justify left bottom)
			)
		)
		(fp_text user "${REFERENCE}"
			(at -3.55 7.4 270)
			(layer "F.Fab")
			(effects
				(font
					(size 0.7 0.7)
					(thickness 0.15)
				)
				(justify left bottom)
			)
		)
		(fp_text user "License: Apache-2.0"
			(at -3.55 6.2 270)
			(layer "F.Fab")
			(effects
				(font
					(size 0.7 0.7)
					(thickness 0.15)
				)
				(justify left bottom)
			)
		)
		(pad "1" smd rect
			(at -2.7 -0.975 270)
			(size 1.2 0.4)
			(layers "F.Cu" "F.Mask" "F.Paste")
			(net 57 "+3V3_TB")
			(pinfunction "VDD")
			(pintype "power_in")
		)
		(pad "2" smd rect
			(at -2.7 -0.325 270)
			(size 1.2 0.4)
			(layers "F.Cu" "F.Mask" "F.Paste")
			(net 400 "Net-(U5-XOUT)")
			(pinfunction "XOUT")
			(pintype "output")
		)
		(pad "3" smd rect
			(at -2.7 0.325 270)
			(size 1.2 0.4)
			(layers "F.Cu" "F.Mask" "F.Paste")
			(net 401 "Net-(U5-XIN{slash}CLKIN)")
			(pinfunction "XIN/CLKIN")
			(pintype "input")
		)
		(pad "4" smd rect
			(at -2.7 0.975 270)
			(size 1.2 0.4)
			(layers "F.Cu" "F.Mask" "F.Paste")
			(net 23 "GND")
			(pinfunction "GND")
			(pintype "power_in")
		)
		(pad "5" smd rect
			(at 2.7 0.975 270)
			(size 1.2 0.4)
			(layers "F.Cu" "F.Mask" "F.Paste")
			(net 214 "/TB Controller/PCIE_CLK_JHL_N")
			(pinfunction "DIFF1")
			(pintype "output")
		)
		(pad "6" smd rect
			(at 2.7 0.325 270)
			(size 1.2 0.4)
			(layers "F.Cu" "F.Mask" "F.Paste")
			(net 213 "/TB Controller/PCIE_CLK_JHL_P")
			(pinfunction "~{DIFF1}")
			(pintype "output")
		)
		(pad "7" smd rect
			(at 2.7 -0.325 270)
			(size 1.2 0.4)
			(layers "F.Cu" "F.Mask" "F.Paste")
			(net 394 "/TB Controller/REFCLK.-")
			(pinfunction "DIFF2")
			(pintype "output")
		)
		(pad "8" smd rect
			(at 2.7 -0.975 270)
			(size 1.2 0.4)
			(layers "F.Cu" "F.Mask" "F.Paste")
			(net 393 "/TB Controller/REFCLK.+")
			(pinfunction "~{DIFF2}")
			(pintype "output")
		)
	)
	(footprint "antmicro-footprints:C_0402_1005Metric"
		(layer "F.Cu")
		(at 130 98.7)
		(descr "Capacitor SMD 0402")
		(tags "capacitor SMD 0402")
		(property "Reference" "C39"
			(at 2.2 4.3 0)
			(layer "F.SilkS")
			(effects
				(font
					(size 0.7 0.7)
					(thickness 0.15)
				)
			)
		)
		(property "Value" "C_10p_0402"
			(at -1.022927 2.155213 0)
			(layer "F.Fab")
			(effects
				(font
					(size 0.7 0.7)
					(thickness 0.15)
				)
				(justify left bottom)
			)
		)
		(property "Datasheet" "https://www.murata.com/products/productdetail?partno=GCM1555C1H100GA16%23"
			(at 0 0 0)
			(layer "F.Fab")
			(hide yes)
			(effects
				(font
					(size 1.27 1.27)
					(thickness 0.15)
				)
			)
		)
		(property "Description" "SMD Multilayer Ceramic Capacitor, 10 pF, 50 V, 0402 [1005 Metric], ± 2%, C0G / NP0, GCM"
			(at 0 0 0)
			(layer "F.Fab")
			(hide yes)
			(effects
				(font
					(size 1.27 1.27)
					(thickness 0.15)
				)
			)
		)
		(property "MPN" "GCM1555C1H100GA16D"
			(at 0 0 0)
			(unlocked yes)
			(layer "F.Fab")
			(hide yes)
			(effects
				(font
					(size 1 1)
					(thickness 0.15)
				)
			)
		)
		(property "Manufacturer" "Murata"
			(at 0 0 0)
			(unlocked yes)
			(layer "F.Fab")
			(hide yes)
			(effects
				(font
					(size 1 1)
					(thickness 0.15)
				)
			)
		)
		(property "License" "Apache-2.0"
			(at 0 0 0)
			(unlocked yes)
			(layer "F.Fab")
			(hide yes)
			(effects
				(font
					(size 1 1)
					(thickness 0.15)
				)
			)
		)
		(property "Val" "10p"
			(at 0 0 0)
			(unlocked yes)
			(layer "F.Fab")
			(hide yes)
			(effects
				(font
					(size 1 1)
					(thickness 0.15)
				)
			)
		)
		(property "Voltage" "50V"
			(at 0 0 0)
			(unlocked yes)
			(layer "F.Fab")
			(hide yes)
			(effects
				(font
					(size 1 1)
					(thickness 0.15)
				)
			)
		)
		(property "Dielectric" "C0G"
			(at 0 0 0)
			(unlocked yes)
			(layer "F.Fab")
			(hide yes)
			(effects
				(font
					(size 1 1)
					(thickness 0.15)
				)
			)
		)
		(property "Author" "Antmicro"
			(at 0 0 0)
			(unlocked yes)
			(layer "F.Fab")
			(hide yes)
			(effects
				(font
					(size 1 1)
					(thickness 0.15)
				)
			)
		)
		(sheetname "/TB Controller/")
		(sheetfile "tb.kicad_sch")
		(attr smd)
		(fp_rect
			(start -0.925 -0.47)
			(end 0.925 0.47)
			(stroke
				(width 0.05)
				(type default)
			)
			(fill no)
			(layer "F.CrtYd")
		)
		(fp_line
			(start -0.494 -0.25)
			(end 0.504 -0.25)
			(stroke
				(width 0.15)
				(type solid)
			)
			(layer "F.Fab")
		)
		(fp_line
			(start -0.494 0.248)
			(end -0.494 -0.25)
			(stroke
				(width 0.15)
				(type solid)
			)
			(layer "F.Fab")
		)
		(fp_line
			(start 0.504 -0.25)
			(end 0.504 0.248)
			(stroke
				(width 0.15)
				(type solid)
			)
			(layer "F.Fab")
		)
		(fp_line
			(start 0.504 0.248)
			(end -0.494 0.248)
			(stroke
				(width 0.15)
				(type solid)
			)
			(layer "F.Fab")
		)
		(fp_text user "${REFERENCE}"
			(at -0.939 4.599 0)
			(layer "F.Fab")
			(effects
				(font
					(size 0.7 0.7)
					(thickness 0.15)
				)
				(justify left bottom)
			)
		)
		(fp_text user "License: Apache-2.0"
			(at -0.939 5.799 0)
			(layer "F.Fab")
			(effects
				(font
					(size 0.7 0.7)
					(thickness 0.15)
				)
				(justify left bottom)
			)
		)
		(fp_text user "Author: Antmicro"
			(at -0.939 3.399 0)
			(layer "F.Fab")
			(effects
				(font
					(size 0.7 0.7)
					(thickness 0.15)
				)
				(justify left bottom)
			)
		)
		(pad "1" smd roundrect
			(at -0.48 0)
			(size 0.59 0.64)
			(layers "F.Cu" "F.Mask" "F.Paste")
			(roundrect_rratio 0.25)
			(net 23 "GND")
			(pintype "passive")
		)
		(pad "2" smd roundrect
			(at 0.48 0)
			(size 0.59 0.64)
			(layers "F.Cu" "F.Mask" "F.Paste")
			(roundrect_rratio 0.25)
			(net 400 "Net-(U5-XOUT)")
			(pintype "passive")
		)
	)
	(footprint "antmicro-footprints:C_0402_1005Metric"
		(layer "F.Cu")
		(at 160.105 69.075 90)
		(descr "Capacitor SMD 0402")
		(tags "capacitor SMD 0402")
		(property "Reference" "C286"
			(at 11.574999 20.295 90)
			(layer "F.SilkS")
			(effects
				(font
					(size 0.7 0.7)
					(thickness 0.15)
				)
			)
		)
		(property "Value" "C_100n_0402"
			(at -1.022927 2.155213 90)
			(layer "F.Fab")
			(effects
				(font
					(size 0.7 0.7)
					(thickness 0.15)
				)
				(justify left bottom)
			)
		)
		(property "Datasheet" "https://www.murata.com/products/productdetail?partno=GRM155R61H104KE14%23"
			(at 0 0 90)
			(layer "F.Fab")
			(hide yes)
			(effects
				(font
					(size 1.27 1.27)
					(thickness 0.15)
				)
			)
		)
		(property "Description" "SMD Multilayer Ceramic Capacitor, 0.1 µF, 50 V, 0402 [1005 Metric], ± 10%, X5R, GRM Series"
			(at 0 0 90)
			(layer "F.Fab")
			(hide yes)
			(effects
				(font
					(size 1.27 1.27)
					(thickness 0.15)
				)
			)
		)
		(property "MPN" "GRM155R61H104KE14D"
			(at 0 0 90)
			(unlocked yes)
			(layer "F.Fab")
			(hide yes)
			(effects
				(font
					(size 1 1)
					(thickness 0.15)
				)
			)
		)
		(property "Val" "100n"
			(at 0 0 90)
			(unlocked yes)
			(layer "F.Fab")
			(hide yes)
			(effects
				(font
					(size 1 1)
					(thickness 0.15)
				)
			)
		)
		(property "Voltage" "50V"
			(at 0 0 90)
			(unlocked yes)
			(layer "F.Fab")
			(hide yes)
			(effects
				(font
					(size 1 1)
					(thickness 0.15)
				)
			)
		)
		(property "Dielectric" "X5R"
			(at 0 0 90)
			(unlocked yes)
			(layer "F.Fab")
			(hide yes)
			(effects
				(font
					(size 1 1)
					(thickness 0.15)
				)
			)
		)
		(property "Manufacturer" "Murata"
			(at 0 0 90)
			(unlocked yes)
			(layer "F.Fab")
			(hide yes)
			(effects
				(font
					(size 1 1)
					(thickness 0.15)
				)
			)
		)
		(property "License" "Apache-2.0"
			(at 0 0 90)
			(unlocked yes)
			(layer "F.Fab")
			(hide yes)
			(effects
				(font
					(size 1 1)
					(thickness 0.15)
				)
			)
		)
		(property "Author" "Antmicro"
			(at 0 0 90)
			(unlocked yes)
			(layer "F.Fab")
			(hide yes)
			(effects
				(font
					(size 1 1)
					(thickness 0.15)
				)
			)
		)
		(sheetname "/X710-AT2 10GbE/")
		(sheetfile "x710-at2-10gbe.kicad_sch")
		(attr smd)
		(fp_rect
			(start -0.925 -0.47)
			(end 0.925 0.47)
			(stroke
				(width 0.05)
				(type default)
			)
			(fill no)
			(layer "F.CrtYd")
		)
		(fp_line
			(start 0.504 -0.25)
			(end 0.504 0.248)
			(stroke
				(width 0.15)
				(type solid)
			)
			(layer "F.Fab")
		)
		(fp_line
			(start -0.494 -0.25)
			(end 0.504 -0.25)
			(stroke
				(width 0.15)
				(type solid)
			)
			(layer "F.Fab")
		)
		(fp_line
			(start 0.504 0.248)
			(end -0.494 0.248)
			(stroke
				(width 0.15)
				(type solid)
			)
			(layer "F.Fab")
		)
		(fp_line
			(start -0.494 0.248)
			(end -0.494 -0.25)
			(stroke
				(width 0.15)
				(type solid)
			)
			(layer "F.Fab")
		)
		(fp_text user "${REFERENCE}"
			(at -0.939 4.599 90)
			(layer "F.Fab")
			(effects
				(font
					(size 0.7 0.7)
					(thickness 0.15)
				)
				(justify left bottom)
			)
		)
		(fp_text user "License: Apache-2.0"
			(at -0.939 5.799 90)
			(layer "F.Fab")
			(effects
				(font
					(size 0.7 0.7)
					(thickness 0.15)
				)
				(justify left bottom)
			)
		)
		(fp_text user "Author: Antmicro"
			(at -0.939 3.399 90)
			(layer "F.Fab")
			(effects
				(font
					(size 0.7 0.7)
					(thickness 0.15)
				)
				(justify left bottom)
			)
		)
		(pad "1" smd roundrect
			(at -0.48 0 90)
			(size 0.59 0.64)
			(layers "F.Cu" "F.Mask" "F.Paste")
			(roundrect_rratio 0.25)
			(net 26 "/X710-AT2 10GbE/25MHZ_OSC.-")
			(pintype "passive")
		)
		(pad "2" smd roundrect
			(at 0.48 0 90)
			(size 0.59 0.64)
			(layers "F.Cu" "F.Mask" "F.Paste")
			(roundrect_rratio 0.25)
			(net 55 "/X710-AT2 10GbE/25MHZ_OSC_AC.-")
			(pintype "passive")
		)
	)
	(footprint "antmicro-footprints:C_0603_1608Metric_EIA"
		(layer "F.Cu")
		(at 133.105001 99.774999 -90)
		(descr "Capacitor SMD 0603, IPC-7351 Density Level A")
		(tags "Capacitor 0603")
		(property "Reference" "C252"
			(at -9.274999 -38.13 270)
			(layer "F.SilkS")
			(effects
				(font
					(size 0.7 0.7)
					(thickness 0.15)
				)
			)
		)
		(property "Value" "C_22u_16V_0603"
			(at -1.42757 1.770288 270)
			(layer "F.Fab")
			(effects
				(font
					(size 0.7 0.7)
					(thickness 0.15)
				)
				(justify left bottom)
			)
		)
		(property "Datasheet" "https://product.samsungsem.com/mlcc/CL10A226MO7JZN.do"
			(at 0 0 270)
			(layer "F.Fab")
			(hide yes)
			(effects
				(font
					(size 1.27 1.27)
					(thickness 0.15)
				)
			)
		)
		(property "Description" "SMD Multilayer Ceramic Capacitor"
			(at 0 0 270)
			(layer "F.Fab")
			(hide yes)
			(effects
				(font
					(size 1.27 1.27)
					(thickness 0.15)
				)
			)
		)
		(property "MPN" "CL10A226MO7JZNC"
			(at 0 0 270)
			(unlocked yes)
			(layer "F.Fab")
			(hide yes)
			(effects
				(font
					(size 1 1)
					(thickness 0.15)
				)
			)
		)
		(property "Manufacturer" "Samsung Electro-Mechanics"
			(at 0 0 270)
			(unlocked yes)
			(layer "F.Fab")
			(hide yes)
			(effects
				(font
					(size 1 1)
					(thickness 0.15)
				)
			)
		)
		(property "License" "Apache-2.0"
			(at 0 0 270)
			(unlocked yes)
			(layer "F.Fab")
			(hide yes)
			(effects
				(font
					(size 1 1)
					(thickness 0.15)
				)
			)
		)
		(property "Author" "Antmicro"
			(at 0 0 270)
			(unlocked yes)
			(layer "F.Fab")
			(hide yes)
			(effects
				(font
					(size 1 1)
					(thickness 0.15)
				)
			)
		)
		(property "Val" "22u"
			(at 0 0 270)
			(unlocked yes)
			(layer "F.Fab")
			(hide yes)
			(effects
				(font
					(size 1 1)
					(thickness 0.15)
				)
			)
		)
		(property "Voltage" "16V"
			(at 0 0 270)
			(unlocked yes)
			(layer "F.Fab")
			(hide yes)
			(effects
				(font
					(size 1 1)
					(thickness 0.15)
				)
			)
		)
		(property "Dielectric" ""
			(at 0 0 270)
			(unlocked yes)
			(layer "F.Fab")
			(hide yes)
			(effects
				(font
					(size 1 1)
					(thickness 0.15)
				)
			)
		)
		(sheetname "/X710-AT2 power/")
		(sheetfile "x710-at2-power.kicad_sch")
		(attr smd)
		(fp_line
			(start -0.15 0.55)
			(end 0.15 0.55)
			(stroke
				(width 0.15)
				(type solid)
			)
			(layer "F.SilkS")
		)
		(fp_line
			(start -0.15 -0.55)
			(end 0.15 -0.55)
			(stroke
				(width 0.15)
				(type solid)
			)
			(layer "F.SilkS")
		)
		(fp_rect
			(start -1.25 -0.65)
			(end 1.25 0.65)
			(stroke
				(width 0.05)
				(type solid)
			)
			(fill no)
			(layer "F.CrtYd")
		)
		(fp_rect
			(start -0.8 -0.45)
			(end 0.8 0.45)
			(stroke
				(width 0.15)
				(type solid)
			)
			(fill no)
			(layer "F.Fab")
		)
		(fp_text user "Author: Antmicro"
			(at -1.682 4.894 270)
			(layer "F.Fab")
			(effects
				(font
					(size 0.7 0.7)
					(thickness 0.15)
				)
				(justify left bottom)
			)
		)
		(fp_text user "${REFERENCE}"
			(at -1.682 3.895 270)
			(layer "F.Fab")
			(effects
				(font
					(size 0.7 0.7)
					(thickness 0.15)
				)
				(justify left bottom)
			)
		)
		(fp_text user "License: Apache-2.0"
			(at -1.682 5.895 270)
			(layer "F.Fab")
			(effects
				(font
					(size 0.7 0.7)
					(thickness 0.15)
				)
				(justify left bottom)
			)
		)
		(pad "1" smd roundrect
			(at -0.7 0 270)
			(size 0.8 1.1)
			(layers "F.Cu" "F.Mask" "F.Paste")
			(roundrect_rratio 0.2)
			(net 23 "GND")
			(pintype "passive")
		)
		(pad "2" smd roundrect
			(at 0.7 0 270)
			(size 0.8 1.1)
			(layers "F.Cu" "F.Mask" "F.Paste")
			(roundrect_rratio 0.2)
			(net 9 "VCCD")
			(pintype "passive")
		)
	)
	(footprint "antmicro-footprints:C_0402_1005Metric"
		(layer "F.Cu")
		(at 162.6 111.85)
		(descr "Capacitor SMD 0402")
		(tags "capacitor SMD 0402")
		(property "Reference" "C117"
			(at 12.450003 16.799998 0)
			(layer "F.SilkS")
			(effects
				(font
					(size 0.7 0.7)
					(thickness 0.15)
				)
			)
		)
		(property "Value" "C_100n_0402"
			(at -1.022927 2.155213 0)
			(layer "F.Fab")
			(effects
				(font
					(size 0.7 0.7)
					(thickness 0.15)
				)
				(justify left bottom)
			)
		)
		(property "Datasheet" "https://www.murata.com/products/productdetail?partno=GRM155R61H104KE14%23"
			(at 0 0 0)
			(layer "F.Fab")
			(hide yes)
			(effects
				(font
					(size 1.27 1.27)
					(thickness 0.15)
				)
			)
		)
		(property "Description" "SMD Multilayer Ceramic Capacitor, 0.1 µF, 50 V, 0402 [1005 Metric], ± 10%, X5R, GRM Series"
			(at 0 0 0)
			(layer "F.Fab")
			(hide yes)
			(effects
				(font
					(size 1.27 1.27)
					(thickness 0.15)
				)
			)
		)
		(property "MPN" "GRM155R61H104KE14D"
			(at 0 0 0)
			(unlocked yes)
			(layer "F.Fab")
			(hide yes)
			(effects
				(font
					(size 1 1)
					(thickness 0.15)
				)
			)
		)
		(property "Manufacturer" "Murata"
			(at 0 0 0)
			(unlocked yes)
			(layer "F.Fab")
			(hide yes)
			(effects
				(font
					(size 1 1)
					(thickness 0.15)
				)
			)
		)
		(property "License" "Apache-2.0"
			(at 0 0 0)
			(unlocked yes)
			(layer "F.Fab")
			(hide yes)
			(effects
				(font
					(size 1 1)
					(thickness 0.15)
				)
			)
		)
		(property "Author" "Antmicro"
			(at 0 0 0)
			(unlocked yes)
			(layer "F.Fab")
			(hide yes)
			(effects
				(font
					(size 1 1)
					(thickness 0.15)
				)
			)
		)
		(property "Val" "100n"
			(at 0 0 0)
			(unlocked yes)
			(layer "F.Fab")
			(hide yes)
			(effects
				(font
					(size 1 1)
					(thickness 0.15)
				)
			)
		)
		(property "Voltage" "50V"
			(at 0 0 0)
			(unlocked yes)
			(layer "F.Fab")
			(hide yes)
			(effects
				(font
					(size 1 1)
					(thickness 0.15)
				)
			)
		)
		(property "Dielectric" "X5R"
			(at 0 0 0)
			(unlocked yes)
			(layer "F.Fab")
			(hide yes)
			(effects
				(font
					(size 1 1)
					(thickness 0.15)
				)
			)
		)
		(sheetname "/X710 DCDC converters/")
		(sheetfile "DCDC_converters_X710.kicad_sch")
		(attr smd)
		(fp_rect
			(start -0.925 -0.47)
			(end 0.925 0.47)
			(stroke
				(width 0.05)
				(type default)
			)
			(fill no)
			(layer "F.CrtYd")
		)
		(fp_line
			(start -0.494 -0.25)
			(end 0.504 -0.25)
			(stroke
				(width 0.15)
				(type solid)
			)
			(layer "F.Fab")
		)
		(fp_line
			(start -0.494 0.248)
			(end -0.494 -0.25)
			(stroke
				(width 0.15)
				(type solid)
			)
			(layer "F.Fab")
		)
		(fp_line
			(start 0.504 -0.25)
			(end 0.504 0.248)
			(stroke
				(width 0.15)
				(type solid)
			)
			(layer "F.Fab")
		)
		(fp_line
			(start 0.504 0.248)
			(end -0.494 0.248)
			(stroke
				(width 0.15)
				(type solid)
			)
			(layer "F.Fab")
		)
		(fp_text user "${REFERENCE}"
			(at -0.939 4.599 0)
			(layer "F.Fab")
			(effects
				(font
					(size 0.7 0.7)
					(thickness 0.15)
				)
				(justify left bottom)
			)
		)
		(fp_text user "License: Apache-2.0"
			(at -0.939 5.799 0)
			(layer "F.Fab")
			(effects
				(font
					(size 0.7 0.7)
					(thickness 0.15)
				)
				(justify left bottom)
			)
		)
		(fp_text user "Author: Antmicro"
			(at -0.939 3.399 0)
			(layer "F.Fab")
			(effects
				(font
					(size 0.7 0.7)
					(thickness 0.15)
				)
				(justify left bottom)
			)
		)
		(pad "1" smd roundrect
			(at -0.48 0)
			(size 0.59 0.64)
			(layers "F.Cu" "F.Mask" "F.Paste")
			(roundrect_rratio 0.25)
			(net 23 "GND")
			(pintype "passive")
		)
		(pad "2" smd roundrect
			(at 0.48 0)
			(size 0.59 0.64)
			(layers "F.Cu" "F.Mask" "F.Paste")
			(roundrect_rratio 0.25)
			(net 40 "+5V")
			(pintype "passive")
		)
	)
	(footprint "antmicro-footprints:LED_0603_1608Metric_G"
		(layer "F.Cu")
		(at 135 143.5 -90)
		(descr "LED SMD 0603 Green")
		(tags "LED SMD 0603 Green")
		(property "Reference" "D11"
			(at 1 0.8 270)
			(layer "F.SilkS")
			(effects
				(font
					(size 0.7 0.7)
					(thickness 0.15)
				)
				(justify left bottom)
			)
		)
		(property "Value" "LED_G_0603_LG_L29K-G2J1-24-Z"
			(at -0.001 1.599 270)
			(layer "F.Fab")
			(effects
				(font
					(size 0.7 0.7)
					(thickness 0.15)
				)
				(justify left bottom)
			)
		)
		(property "Datasheet" "https://look.ams-osram.com/m/19ee86b3ae0ee95b/original/LG-L29K.pdf"
			(at 0 0 270)
			(layer "F.Fab")
			(hide yes)
			(effects
				(font
					(size 1.27 1.27)
					(thickness 0.15)
				)
			)
		)
		(property "Description" "LED, Green, SMD, 0603, 20 mA, 1.7 V, 570 nm"
			(at 0 0 270)
			(layer "F.Fab")
			(hide yes)
			(effects
				(font
					(size 1.27 1.27)
					(thickness 0.15)
				)
			)
		)
		(property "MPN" "LG L29K-G2J1-24-Z"
			(at 0 0 270)
			(unlocked yes)
			(layer "F.Fab")
			(hide yes)
			(effects
				(font
					(size 1 1)
					(thickness 0.15)
				)
			)
		)
		(property "Manufacturer" "OSRAM"
			(at 0 0 270)
			(unlocked yes)
			(layer "F.Fab")
			(hide yes)
			(effects
				(font
					(size 1 1)
					(thickness 0.15)
				)
			)
		)
		(property "Color" "Green"
			(at 0 0 270)
			(unlocked yes)
			(layer "F.Fab")
			(hide yes)
			(effects
				(font
					(size 1 1)
					(thickness 0.15)
				)
			)
		)
		(property "Author" "Antmicro"
			(at 0 0 270)
			(unlocked yes)
			(layer "F.Fab")
			(hide yes)
			(effects
				(font
					(size 1 1)
					(thickness 0.15)
				)
			)
		)
		(property "License" "Apache-2.0"
			(at 0 0 270)
			(unlocked yes)
			(layer "F.Fab")
			(hide yes)
			(effects
				(font
					(size 1 1)
					(thickness 0.15)
				)
			)
		)
		(sheetname "/X710 DCDC converters/")
		(sheetfile "DCDC_converters_X710.kicad_sch")
		(attr smd)
		(fp_line
			(start 0.22 0.35)
			(end -0.22 0.35)
			(stroke
				(width 0.15)
				(type solid)
			)
			(layer "F.SilkS")
		)
		(fp_line
			(start -0.094672 0.201008)
			(end -0.094672 -0.198992)
			(stroke
				(width 0.1)
				(type solid)
			)
			(layer "F.SilkS")
		)
		(fp_line
			(start 0.105328 0.201008)
			(end -0.094672 0.001008)
			(stroke
				(width 0.1)
				(type solid)
			)
			(layer "F.SilkS")
		)
		(fp_line
			(start 0.105328 0.201008)
			(end 0.105328 -0.198992)
			(stroke
				(width 0.1)
				(type solid)
			)
			(layer "F.SilkS")
		)
		(fp_line
			(start -0.094672 0.001008)
			(end -0.24 0.001008)
			(stroke
				(width 0.1)
				(type solid)
			)
			(layer "F.SilkS")
		)
		(fp_line
			(start -0.094672 0.001008)
			(end 0.105328 -0.198992)
			(stroke
				(width 0.1)
				(type solid)
			)
			(layer "F.SilkS")
		)
		(fp_line
			(start 0.105328 0.001008)
			(end 0.24 0.001)
			(stroke
				(width 0.1)
				(type solid)
			)
			(layer "F.SilkS")
		)
		(fp_line
			(start -1.18 -0.319)
			(end -1.18 0.321)
			(stroke
				(width 0.15)
				(type solid)
			)
			(layer "F.SilkS")
		)
		(fp_line
			(start 0.22 -0.35)
			(end -0.22 -0.35)
			(stroke
				(width 0.15)
				(type solid)
			)
			(layer "F.SilkS")
		)
		(fp_rect
			(start 1.25 0.65)
			(end -1.25 -0.65)
			(stroke
				(width 0.05)
				(type solid)
			)
			(fill no)
			(layer "F.CrtYd")
		)
		(fp_line
			(start -0.199 0.2)
			(end -0.199 0.1)
			(stroke
				(width 0.15)
				(type solid)
			)
			(layer "F.Fab")
		)
		(fp_line
			(start 0.201 0.2)
			(end 0.201 0)
			(stroke
				(width 0.15)
				(type solid)
			)
			(layer "F.Fab")
		)
		(fp_line
			(start -0.199 0)
			(end -0.597 0)
			(stroke
				(width 0.15)
				(type solid)
			)
			(layer "F.Fab")
		)
		(fp_line
			(start -0.101 0)
			(end 0.201 0.2)
			(stroke
				(width 0.15)
				(type solid)
			)
			(layer "F.Fab")
		)
		(fp_line
			(start 0.201 0)
			(end 0.201 -0.202)
			(stroke
				(width 0.15)
				(type solid)
			)
			(layer "F.Fab")
		)
		(fp_line
			(start 0.599 0)
			(end 0.201 0)
			(stroke
				(width 0.15)
				(type solid)
			)
			(layer "F.Fab")
		)
		(fp_line
			(start -0.199 -0.202)
			(end -0.199 0.1)
			(stroke
				(width 0.15)
				(type solid)
			)
			(layer "F.Fab")
		)
		(fp_line
			(start 0.201 -0.202)
			(end -0.101 0)
			(stroke
				(width 0.15)
				(type solid)
			)
			(layer "F.Fab")
		)
		(fp_rect
			(start 0.848 0.4)
			(end -0.85 -0.402)
			(stroke
				(width 0.15)
				(type solid)
			)
			(fill no)
			(layer "F.Fab")
		)
		(fp_text user "License: Apache-2.0"
			(at -1.4224 3.599 270)
			(layer "F.Fab")
			(effects
				(font
					(size 0.7 0.7)
					(thickness 0.15)
				)
				(justify left bottom)
			)
		)
		(fp_text user "${REFERENCE}"
			(at -1.4224 5.999 270)
			(layer "F.Fab")
			(effects
				(font
					(size 0.7 0.7)
					(thickness 0.15)
				)
				(justify left bottom)
			)
		)
		(fp_text user "Author: Antmicro"
			(at -1.4224 4.799 270)
			(layer "F.Fab")
			(effects
				(font
					(size 0.7 0.7)
					(thickness 0.15)
				)
				(justify left bottom)
			)
		)
		(pad "1" smd roundrect
			(at -0.7 0 90)
			(size 0.8 1)
			(layers "F.Cu" "F.Mask" "F.Paste")
			(roundrect_rratio 0.2)
			(net 418 "Net-(D11-C)")
			(pinfunction "C")
			(pintype "passive")
		)
		(pad "2" smd roundrect
			(at 0.7 0 90)
			(size 0.8 1)
			(layers "F.Cu" "F.Mask" "F.Paste")
			(roundrect_rratio 0.2)
			(net 419 "Net-(D11-A)")
			(pinfunction "A")
			(pintype "passive")
		)
	)
	(footprint "antmicro-footprints:C_0402_1005Metric"
		(layer "F.Cu")
		(at 132.2 96.4 -90)
		(descr "Capacitor SMD 0402")
		(tags "capacitor SMD 0402")
		(property "Reference" "C114"
			(at -9.299999 -37.414999 270)
			(layer "F.SilkS")
			(effects
				(font
					(size 0.7 0.7)
					(thickness 0.15)
				)
			)
		)
		(property "Value" "C_100n_0402"
			(at -1.022927 2.155213 270)
			(layer "F.Fab")
			(effects
				(font
					(size 0.7 0.7)
					(thickness 0.15)
				)
				(justify left bottom)
			)
		)
		(property "Datasheet" "https://www.murata.com/products/productdetail?partno=GRM155R61H104KE14%23"
			(at 0 0 270)
			(layer "F.Fab")
			(hide yes)
			(effects
				(font
					(size 1.27 1.27)
					(thickness 0.15)
				)
			)
		)
		(property "Description" "SMD Multilayer Ceramic Capacitor, 0.1 µF, 50 V, 0402 [1005 Metric], ± 10%, X5R, GRM Series"
			(at 0 0 270)
			(layer "F.Fab")
			(hide yes)
			(effects
				(font
					(size 1.27 1.27)
					(thickness 0.15)
				)
			)
		)
		(property "MPN" "GRM155R61H104KE14D"
			(at 0 0 270)
			(unlocked yes)
			(layer "F.Fab")
			(hide yes)
			(effects
				(font
					(size 1 1)
					(thickness 0.15)
				)
			)
		)
		(property "Manufacturer" "Murata"
			(at 0 0 270)
			(unlocked yes)
			(layer "F.Fab")
			(hide yes)
			(effects
				(font
					(size 1 1)
					(thickness 0.15)
				)
			)
		)
		(property "License" "Apache-2.0"
			(at 0 0 270)
			(unlocked yes)
			(layer "F.Fab")
			(hide yes)
			(effects
				(font
					(size 1 1)
					(thickness 0.15)
				)
			)
		)
		(property "Author" "Antmicro"
			(at 0 0 270)
			(unlocked yes)
			(layer "F.Fab")
			(hide yes)
			(effects
				(font
					(size 1 1)
					(thickness 0.15)
				)
			)
		)
		(property "Val" "100n"
			(at 0 0 270)
			(unlocked yes)
			(layer "F.Fab")
			(hide yes)
			(effects
				(font
					(size 1 1)
					(thickness 0.15)
				)
			)
		)
		(property "Voltage" "50V"
			(at 0 0 270)
			(unlocked yes)
			(layer "F.Fab")
			(hide yes)
			(effects
				(font
					(size 1 1)
					(thickness 0.15)
				)
			)
		)
		(property "Dielectric" "X5R"
			(at 0 0 270)
			(unlocked yes)
			(layer "F.Fab")
			(hide yes)
			(effects
				(font
					(size 1 1)
					(thickness 0.15)
				)
			)
		)
		(sheetname "/X710 DCDC converters/")
		(sheetfile "DCDC_converters_X710.kicad_sch")
		(attr smd)
		(fp_rect
			(start -0.925 -0.47)
			(end 0.925 0.47)
			(stroke
				(width 0.05)
				(type default)
			)
			(fill no)
			(layer "F.CrtYd")
		)
		(fp_line
			(start -0.494 0.248)
			(end -0.494 -0.25)
			(stroke
				(width 0.15)
				(type solid)
			)
			(layer "F.Fab")
		)
		(fp_line
			(start 0.504 0.248)
			(end -0.494 0.248)
			(stroke
				(width 0.15)
				(type solid)
			)
			(layer "F.Fab")
		)
		(fp_line
			(start -0.494 -0.25)
			(end 0.504 -0.25)
			(stroke
				(width 0.15)
				(type solid)
			)
			(layer "F.Fab")
		)
		(fp_line
			(start 0.504 -0.25)
			(end 0.504 0.248)
			(stroke
				(width 0.15)
				(type solid)
			)
			(layer "F.Fab")
		)
		(fp_text user "License: Apache-2.0"
			(at -0.939 5.799 270)
			(layer "F.Fab")
			(effects
				(font
					(size 0.7 0.7)
					(thickness 0.15)
				)
				(justify left bottom)
			)
		)
		(fp_text user "${REFERENCE}"
			(at -0.939 4.599 270)
			(layer "F.Fab")
			(effects
				(font
					(size 0.7 0.7)
					(thickness 0.15)
				)
				(justify left bottom)
			)
		)
		(fp_text user "Author: Antmicro"
			(at -0.939 3.399 270)
			(layer "F.Fab")
			(effects
				(font
					(size 0.7 0.7)
					(thickness 0.15)
				)
				(justify left bottom)
			)
		)
		(pad "1" smd roundrect
			(at -0.48 0 270)
			(size 0.59 0.64)
			(layers "F.Cu" "F.Mask" "F.Paste")
			(roundrect_rratio 0.25)
			(net 23 "GND")
			(pintype "passive")
		)
		(pad "2" smd roundrect
			(at 0.48 0 270)
			(size 0.59 0.64)
			(layers "F.Cu" "F.Mask" "F.Paste")
			(roundrect_rratio 0.25)
			(net 40 "+5V")
			(pintype "passive")
		)
	)
	(footprint "antmicro-footprints:C_0603_1608Metric_EIA"
		(layer "F.Cu")
		(at 141.704999 99.774999 -90)
		(descr "Capacitor SMD 0603, IPC-7351 Density Level A")
		(tags "Capacitor 0603")
		(property "Reference" "C175"
			(at -9.274999 -35.545001 270)
			(layer "F.SilkS")
			(effects
				(font
					(size 0.7 0.7)
					(thickness 0.15)
				)
			)
		)
		(property "Value" "C_22u_16V_0603"
			(at -1.42757 1.770288 270)
			(layer "F.Fab")
			(effects
				(font
					(size 0.7 0.7)
					(thickness 0.15)
				)
				(justify left bottom)
			)
		)
		(property "Datasheet" "https://product.samsungsem.com/mlcc/CL10A226MO7JZN.do"
			(at 0 0 270)
			(layer "F.Fab")
			(hide yes)
			(effects
				(font
					(size 1.27 1.27)
					(thickness 0.15)
				)
			)
		)
		(property "Description" "SMD Multilayer Ceramic Capacitor"
			(at 0 0 270)
			(layer "F.Fab")
			(hide yes)
			(effects
				(font
					(size 1.27 1.27)
					(thickness 0.15)
				)
			)
		)
		(property "MPN" "CL10A226MO7JZNC"
			(at 0 0 270)
			(unlocked yes)
			(layer "F.Fab")
			(hide yes)
			(effects
				(font
					(size 1 1)
					(thickness 0.15)
				)
			)
		)
		(property "Manufacturer" "Samsung Electro-Mechanics"
			(at 0 0 270)
			(unlocked yes)
			(layer "F.Fab")
			(hide yes)
			(effects
				(font
					(size 1 1)
					(thickness 0.15)
				)
			)
		)
		(property "License" "Apache-2.0"
			(at 0 0 270)
			(unlocked yes)
			(layer "F.Fab")
			(hide yes)
			(effects
				(font
					(size 1 1)
					(thickness 0.15)
				)
			)
		)
		(property "Author" "Antmicro"
			(at 0 0 270)
			(unlocked yes)
			(layer "F.Fab")
			(hide yes)
			(effects
				(font
					(size 1 1)
					(thickness 0.15)
				)
			)
		)
		(property "Val" "22u"
			(at 0 0 270)
			(unlocked yes)
			(layer "F.Fab")
			(hide yes)
			(effects
				(font
					(size 1 1)
					(thickness 0.15)
				)
			)
		)
		(property "Voltage" "16V"
			(at 0 0 270)
			(unlocked yes)
			(layer "F.Fab")
			(hide yes)
			(effects
				(font
					(size 1 1)
					(thickness 0.15)
				)
			)
		)
		(property "Dielectric" ""
			(at 0 0 270)
			(unlocked yes)
			(layer "F.Fab")
			(hide yes)
			(effects
				(font
					(size 1 1)
					(thickness 0.15)
				)
			)
		)
		(sheetname "/X710-AT2 power/")
		(sheetfile "x710-at2-power.kicad_sch")
		(attr smd)
		(fp_line
			(start -0.15 0.55)
			(end 0.15 0.55)
			(stroke
				(width 0.15)
				(type solid)
			)
			(layer "F.SilkS")
		)
		(fp_line
			(start -0.15 -0.55)
			(end 0.15 -0.55)
			(stroke
				(width 0.15)
				(type solid)
			)
			(layer "F.SilkS")
		)
		(fp_rect
			(start -1.25 -0.65)
			(end 1.25 0.65)
			(stroke
				(width 0.05)
				(type solid)
			)
			(fill no)
			(layer "F.CrtYd")
		)
		(fp_rect
			(start -0.8 -0.45)
			(end 0.8 0.45)
			(stroke
				(width 0.15)
				(type solid)
			)
			(fill no)
			(layer "F.Fab")
		)
		(fp_text user "${REFERENCE}"
			(at -1.682 3.895 270)
			(layer "F.Fab")
			(effects
				(font
					(size 0.7 0.7)
					(thickness 0.15)
				)
				(justify left bottom)
			)
		)
		(fp_text user "License: Apache-2.0"
			(at -1.682 5.895 270)
			(layer "F.Fab")
			(effects
				(font
					(size 0.7 0.7)
					(thickness 0.15)
				)
				(justify left bottom)
			)
		)
		(fp_text user "Author: Antmicro"
			(at -1.682 4.894 270)
			(layer "F.Fab")
			(effects
				(font
					(size 0.7 0.7)
					(thickness 0.15)
				)
				(justify left bottom)
			)
		)
		(pad "1" smd roundrect
			(at -0.7 0 270)
			(size 0.8 1.1)
			(layers "F.Cu" "F.Mask" "F.Paste")
			(roundrect_rratio 0.2)
			(net 23 "GND")
			(pintype "passive")
		)
		(pad "2" smd roundrect
			(at 0.7 0 270)
			(size 0.8 1.1)
			(layers "F.Cu" "F.Mask" "F.Paste")
			(roundrect_rratio 0.2)
			(net 6 "DVDD")
			(pintype "passive")
		)
	)
	(footprint "antmicro-footprints:C_0402_1005Metric"
		(layer "F.Cu")
		(at 117.8 121 180)
		(descr "Capacitor SMD 0402")
		(tags "capacitor SMD 0402")
		(property "Reference" "C45"
			(at -0.8 -0.2 180)
			(layer "F.SilkS")
			(effects
				(font
					(size 0.7 0.7)
					(thickness 0.15)
				)
				(justify left bottom)
			)
		)
		(property "Value" "C_220n_0402"
			(at -1.022927 2.155213 180)
			(layer "F.Fab")
			(effects
				(font
					(size 0.7 0.7)
					(thickness 0.15)
				)
				(justify left bottom)
			)
		)
		(property "Datasheet" "https://www.yageo.com/en/Chart/Download/pdf/CC0402KRX5R6BB224"
			(at 0 0 180)
			(layer "F.Fab")
			(hide yes)
			(effects
				(font
					(size 1.27 1.27)
					(thickness 0.15)
				)
			)
		)
		(property "Description" "SMD Multilayer Ceramic Capacitor, 0.22 µF, 10 V, 0402 [1005 Metric], ± 10%, X5R, CC Series"
			(at 0 0 180)
			(layer "F.Fab")
			(hide yes)
			(effects
				(font
					(size 1.27 1.27)
					(thickness 0.15)
				)
			)
		)
		(property "MPN" "CC0402KRX5R6BB224"
			(at 0 0 180)
			(unlocked yes)
			(layer "F.Fab")
			(hide yes)
			(effects
				(font
					(size 1 1)
					(thickness 0.15)
				)
			)
		)
		(property "Manufacturer" "YAGEO"
			(at 0 0 180)
			(unlocked yes)
			(layer "F.Fab")
			(hide yes)
			(effects
				(font
					(size 1 1)
					(thickness 0.15)
				)
			)
		)
		(property "License" "Apache-2.0"
			(at 0 0 180)
			(unlocked yes)
			(layer "F.Fab")
			(hide yes)
			(effects
				(font
					(size 1 1)
					(thickness 0.15)
				)
			)
		)
		(property "Val" "220n"
			(at 0 0 180)
			(unlocked yes)
			(layer "F.Fab")
			(hide yes)
			(effects
				(font
					(size 1 1)
					(thickness 0.15)
				)
			)
		)
		(property "Voltage" ""
			(at 0 0 180)
			(unlocked yes)
			(layer "F.Fab")
			(hide yes)
			(effects
				(font
					(size 1 1)
					(thickness 0.15)
				)
			)
		)
		(property "Dielectric" ""
			(at 0 0 180)
			(unlocked yes)
			(layer "F.Fab")
			(hide yes)
			(effects
				(font
					(size 1 1)
					(thickness 0.15)
				)
			)
		)
		(property "Author" "Antmicro"
			(at 0 0 180)
			(unlocked yes)
			(layer "F.Fab")
			(hide yes)
			(effects
				(font
					(size 1 1)
					(thickness 0.15)
				)
			)
		)
		(sheetname "/TB Controller/")
		(sheetfile "tb.kicad_sch")
		(attr smd)
		(fp_rect
			(start -0.925 -0.47)
			(end 0.925 0.47)
			(stroke
				(width 0.05)
				(type default)
			)
			(fill no)
			(layer "F.CrtYd")
		)
		(fp_line
			(start 0.504 0.248)
			(end -0.494 0.248)
			(stroke
				(width 0.15)
				(type solid)
			)
			(layer "F.Fab")
		)
		(fp_line
			(start 0.504 -0.25)
			(end 0.504 0.248)
			(stroke
				(width 0.15)
				(type solid)
			)
			(layer "F.Fab")
		)
		(fp_line
			(start -0.494 0.248)
			(end -0.494 -0.25)
			(stroke
				(width 0.15)
				(type solid)
			)
			(layer "F.Fab")
		)
		(fp_line
			(start -0.494 -0.25)
			(end 0.504 -0.25)
			(stroke
				(width 0.15)
				(type solid)
			)
			(layer "F.Fab")
		)
		(fp_text user "License: Apache-2.0"
			(at -0.939 5.799 180)
			(layer "F.Fab")
			(effects
				(font
					(size 0.7 0.7)
					(thickness 0.15)
				)
				(justify left bottom)
			)
		)
		(fp_text user "Author: Antmicro"
			(at -0.939 3.399 180)
			(layer "F.Fab")
			(effects
				(font
					(size 0.7 0.7)
					(thickness 0.15)
				)
				(justify left bottom)
			)
		)
		(fp_text user "${REFERENCE}"
			(at -0.939 4.599 180)
			(layer "F.Fab")
			(effects
				(font
					(size 0.7 0.7)
					(thickness 0.15)
				)
				(justify left bottom)
			)
		)
		(pad "1" smd roundrect
			(at -0.48 0 180)
			(size 0.59 0.64)
			(layers "F.Cu" "F.Mask" "F.Paste")
			(roundrect_rratio 0.25)
			(net 325 "/TB Controller/TB_PCIE_TX1_P")
			(pintype "passive")
		)
		(pad "2" smd roundrect
			(at 0.48 0 180)
			(size 0.59 0.64)
			(layers "F.Cu" "F.Mask" "F.Paste")
			(roundrect_rratio 0.25)
			(net 317 "/TB Controller/PCIex4.RX1+")
			(pintype "passive")
		)
	)
	(footprint "antmicro-footprints:C_0805_2012Metric"
		(layer "F.Cu")
		(at 129 140.3)
		(descr "Capacitor SMD 0805")
		(tags "capacitor SMD 0805")
		(property "Reference" "C30"
			(at -1.2 1.8 0)
			(layer "F.SilkS")
			(effects
				(font
					(size 0.7 0.7)
					(thickness 0.15)
				)
				(justify left bottom)
			)
		)
		(property "Value" "C_22u_25V_0805"
			(at -2.055717 1.963152 0)
			(layer "F.Fab")
			(effects
				(font
					(size 0.7 0.7)
					(thickness 0.15)
				)
				(justify left bottom)
			)
		)
		(property "Datasheet" "https://product.samsungsem.com/mlcc/CL21A226MAYNNN.do"
			(at 0 0 0)
			(layer "F.Fab")
			(hide yes)
			(effects
				(font
					(size 1.27 1.27)
					(thickness 0.15)
				)
			)
		)
		(property "Description" "SMT Multilayer Ceramic Capacitor, 22uF, +/-20%, 25V, X5R, 0805 [2012 Metric]"
			(at 0 0 0)
			(layer "F.Fab")
			(hide yes)
			(effects
				(font
					(size 1.27 1.27)
					(thickness 0.15)
				)
			)
		)
		(property "MPN" "CL21A226MAYNNNE"
			(at 0 0 0)
			(unlocked yes)
			(layer "F.Fab")
			(hide yes)
			(effects
				(font
					(size 1 1)
					(thickness 0.15)
				)
			)
		)
		(property "Manufacturer" "Samsung Electro-Mechanics"
			(at 0 0 0)
			(unlocked yes)
			(layer "F.Fab")
			(hide yes)
			(effects
				(font
					(size 1 1)
					(thickness 0.15)
				)
			)
		)
		(property "License" "Apache-2.0"
			(at 0 0 0)
			(unlocked yes)
			(layer "F.Fab")
			(hide yes)
			(effects
				(font
					(size 1 1)
					(thickness 0.15)
				)
			)
		)
		(property "Val" "22u"
			(at 0 0 0)
			(unlocked yes)
			(layer "F.Fab")
			(hide yes)
			(effects
				(font
					(size 1 1)
					(thickness 0.15)
				)
			)
		)
		(property "Voltage" "25V"
			(at 0 0 0)
			(unlocked yes)
			(layer "F.Fab")
			(hide yes)
			(effects
				(font
					(size 1 1)
					(thickness 0.15)
				)
			)
		)
		(property "Dielectric" "X5R"
			(at 0 0 0)
			(unlocked yes)
			(layer "F.Fab")
			(hide yes)
			(effects
				(font
					(size 1 1)
					(thickness 0.15)
				)
			)
		)
		(property "Author" "Antmicro"
			(at 0 0 0)
			(unlocked yes)
			(layer "F.Fab")
			(hide yes)
			(effects
				(font
					(size 1 1)
					(thickness 0.15)
				)
			)
		)
		(property "Public" "False"
			(at 0 0 0)
			(unlocked yes)
			(layer "F.Fab")
			(hide yes)
			(effects
				(font
					(size 1 1)
					(thickness 0.15)
				)
			)
		)
		(sheetname "/PD and TB DC-DC/")
		(sheetfile "PD_and_TB_DC_DC.kicad_sch")
		(attr smd)
		(fp_line
			(start -0.3 -0.7)
			(end 0.3 -0.7)
			(stroke
				(width 0.15)
				(type solid)
			)
			(layer "F.SilkS")
		)
		(fp_line
			(start -0.3 0.7)
			(end 0.3 0.7)
			(stroke
				(width 0.15)
				(type solid)
			)
			(layer "F.SilkS")
		)
		(fp_rect
			(start 1.95 -0.9)
			(end -1.95 0.9)
			(stroke
				(width 0.05)
				(type default)
			)
			(fill no)
			(layer "F.CrtYd")
		)
		(fp_rect
			(start -0.95 -0.675)
			(end 0.95 0.675)
			(stroke
				(width 0.15)
				(type solid)
			)
			(fill no)
			(layer "F.Fab")
		)
		(fp_text user "Author: Antmicro"
			(at -1.9 5.947 0)
			(layer "F.Fab")
			(effects
				(font
					(size 0.7 0.7)
					(thickness 0.15)
				)
				(justify left bottom)
			)
		)
		(fp_text user "License: Apache-2.0"
			(at -1.9 4.947 0)
			(layer "F.Fab")
			(effects
				(font
					(size 0.7 0.7)
					(thickness 0.15)
				)
				(justify left bottom)
			)
		)
		(fp_text user "${REFERENCE}"
			(at -1.9 3.947 0)
			(layer "F.Fab")
			(effects
				(font
					(size 0.7 0.7)
					(thickness 0.15)
				)
				(justify left bottom)
			)
		)
		(pad "1" smd roundrect
			(at -1.1 0)
			(size 1.2 1.3)
			(layers "F.Cu" "F.Mask" "F.Paste")
			(roundrect_rratio 0.25)
			(net 23 "GND")
			(pintype "passive")
		)
		(pad "2" smd roundrect
			(at 1.1 0)
			(size 1.2 1.3)
			(layers "F.Cu" "F.Mask" "F.Paste")
			(roundrect_rratio 0.25)
			(net 182 "VBUS")
			(pintype "passive")
		)
	)
	(footprint "antmicro-footprints:R_0402_1005Metric"
		(layer "F.Cu")
		(at 161 46.3 -90)
		(descr "Resistor SMD 0402")
		(tags "resistor SMD 0402")
		(property "Reference" "R231"
			(at 1.9 -6.3 270)
			(layer "F.SilkS")
			(effects
				(font
					(size 0.7 0.7)
					(thickness 0.15)
				)
				(justify left bottom)
			)
		)
		(property "Value" "R_73k2_0402"
			(at -1.011843 1.772047 270)
			(layer "F.Fab")
			(effects
				(font
					(size 0.7 0.7)
					(thickness 0.15)
				)
				(justify left bottom)
			)
		)
		(property "Datasheet" "https://www.bourns.com/docs/product-datasheets/cr.pdf"
			(at 0 0 270)
			(layer "F.Fab")
			(hide yes)
			(effects
				(font
					(size 1.27 1.27)
					(thickness 0.15)
				)
			)
		)
		(property "Description" "SMD Chip Resistor"
			(at 0 0 270)
			(layer "F.Fab")
			(hide yes)
			(effects
				(font
					(size 1.27 1.27)
					(thickness 0.15)
				)
			)
		)
		(property "MPN" "CR0402-FX-7322GLF"
			(at 0 0 270)
			(unlocked yes)
			(layer "F.Fab")
			(hide yes)
			(effects
				(font
					(size 1 1)
					(thickness 0.15)
				)
			)
		)
		(property "Manufacturer" "Bourns"
			(at 0 0 270)
			(unlocked yes)
			(layer "F.Fab")
			(hide yes)
			(effects
				(font
					(size 1 1)
					(thickness 0.15)
				)
			)
		)
		(property "License" "Apache-2.0"
			(at 0 0 270)
			(unlocked yes)
			(layer "F.Fab")
			(hide yes)
			(effects
				(font
					(size 1 1)
					(thickness 0.15)
				)
			)
		)
		(property "Author" "Antmicro"
			(at 0 0 270)
			(unlocked yes)
			(layer "F.Fab")
			(hide yes)
			(effects
				(font
					(size 1 1)
					(thickness 0.15)
				)
			)
		)
		(property "Val" "73k2"
			(at 0 0 270)
			(unlocked yes)
			(layer "F.Fab")
			(hide yes)
			(effects
				(font
					(size 1 1)
					(thickness 0.15)
				)
			)
		)
		(property "Tolerance" "1%"
			(at 0 0 270)
			(unlocked yes)
			(layer "F.Fab")
			(hide yes)
			(effects
				(font
					(size 1 1)
					(thickness 0.15)
				)
			)
		)
		(sheetname "/Power input/")
		(sheetfile "power_input.kicad_sch")
		(attr smd)
		(fp_rect
			(start -0.925 -0.47)
			(end 0.925 0.47)
			(stroke
				(width 0.05)
				(type default)
			)
			(fill no)
			(layer "F.CrtYd")
		)
		(fp_rect
			(start -0.5 -0.25)
			(end 0.5 0.25)
			(stroke
				(width 0.15)
				(type solid)
			)
			(fill no)
			(layer "F.Fab")
		)
		(fp_text user "${REFERENCE}"
			(at -0.95 3.168 270)
			(layer "F.Fab")
			(effects
				(font
					(size 0.7 0.7)
					(thickness 0.15)
				)
				(justify left bottom)
			)
		)
		(fp_text user "License: Apache-2.0"
			(at -0.95 5.169 270)
			(layer "F.Fab")
			(effects
				(font
					(size 0.7 0.7)
					(thickness 0.15)
				)
				(justify left bottom)
			)
		)
		(fp_text user "Author: Antmicro"
			(at -0.95 4.169 270)
			(layer "F.Fab")
			(effects
				(font
					(size 0.7 0.7)
					(thickness 0.15)
				)
				(justify left bottom)
			)
		)
		(pad "1" smd roundrect
			(at -0.48 0 270)
			(size 0.59 0.64)
			(layers "F.Cu" "F.Mask" "F.Paste")
			(roundrect_rratio 0.25)
			(net 391 "/Power input/5V_FB")
			(pintype "passive")
		)
		(pad "2" smd roundrect
			(at 0.48 0 270)
			(size 0.59 0.64)
			(layers "F.Cu" "F.Mask" "F.Paste")
			(roundrect_rratio 0.25)
			(net 349 "/Power input/5V_OUT")
			(pintype "passive")
		)
	)
	(footprint "antmicro-footprints:C_0402_1005Metric"
		(layer "F.Cu")
		(at 159.249996 111.15 180)
		(descr "Capacitor SMD 0402")
		(tags "capacitor SMD 0402")
		(property "Reference" "C132"
			(at -12.950004 -17.25 180)
			(layer "F.SilkS")
			(effects
				(font
					(size 0.7 0.7)
					(thickness 0.15)
				)
			)
		)
		(property "Value" "C_33p_0402"
			(at -1.022927 2.155213 180)
			(layer "F.Fab")
			(effects
				(font
					(size 0.7 0.7)
					(thickness 0.15)
				)
				(justify left bottom)
			)
		)
		(property "Datasheet" "https://spicat.kyocera-avx.com/product/mlcc/chartview/04025A330FAT2A/"
			(at 0 0 180)
			(layer "F.Fab")
			(hide yes)
			(effects
				(font
					(size 1.27 1.27)
					(thickness 0.15)
				)
			)
		)
		(property "Description" "SMD Multilayer Ceramic Capacitor, 33 pF, 50 V, 0402 [1005 Metric], ± 5%, C0G / NP0, MC"
			(at 0 0 180)
			(layer "F.Fab")
			(hide yes)
			(effects
				(font
					(size 1.27 1.27)
					(thickness 0.15)
				)
			)
		)
		(property "MPN" "04025A330FAT2A"
			(at 0 0 180)
			(unlocked yes)
			(layer "F.Fab")
			(hide yes)
			(effects
				(font
					(size 1 1)
					(thickness 0.15)
				)
			)
		)
		(property "Manufacturer" "KYOCERA AVX"
			(at 0 0 180)
			(unlocked yes)
			(layer "F.Fab")
			(hide yes)
			(effects
				(font
					(size 1 1)
					(thickness 0.15)
				)
			)
		)
		(property "License" "Apache-2.0"
			(at 0 0 180)
			(unlocked yes)
			(layer "F.Fab")
			(hide yes)
			(effects
				(font
					(size 1 1)
					(thickness 0.15)
				)
			)
		)
		(property "Author" "Antmicro"
			(at 0 0 180)
			(unlocked yes)
			(layer "F.Fab")
			(hide yes)
			(effects
				(font
					(size 1 1)
					(thickness 0.15)
				)
			)
		)
		(property "Val" "33p"
			(at 0 0 180)
			(unlocked yes)
			(layer "F.Fab")
			(hide yes)
			(effects
				(font
					(size 1 1)
					(thickness 0.15)
				)
			)
		)
		(property "Voltage" ""
			(at 0 0 180)
			(unlocked yes)
			(layer "F.Fab")
			(hide yes)
			(effects
				(font
					(size 1 1)
					(thickness 0.15)
				)
			)
		)
		(property "Dielectric" ""
			(at 0 0 180)
			(unlocked yes)
			(layer "F.Fab")
			(hide yes)
			(effects
				(font
					(size 1 1)
					(thickness 0.15)
				)
			)
		)
		(sheetname "/X710 DCDC converters/")
		(sheetfile "DCDC_converters_X710.kicad_sch")
		(attr smd dnp)
		(fp_rect
			(start -0.925 -0.47)
			(end 0.925 0.47)
			(stroke
				(width 0.05)
				(type default)
			)
			(fill no)
			(layer "F.CrtYd")
		)
		(fp_line
			(start 0.504 0.248)
			(end -0.494 0.248)
			(stroke
				(width 0.15)
				(type solid)
			)
			(layer "F.Fab")
		)
		(fp_line
			(start 0.504 -0.25)
			(end 0.504 0.248)
			(stroke
				(width 0.15)
				(type solid)
			)
			(layer "F.Fab")
		)
		(fp_line
			(start -0.494 0.248)
			(end -0.494 -0.25)
			(stroke
				(width 0.15)
				(type solid)
			)
			(layer "F.Fab")
		)
		(fp_line
			(start -0.494 -0.25)
			(end 0.504 -0.25)
			(stroke
				(width 0.15)
				(type solid)
			)
			(layer "F.Fab")
		)
		(fp_text user "License: Apache-2.0"
			(at -0.939 5.799 180)
			(layer "F.Fab")
			(effects
				(font
					(size 0.7 0.7)
					(thickness 0.15)
				)
				(justify left bottom)
			)
		)
		(fp_text user "${REFERENCE}"
			(at -0.939 4.599 180)
			(layer "F.Fab")
			(effects
				(font
					(size 0.7 0.7)
					(thickness 0.15)
				)
				(justify left bottom)
			)
		)
		(fp_text user "Author: Antmicro"
			(at -0.939 3.399 180)
			(layer "F.Fab")
			(effects
				(font
					(size 0.7 0.7)
					(thickness 0.15)
				)
				(justify left bottom)
			)
		)
		(pad "1" smd roundrect
			(at -0.48 0 180)
			(size 0.59 0.64)
			(layers "F.Cu" "F.Mask" "F.Paste")
			(roundrect_rratio 0.25)
			(net 340 "/X710 DCDC converters/1V0_FB")
			(pintype "passive")
		)
		(pad "2" smd roundrect
			(at 0.48 0 180)
			(size 0.59 0.64)
			(layers "F.Cu" "F.Mask" "F.Paste")
			(roundrect_rratio 0.25)
			(net 339 "/X710 DCDC converters/+1V0_OUT")
			(pintype "passive")
		)
	)
	(footprint "antmicro-footprints:C_0603_1608Metric"
		(layer "F.Cu")
		(at 150.305 66.024999 90)
		(descr "Capacitor SMD 0603")
		(tags "capacitor 0603")
		(property "Reference" "C209"
			(at 12.424999 20.045 90)
			(layer "F.SilkS")
			(effects
				(font
					(size 0.65 0.65)
					(thickness 0.1625)
					(bold yes)
				)
			)
		)
		(property "Value" "C_10u_10V_X7R_0603"
			(at -1.42757 1.770288 90)
			(layer "F.Fab")
			(effects
				(font
					(size 0.7 0.7)
					(thickness 0.15)
				)
				(justify left bottom)
			)
		)
		(property "Datasheet" "https://www.murata.com/products/productdetail?partno=GRM188Z71A106KA73%23"
			(at 0 0 90)
			(layer "F.Fab")
			(hide yes)
			(effects
				(font
					(size 1.27 1.27)
					(thickness 0.15)
				)
			)
		)
		(property "Description" "SMD Multilayer Ceramic Capacitor,  10µF, 10V, 0603, ±10%, X7R"
			(at 0 0 90)
			(layer "F.Fab")
			(hide yes)
			(effects
				(font
					(size 1.27 1.27)
					(thickness 0.15)
				)
			)
		)
		(property "MPN" "GRM188Z71A106KA73D"
			(at 0 0 90)
			(unlocked yes)
			(layer "F.Fab")
			(hide yes)
			(effects
				(font
					(size 1 1)
					(thickness 0.15)
				)
			)
		)
		(property "Val" "10u"
			(at 0 0 90)
			(unlocked yes)
			(layer "F.Fab")
			(hide yes)
			(effects
				(font
					(size 1 1)
					(thickness 0.15)
				)
			)
		)
		(property "Voltage" "10V"
			(at 0 0 90)
			(unlocked yes)
			(layer "F.Fab")
			(hide yes)
			(effects
				(font
					(size 1 1)
					(thickness 0.15)
				)
			)
		)
		(property "Dielectric" "X7R"
			(at 0 0 90)
			(unlocked yes)
			(layer "F.Fab")
			(hide yes)
			(effects
				(font
					(size 1 1)
					(thickness 0.15)
				)
			)
		)
		(property "Manufacturer" "Murata"
			(at 0 0 90)
			(unlocked yes)
			(layer "F.Fab")
			(hide yes)
			(effects
				(font
					(size 1 1)
					(thickness 0.15)
				)
			)
		)
		(property "License" "Apache-2.0"
			(at 0 0 90)
			(unlocked yes)
			(layer "F.Fab")
			(hide yes)
			(effects
				(font
					(size 1 1)
					(thickness 0.15)
				)
			)
		)
		(property "Author" "Antmicro"
			(at 0 0 90)
			(unlocked yes)
			(layer "F.Fab")
			(hide yes)
			(effects
				(font
					(size 1 1)
					(thickness 0.15)
				)
			)
		)
		(sheetname "/X710-AT2 power/")
		(sheetfile "x710-at2-power.kicad_sch")
		(attr smd)
		(fp_line
			(start -0.15 -0.4)
			(end 0.15 -0.4)
			(stroke
				(width 0.15)
				(type solid)
			)
			(layer "F.SilkS")
		)
		(fp_line
			(start -0.15 0.4)
			(end 0.15 0.4)
			(stroke
				(width 0.15)
				(type solid)
			)
			(layer "F.SilkS")
		)
		(fp_rect
			(start -1.25 -0.65)
			(end 1.25 0.65)
			(stroke
				(width 0.05)
				(type solid)
			)
			(fill no)
			(layer "F.CrtYd")
		)
		(fp_rect
			(start -0.8 -0.4)
			(end 0.8 0.4)
			(stroke
				(width 0.15)
				(type solid)
			)
			(fill no)
			(layer "F.Fab")
		)
		(fp_text user "License: Apache-2.0"
			(at -1.682 5.895 90)
			(layer "F.Fab")
			(effects
				(font
					(size 0.7 0.7)
					(thickness 0.15)
				)
				(justify left bottom)
			)
		)
		(fp_text user "${REFERENCE}"
			(at -1.682 3.895 90)
			(layer "F.Fab")
			(effects
				(font
					(size 0.7 0.7)
					(thickness 0.15)
				)
				(justify left bottom)
			)
		)
		(fp_text user "Author: Antmicro"
			(at -1.682 4.894 90)
			(layer "F.Fab")
			(effects
				(font
					(size 0.7 0.7)
					(thickness 0.15)
				)
				(justify left bottom)
			)
		)
		(pad "1" smd roundrect
			(at -0.7 0 90)
			(size 0.8 1)
			(layers "F.Cu" "F.Mask" "F.Paste")
			(roundrect_rratio 0.2)
			(net 23 "GND")
			(pintype "passive")
		)
		(pad "2" smd roundrect
			(at 0.7 0 90)
			(size 0.8 1)
			(layers "F.Cu" "F.Mask" "F.Paste")
			(roundrect_rratio 0.2)
			(net 1 "VCCA")
			(pintype "passive")
		)
	)
	(footprint "antmicro-footprints:R_0603_1608Metric"
		(layer "F.Cu")
		(at 158.2 103.05 90)
		(descr "Resistor SMD 0603")
		(tags "resistor SMD 0603")
		(property "Reference" "R111"
			(at -17.649996 13.250002 90)
			(layer "F.SilkS")
			(effects
				(font
					(size 0.7 0.7)
					(thickness 0.15)
				)
			)
		)
		(property "Value" "R_0R_22.4A_0603"
			(at 0 1.6 90)
			(layer "F.Fab")
			(effects
				(font
					(size 0.7 0.7)
					(thickness 0.15)
				)
				(justify left bottom)
			)
		)
		(property "Datasheet" "https://fscdn.rohm.com/en/products/databook/datasheet/passive/resistor/chip_resistor/pmr-jpw-e.pdf"
			(at 0 0 90)
			(layer "F.Fab")
			(hide yes)
			(effects
				(font
					(size 1.27 1.27)
					(thickness 0.15)
				)
			)
		)
		(property "Description" "SMD Chip Resistor"
			(at 0 0 90)
			(layer "F.Fab")
			(hide yes)
			(effects
				(font
					(size 1.27 1.27)
					(thickness 0.15)
				)
			)
		)
		(property "MPN" "PMR03EZPJ000"
			(at 0 0 90)
			(unlocked yes)
			(layer "F.Fab")
			(hide yes)
			(effects
				(font
					(size 1 1)
					(thickness 0.15)
				)
			)
		)
		(property "Manufacturer" "ROHM Semiconductor"
			(at 0 0 90)
			(unlocked yes)
			(layer "F.Fab")
			(hide yes)
			(effects
				(font
					(size 1 1)
					(thickness 0.15)
				)
			)
		)
		(property "Val" "0R"
			(at 0 0 90)
			(unlocked yes)
			(layer "F.Fab")
			(hide yes)
			(effects
				(font
					(size 1 1)
					(thickness 0.15)
				)
			)
		)
		(property "Max. Curr." "22.4A"
			(at 0 0 90)
			(unlocked yes)
			(layer "F.Fab")
			(hide yes)
			(effects
				(font
					(size 1 1)
					(thickness 0.15)
				)
			)
		)
		(property "Author" "Antmicro"
			(at 0 0 90)
			(unlocked yes)
			(layer "F.Fab")
			(hide yes)
			(effects
				(font
					(size 1 1)
					(thickness 0.15)
				)
			)
		)
		(property "License" "Apache-2.0"
			(at 0 0 90)
			(unlocked yes)
			(layer "F.Fab")
			(hide yes)
			(effects
				(font
					(size 1 1)
					(thickness 0.15)
				)
			)
		)
		(property "Tolerance" "template_tolerance"
			(at 0 0 90)
			(unlocked yes)
			(layer "F.Fab")
			(hide yes)
			(effects
				(font
					(size 1 1)
					(thickness 0.15)
				)
			)
		)
		(sheetname "/X710 DCDC converters/")
		(sheetfile "DCDC_converters_X710.kicad_sch")
		(attr smd)
		(fp_line
			(start -0.15 -0.4)
			(end 0.15 -0.4)
			(stroke
				(width 0.15)
				(type solid)
			)
			(layer "F.SilkS")
		)
		(fp_line
			(start -0.15 0.4)
			(end 0.15 0.4)
			(stroke
				(width 0.15)
				(type solid)
			)
			(layer "F.SilkS")
		)
		(fp_rect
			(start -1.25 -0.65)
			(end 1.25 0.65)
			(stroke
				(width 0.05)
				(type solid)
			)
			(fill no)
			(layer "F.CrtYd")
		)
		(fp_rect
			(start -0.8 -0.4)
			(end 0.8 0.4)
			(stroke
				(width 0.15)
				(type solid)
			)
			(fill no)
			(layer "F.Fab")
		)
		(fp_text user "License: Apache-2.0"
			(at -1.25 5.9 90)
			(layer "F.Fab")
			(effects
				(font
					(size 0.7 0.7)
					(thickness 0.15)
				)
				(justify left bottom)
			)
		)
		(fp_text user "${REFERENCE}"
			(at -1.25 3.898 90)
			(layer "F.Fab")
			(effects
				(font
					(size 0.7 0.7)
					(thickness 0.15)
				)
				(justify left bottom)
			)
		)
		(fp_text user "Author: Antmicro"
			(at -1.25 4.9 90)
			(layer "F.Fab")
			(effects
				(font
					(size 0.7 0.7)
					(thickness 0.15)
				)
				(justify left bottom)
			)
		)
		(pad "1" smd roundrect
			(at -0.7 0 90)
			(size 0.8 1)
			(layers "F.Cu" "F.Mask" "F.Paste")
			(roundrect_rratio 0.2)
			(net 339 "/X710 DCDC converters/+1V0_OUT")
			(pintype "passive")
		)
		(pad "2" smd roundrect
			(at 0.7 0 90)
			(size 0.8 1)
			(layers "F.Cu" "F.Mask" "F.Paste")
			(roundrect_rratio 0.2)
			(net 136 "+1V0")
			(pintype "passive")
		)
	)
	(footprint "antmicro-footprints:R_0402_1005Metric"
		(layer "F.Cu")
		(at 116.4 104.1)
		(descr "Resistor SMD 0402")
		(tags "resistor SMD 0402")
		(property "Reference" "R20"
			(at 0 -8.1 0)
			(layer "F.SilkS")
			(effects
				(font
					(size 0.7 0.7)
					(thickness 0.15)
				)
			)
		)
		(property "Value" "R_100k_0402"
			(at -1.011843 1.772047 0)
			(layer "F.Fab")
			(effects
				(font
					(size 0.7 0.7)
					(thickness 0.15)
				)
				(justify left bottom)
			)
		)
		(property "Datasheet" "https://www.bourns.com/docs/product-datasheets/cr.pdf"
			(at 0 0 0)
			(layer "F.Fab")
			(hide yes)
			(effects
				(font
					(size 1.27 1.27)
					(thickness 0.15)
				)
			)
		)
		(property "Description" "SMD Chip Resistor, 100 kohm, ± 1%, 62.5 mW, 0402 [1005 Metric], Thick Film, General Purpose"
			(at 0 0 0)
			(layer "F.Fab")
			(hide yes)
			(effects
				(font
					(size 1.27 1.27)
					(thickness 0.15)
				)
			)
		)
		(property "MPN" "CR0402-FX-1003GLF"
			(at 0 0 0)
			(unlocked yes)
			(layer "F.Fab")
			(hide yes)
			(effects
				(font
					(size 1 1)
					(thickness 0.15)
				)
			)
		)
		(property "Manufacturer" "Bourns"
			(at 0 0 0)
			(unlocked yes)
			(layer "F.Fab")
			(hide yes)
			(effects
				(font
					(size 1 1)
					(thickness 0.15)
				)
			)
		)
		(property "License" "Apache-2.0"
			(at 0 0 0)
			(unlocked yes)
			(layer "F.Fab")
			(hide yes)
			(effects
				(font
					(size 1 1)
					(thickness 0.15)
				)
			)
		)
		(property "Val" "100k"
			(at 0 0 0)
			(unlocked yes)
			(layer "F.Fab")
			(hide yes)
			(effects
				(font
					(size 1 1)
					(thickness 0.15)
				)
			)
		)
		(property "Tolerance" "1%"
			(at 0 0 0)
			(unlocked yes)
			(layer "F.Fab")
			(hide yes)
			(effects
				(font
					(size 1 1)
					(thickness 0.15)
				)
			)
		)
		(property "Author" "Antmicro"
			(at 0 0 0)
			(unlocked yes)
			(layer "F.Fab")
			(hide yes)
			(effects
				(font
					(size 1 1)
					(thickness 0.15)
				)
			)
		)
		(sheetname "/PD and TB DC-DC/")
		(sheetfile "PD_and_TB_DC_DC.kicad_sch")
		(attr smd)
		(fp_rect
			(start -0.925 -0.47)
			(end 0.925 0.47)
			(stroke
				(width 0.05)
				(type default)
			)
			(fill no)
			(layer "F.CrtYd")
		)
		(fp_rect
			(start -0.5 -0.25)
			(end 0.5 0.25)
			(stroke
				(width 0.15)
				(type solid)
			)
			(fill no)
			(layer "F.Fab")
		)
		(fp_text user "License: Apache-2.0"
			(at -0.95 5.169 0)
			(layer "F.Fab")
			(effects
				(font
					(size 0.7 0.7)
					(thickness 0.15)
				)
				(justify left bottom)
			)
		)
		(fp_text user "${REFERENCE}"
			(at -0.95 3.168 0)
			(layer "F.Fab")
			(effects
				(font
					(size 0.7 0.7)
					(thickness 0.15)
				)
				(justify left bottom)
			)
		)
		(fp_text user "Author: Antmicro"
			(at -0.95 4.169 0)
			(layer "F.Fab")
			(effects
				(font
					(size 0.7 0.7)
					(thickness 0.15)
				)
				(justify left bottom)
			)
		)
		(pad "1" smd roundrect
			(at -0.48 0)
			(size 0.59 0.64)
			(layers "F.Cu" "F.Mask" "F.Paste")
			(roundrect_rratio 0.25)
			(net 17 "Net-(U2-PG)")
			(pintype "passive")
		)
		(pad "2" smd roundrect
			(at 0.48 0)
			(size 0.59 0.64)
			(layers "F.Cu" "F.Mask" "F.Paste")
			(roundrect_rratio 0.25)
			(net 303 "/PD and TB DC-DC/SMPS_LDO")
			(pintype "passive")
		)
	)
	(footprint "antmicro-footprints:LED_0603_1608Metric_G"
		(layer "F.Cu")
		(at 183.2 76)
		(descr "LED SMD 0603 Green")
		(tags "LED SMD 0603 Green")
		(property "Reference" "D10"
			(at -1.2 5.75 0)
			(layer "F.SilkS")
			(effects
				(font
					(size 0.7 0.7)
					(thickness 0.15)
				)
				(justify left bottom)
			)
		)
		(property "Value" "LED_G_0603_LG_L29K-G2J1-24-Z"
			(at -0.001 1.599 0)
			(layer "F.Fab")
			(effects
				(font
					(size 0.7 0.7)
					(thickness 0.15)
				)
				(justify left bottom)
			)
		)
		(property "Datasheet" "https://look.ams-osram.com/m/19ee86b3ae0ee95b/original/LG-L29K.pdf"
			(at 0 0 0)
			(layer "F.Fab")
			(hide yes)
			(effects
				(font
					(size 1.27 1.27)
					(thickness 0.15)
				)
			)
		)
		(property "Description" "LED, Green, SMD, 0603, 20 mA, 1.7 V, 570 nm"
			(at 0 0 0)
			(layer "F.Fab")
			(hide yes)
			(effects
				(font
					(size 1.27 1.27)
					(thickness 0.15)
				)
			)
		)
		(property "MPN" "LG L29K-G2J1-24-Z"
			(at 0 0 0)
			(unlocked yes)
			(layer "F.Fab")
			(hide yes)
			(effects
				(font
					(size 1 1)
					(thickness 0.15)
				)
			)
		)
		(property "Manufacturer" "OSRAM"
			(at 0 0 0)
			(unlocked yes)
			(layer "F.Fab")
			(hide yes)
			(effects
				(font
					(size 1 1)
					(thickness 0.15)
				)
			)
		)
		(property "Color" "Green"
			(at 0 0 0)
			(unlocked yes)
			(layer "F.Fab")
			(hide yes)
			(effects
				(font
					(size 1 1)
					(thickness 0.15)
				)
			)
		)
		(property "Author" "Antmicro"
			(at 0 0 0)
			(unlocked yes)
			(layer "F.Fab")
			(hide yes)
			(effects
				(font
					(size 1 1)
					(thickness 0.15)
				)
			)
		)
		(property "License" "Apache-2.0"
			(at 0 0 0)
			(unlocked yes)
			(layer "F.Fab")
			(hide yes)
			(effects
				(font
					(size 1 1)
					(thickness 0.15)
				)
			)
		)
		(sheetname "/X710 DCDC converters/")
		(sheetfile "DCDC_converters_X710.kicad_sch")
		(attr smd)
		(fp_line
			(start -1.18 -0.319)
			(end -1.18 0.321)
			(stroke
				(width 0.15)
				(type solid)
			)
			(layer "F.SilkS")
		)
		(fp_line
			(start -0.094672 0.001008)
			(end -0.24 0.001008)
			(stroke
				(width 0.1)
				(type solid)
			)
			(layer "F.SilkS")
		)
		(fp_line
			(start -0.094672 0.001008)
			(end 0.105328 -0.198992)
			(stroke
				(width 0.1)
				(type solid)
			)
			(layer "F.SilkS")
		)
		(fp_line
			(start -0.094672 0.201008)
			(end -0.094672 -0.198992)
			(stroke
				(width 0.1)
				(type solid)
			)
			(layer "F.SilkS")
		)
		(fp_line
			(start 0.105328 0.001008)
			(end 0.24 0.001)
			(stroke
				(width 0.1)
				(type solid)
			)
			(layer "F.SilkS")
		)
		(fp_line
			(start 0.105328 0.201008)
			(end -0.094672 0.001008)
			(stroke
				(width 0.1)
				(type solid)
			)
			(layer "F.SilkS")
		)
		(fp_line
			(start 0.105328 0.201008)
			(end 0.105328 -0.198992)
			(stroke
				(width 0.1)
				(type solid)
			)
			(layer "F.SilkS")
		)
		(fp_line
			(start 0.22 -0.35)
			(end -0.22 -0.35)
			(stroke
				(width 0.15)
				(type solid)
			)
			(layer "F.SilkS")
		)
		(fp_line
			(start 0.22 0.35)
			(end -0.22 0.35)
			(stroke
				(width 0.15)
				(type solid)
			)
			(layer "F.SilkS")
		)
		(fp_rect
			(start 1.25 0.65)
			(end -1.25 -0.65)
			(stroke
				(width 0.05)
				(type solid)
			)
			(fill no)
			(layer "F.CrtYd")
		)
		(fp_line
			(start -0.199 -0.202)
			(end -0.199 0.1)
			(stroke
				(width 0.15)
				(type solid)
			)
			(layer "F.Fab")
		)
		(fp_line
			(start -0.199 0)
			(end -0.597 0)
			(stroke
				(width 0.15)
				(type solid)
			)
			(layer "F.Fab")
		)
		(fp_line
			(start -0.199 0.2)
			(end -0.199 0.1)
			(stroke
				(width 0.15)
				(type solid)
			)
			(layer "F.Fab")
		)
		(fp_line
			(start -0.101 0)
			(end 0.201 0.2)
			(stroke
				(width 0.15)
				(type solid)
			)
			(layer "F.Fab")
		)
		(fp_line
			(start 0.201 -0.202)
			(end -0.101 0)
			(stroke
				(width 0.15)
				(type solid)
			)
			(layer "F.Fab")
		)
		(fp_line
			(start 0.201 0)
			(end 0.201 -0.202)
			(stroke
				(width 0.15)
				(type solid)
			)
			(layer "F.Fab")
		)
		(fp_line
			(start 0.201 0.2)
			(end 0.201 0)
			(stroke
				(width 0.15)
				(type solid)
			)
			(layer "F.Fab")
		)
		(fp_line
			(start 0.599 0)
			(end 0.201 0)
			(stroke
				(width 0.15)
				(type solid)
			)
			(layer "F.Fab")
		)
		(fp_rect
			(start 0.848 0.4)
			(end -0.85 -0.402)
			(stroke
				(width 0.15)
				(type solid)
			)
			(fill no)
			(layer "F.Fab")
		)
		(fp_text user "${REFERENCE}"
			(at -1.4224 5.999 0)
			(layer "F.Fab")
			(effects
				(font
					(size 0.7 0.7)
					(thickness 0.15)
				)
				(justify left bottom)
			)
		)
		(fp_text user "License: Apache-2.0"
			(at -1.4224 3.599 0)
			(layer "F.Fab")
			(effects
				(font
					(size 0.7 0.7)
					(thickness 0.15)
				)
				(justify left bottom)
			)
		)
		(fp_text user "Author: Antmicro"
			(at -1.4224 4.799 0)
			(layer "F.Fab")
			(effects
				(font
					(size 0.7 0.7)
					(thickness 0.15)
				)
				(justify left bottom)
			)
		)
		(pad "1" smd roundrect
			(at -0.7 0 180)
			(size 0.8 1)
			(layers "F.Cu" "F.Mask" "F.Paste")
			(roundrect_rratio 0.2)
			(net 417 "Net-(D10-C)")
			(pinfunction "C")
			(pintype "passive")
		)
		(pad "2" smd roundrect
			(at 0.7 0 180)
			(size 0.8 1)
			(layers "F.Cu" "F.Mask" "F.Paste")
			(roundrect_rratio 0.2)
			(net 334 "/X710 DCDC converters/+3V3_OUT")
			(pinfunction "A")
			(pintype "passive")
		)
	)
	(footprint "antmicro-footprints:R_0402_1005Metric"
		(layer "F.Cu")
		(at 143.849998 112.150002)
		(descr "Resistor SMD 0402")
		(tags "resistor SMD 0402")
		(property "Reference" "R107"
			(at 15.349999 17.25 0)
			(layer "F.SilkS")
			(effects
				(font
					(size 0.7 0.7)
					(thickness 0.15)
				)
			)
		)
		(property "Value" "R_30k_0402"
			(at -1.011843 1.772047 0)
			(layer "F.Fab")
			(effects
				(font
					(size 0.7 0.7)
					(thickness 0.15)
				)
				(justify left bottom)
			)
		)
		(property "Datasheet" "https://www.bourns.com/docs/product-datasheets/cr.pdf"
			(at 0 0 0)
			(layer "F.Fab")
			(hide yes)
			(effects
				(font
					(size 1.27 1.27)
					(thickness 0.15)
				)
			)
		)
		(property "Description" "SMD Chip Resistor, 30 kohm, ± 1%, 63 mW, 0402 [1005 Metric], Thick Film, General Purpose"
			(at 0 0 0)
			(layer "F.Fab")
			(hide yes)
			(effects
				(font
					(size 1.27 1.27)
					(thickness 0.15)
				)
			)
		)
		(property "MPN" "CR0402-FX-3002GLF"
			(at 0 0 0)
			(unlocked yes)
			(layer "F.Fab")
			(hide yes)
			(effects
				(font
					(size 1 1)
					(thickness 0.15)
				)
			)
		)
		(property "Manufacturer" "Bourns"
			(at 0 0 0)
			(unlocked yes)
			(layer "F.Fab")
			(hide yes)
			(effects
				(font
					(size 1 1)
					(thickness 0.15)
				)
			)
		)
		(property "License" "Apache-2.0"
			(at 0 0 0)
			(unlocked yes)
			(layer "F.Fab")
			(hide yes)
			(effects
				(font
					(size 1 1)
					(thickness 0.15)
				)
			)
		)
		(property "Author" "Antmicro"
			(at 0 0 0)
			(unlocked yes)
			(layer "F.Fab")
			(hide yes)
			(effects
				(font
					(size 1 1)
					(thickness 0.15)
				)
			)
		)
		(property "Val" "30k"
			(at 0 0 0)
			(unlocked yes)
			(layer "F.Fab")
			(hide yes)
			(effects
				(font
					(size 1 1)
					(thickness 0.15)
				)
			)
		)
		(property "Tolerance" "1%"
			(at 0 0 0)
			(unlocked yes)
			(layer "F.Fab")
			(hide yes)
			(effects
				(font
					(size 1 1)
					(thickness 0.15)
				)
			)
		)
		(sheetname "/X710 DCDC converters/")
		(sheetfile "DCDC_converters_X710.kicad_sch")
		(attr smd)
		(fp_rect
			(start -0.925 -0.47)
			(end 0.925 0.47)
			(stroke
				(width 0.05)
				(type default)
			)
			(fill no)
			(layer "F.CrtYd")
		)
		(fp_rect
			(start -0.5 -0.25)
			(end 0.5 0.25)
			(stroke
				(width 0.15)
				(type solid)
			)
			(fill no)
			(layer "F.Fab")
		)
		(fp_text user "License: Apache-2.0"
			(at -0.95 5.169 0)
			(layer "F.Fab")
			(effects
				(font
					(size 0.7 0.7)
					(thickness 0.15)
				)
				(justify left bottom)
			)
		)
		(fp_text user "${REFERENCE}"
			(at -0.95 3.168 0)
			(layer "F.Fab")
			(effects
				(font
					(size 0.7 0.7)
					(thickness 0.15)
				)
				(justify left bottom)
			)
		)
		(fp_text user "Author: Antmicro"
			(at -0.95 4.169 0)
			(layer "F.Fab")
			(effects
				(font
					(size 0.7 0.7)
					(thickness 0.15)
				)
				(justify left bottom)
			)
		)
		(pad "1" smd roundrect
			(at -0.48 0)
			(size 0.59 0.64)
			(layers "F.Cu" "F.Mask" "F.Paste")
			(roundrect_rratio 0.25)
			(net 23 "GND")
			(pintype "passive")
		)
		(pad "2" smd roundrect
			(at 0.48 0)
			(size 0.59 0.64)
			(layers "F.Cu" "F.Mask" "F.Paste")
			(roundrect_rratio 0.25)
			(net 342 "/X710 DCDC converters/DVDD_FB")
			(pintype "passive")
		)
	)
	(footprint "antmicro-footprints:C_0402_1005Metric"
		(layer "F.Cu")
		(at 132.8 140.4)
		(descr "Capacitor SMD 0402")
		(tags "capacitor SMD 0402")
		(property "Reference" "C28"
			(at 1 0.4 0)
			(layer "F.SilkS")
			(effects
				(font
					(size 0.7 0.7)
					(thickness 0.15)
				)
				(justify left bottom)
			)
		)
		(property "Value" "C_1u_25V_0402"
			(at -1.022927 2.155213 0)
			(layer "F.Fab")
			(effects
				(font
					(size 0.7 0.7)
					(thickness 0.15)
				)
				(justify left bottom)
			)
		)
		(property "Datasheet" "https://www.murata.com/products/productdetail?partno=GRM155R61E105KE11%23"
			(at 0 0 0)
			(layer "F.Fab")
			(hide yes)
			(effects
				(font
					(size 1.27 1.27)
					(thickness 0.15)
				)
			)
		)
		(property "Description" "SMD Multilayer Ceramic Capacitor, 1 µF, 25 V, 0402 [1005 Metric], ± 10%, X5R, GRM Series"
			(at 0 0 0)
			(layer "F.Fab")
			(hide yes)
			(effects
				(font
					(size 1.27 1.27)
					(thickness 0.15)
				)
			)
		)
		(property "MPN" "GRM155R61E105KE11J"
			(at 0 0 0)
			(unlocked yes)
			(layer "F.Fab")
			(hide yes)
			(effects
				(font
					(size 1 1)
					(thickness 0.15)
				)
			)
		)
		(property "Manufacturer" "Murata"
			(at 0 0 0)
			(unlocked yes)
			(layer "F.Fab")
			(hide yes)
			(effects
				(font
					(size 1 1)
					(thickness 0.15)
				)
			)
		)
		(property "License" "Apache-2.0"
			(at 0 0 0)
			(unlocked yes)
			(layer "F.Fab")
			(hide yes)
			(effects
				(font
					(size 1 1)
					(thickness 0.15)
				)
			)
		)
		(property "Author" "Antmicro"
			(at 0 0 0)
			(unlocked yes)
			(layer "F.Fab")
			(hide yes)
			(effects
				(font
					(size 1 1)
					(thickness 0.15)
				)
			)
		)
		(property "Val" "1u"
			(at 0 0 0)
			(unlocked yes)
			(layer "F.Fab")
			(hide yes)
			(effects
				(font
					(size 1 1)
					(thickness 0.15)
				)
			)
		)
		(property "Voltage" "25V"
			(at 0 0 0)
			(unlocked yes)
			(layer "F.Fab")
			(hide yes)
			(effects
				(font
					(size 1 1)
					(thickness 0.15)
				)
			)
		)
		(property "Dielectric" "X5R"
			(at 0 0 0)
			(unlocked yes)
			(layer "F.Fab")
			(hide yes)
			(effects
				(font
					(size 1 1)
					(thickness 0.15)
				)
			)
		)
		(sheetname "/PD and TB DC-DC/")
		(sheetfile "PD_and_TB_DC_DC.kicad_sch")
		(attr smd)
		(fp_rect
			(start -0.925 -0.47)
			(end 0.925 0.47)
			(stroke
				(width 0.05)
				(type default)
			)
			(fill no)
			(layer "F.CrtYd")
		)
		(fp_line
			(start -0.494 -0.25)
			(end 0.504 -0.25)
			(stroke
				(width 0.15)
				(type solid)
			)
			(layer "F.Fab")
		)
		(fp_line
			(start -0.494 0.248)
			(end -0.494 -0.25)
			(stroke
				(width 0.15)
				(type solid)
			)
			(layer "F.Fab")
		)
		(fp_line
			(start 0.504 -0.25)
			(end 0.504 0.248)
			(stroke
				(width 0.15)
				(type solid)
			)
			(layer "F.Fab")
		)
		(fp_line
			(start 0.504 0.248)
			(end -0.494 0.248)
			(stroke
				(width 0.15)
				(type solid)
			)
			(layer "F.Fab")
		)
		(fp_text user "License: Apache-2.0"
			(at -0.939 5.799 0)
			(layer "F.Fab")
			(effects
				(font
					(size 0.7 0.7)
					(thickness 0.15)
				)
				(justify left bottom)
			)
		)
		(fp_text user "Author: Antmicro"
			(at -0.939 3.399 0)
			(layer "F.Fab")
			(effects
				(font
					(size 0.7 0.7)
					(thickness 0.15)
				)
				(justify left bottom)
			)
		)
		(fp_text user "${REFERENCE}"
			(at -0.939 4.599 0)
			(layer "F.Fab")
			(effects
				(font
					(size 0.7 0.7)
					(thickness 0.15)
				)
				(justify left bottom)
			)
		)
		(pad "1" smd roundrect
			(at -0.48 0)
			(size 0.59 0.64)
			(layers "F.Cu" "F.Mask" "F.Paste")
			(roundrect_rratio 0.25)
			(net 23 "GND")
			(pintype "passive")
		)
		(pad "2" smd roundrect
			(at 0.48 0)
			(size 0.59 0.64)
			(layers "F.Cu" "F.Mask" "F.Paste")
			(roundrect_rratio 0.25)
			(net 182 "VBUS")
			(pintype "passive")
		)
	)
	(footprint "antmicro-footprints:MP_Pad6mm_Drill3.2mm"
		(layer "F.Cu")
		(at 120 50)
		(property "Reference" "MP4"
			(at -1.2 -3.4 0)
			(layer "F.SilkS")
			(effects
				(font
					(size 0.7 0.7)
					(thickness 0.15)
				)
				(justify left bottom)
			)
		)
		(property "Value" "MP_Pad6mm_Drill3.2mm"
			(at 0 3.9 0)
			(layer "F.Fab")
			(effects
				(font
					(size 0.7 0.7)
					(thickness 0.15)
				)
				(justify left bottom)
			)
		)
		(property "Description" "Mechanical part"
			(at 0 0 0)
			(layer "F.Fab")
			(hide yes)
			(effects
				(font
					(size 1.27 1.27)
					(thickness 0.15)
				)
			)
		)
		(property "Author" "Antmicro"
			(at 0 0 0)
			(unlocked yes)
			(layer "F.Fab")
			(hide yes)
			(effects
				(font
					(size 1 1)
					(thickness 0.15)
				)
			)
		)
		(property "License" "Apache-2.0"
			(at 0 0 0)
			(unlocked yes)
			(layer "F.Fab")
			(hide yes)
			(effects
				(font
					(size 1 1)
					(thickness 0.15)
				)
			)
		)
		(sheetname "/")
		(sheetfile "thunderbolt-to-10gbe-adapter.kicad_sch")
		(attr exclude_from_pos_files exclude_from_bom)
		(fp_circle
			(center 0 0)
			(end 3.25 0)
			(stroke
				(width 0.05)
				(type default)
			)
			(fill no)
			(layer "F.CrtYd")
		)
		(fp_text user "License: Apache-2.0"
			(at -0.178 8.425 0)
			(layer "F.Fab")
			(effects
				(font
					(size 0.7 0.7)
					(thickness 0.15)
				)
				(justify left bottom)
			)
		)
		(fp_text user "${REFERENCE}"
			(at -0.178 6.025 0)
			(layer "F.Fab")
			(effects
				(font
					(size 0.7 0.7)
					(thickness 0.15)
				)
				(justify left bottom)
			)
		)
		(fp_text user "Author: Antmicro"
			(at -0.178 7.225 0)
			(layer "F.Fab")
			(effects
				(font
					(size 0.7 0.7)
					(thickness 0.15)
				)
				(justify left bottom)
			)
		)
		(pad "1" thru_hole circle
			(at 0 0)
			(size 6 6)
			(drill 3.2)
			(layers "*.Cu" "*.Mask")
			(remove_unused_layers no)
			(net 23 "GND")
			(pintype "passive")
		)
	)
	(footprint "antmicro-footprints:R_0402_1005Metric"
		(layer "F.Cu")
		(at 155.254999 69.074999 90)
		(descr "Resistor SMD 0402")
		(tags "resistor SMD 0402")
		(property "Reference" "R154"
			(at 11.574999 20.295 90)
			(layer "F.SilkS")
			(effects
				(font
					(size 0.7 0.7)
					(thickness 0.15)
				)
			)
		)
		(property "Value" "R_10k_0402"
			(at -1.011843 1.772047 90)
			(layer "F.Fab")
			(effects
				(font
					(size 0.7 0.7)
					(thickness 0.15)
				)
				(justify left bottom)
			)
		)
		(property "Datasheet" "https://www.bourns.com/docs/product-datasheets/cr.pdf"
			(at 0 0 90)
			(layer "F.Fab")
			(hide yes)
			(effects
				(font
					(size 1.27 1.27)
					(thickness 0.15)
				)
			)
		)
		(property "Description" "SMD Chip Resistor, 10 kohm, ± 1%, 62.5 mW, 0402 [1005 Metric], Thick Film, General Purpose"
			(at 0 0 90)
			(layer "F.Fab")
			(hide yes)
			(effects
				(font
					(size 1.27 1.27)
					(thickness 0.15)
				)
			)
		)
		(property "MPN" "CR0402-FX-1002GLF"
			(at 0 0 90)
			(unlocked yes)
			(layer "F.Fab")
			(hide yes)
			(effects
				(font
					(size 1 1)
					(thickness 0.15)
				)
			)
		)
		(property "Manufacturer" "Bourns"
			(at 0 0 90)
			(unlocked yes)
			(layer "F.Fab")
			(hide yes)
			(effects
				(font
					(size 1 1)
					(thickness 0.15)
				)
			)
		)
		(property "License" "Apache-2.0"
			(at 0 0 90)
			(unlocked yes)
			(layer "F.Fab")
			(hide yes)
			(effects
				(font
					(size 1 1)
					(thickness 0.15)
				)
			)
		)
		(property "Author" "Antmicro"
			(at 0 0 90)
			(unlocked yes)
			(layer "F.Fab")
			(hide yes)
			(effects
				(font
					(size 1 1)
					(thickness 0.15)
				)
			)
		)
		(property "Val" "10k"
			(at 0 0 90)
			(unlocked yes)
			(layer "F.Fab")
			(hide yes)
			(effects
				(font
					(size 1 1)
					(thickness 0.15)
				)
			)
		)
		(property "Tolerance" "1%"
			(at 0 0 90)
			(unlocked yes)
			(layer "F.Fab")
			(hide yes)
			(effects
				(font
					(size 1 1)
					(thickness 0.15)
				)
			)
		)
		(sheetname "/X710-AT2 Misc/")
		(sheetfile "x710-at2-mics.kicad_sch")
		(attr smd)
		(fp_rect
			(start -0.925 -0.47)
			(end 0.925 0.47)
			(stroke
				(width 0.05)
				(type default)
			)
			(fill no)
			(layer "F.CrtYd")
		)
		(fp_rect
			(start -0.5 -0.25)
			(end 0.5 0.25)
			(stroke
				(width 0.15)
				(type solid)
			)
			(fill no)
			(layer "F.Fab")
		)
		(fp_text user "License: Apache-2.0"
			(at -0.95 5.169 90)
			(layer "F.Fab")
			(effects
				(font
					(size 0.7 0.7)
					(thickness 0.15)
				)
				(justify left bottom)
			)
		)
		(fp_text user "Author: Antmicro"
			(at -0.95 4.169 90)
			(layer "F.Fab")
			(effects
				(font
					(size 0.7 0.7)
					(thickness 0.15)
				)
				(justify left bottom)
			)
		)
		(fp_text user "${REFERENCE}"
			(at -0.95 3.168 90)
			(layer "F.Fab")
			(effects
				(font
					(size 0.7 0.7)
					(thickness 0.15)
				)
				(justify left bottom)
			)
		)
		(pad "1" smd roundrect
			(at -0.48 0 90)
			(size 0.59 0.64)
			(layers "F.Cu" "F.Mask" "F.Paste")
			(roundrect_rratio 0.25)
			(net 75 "/X710-AT2 Misc/AUX_PWR")
			(pintype "passive")
		)
		(pad "2" smd roundrect
			(at 0.48 0 90)
			(size 0.59 0.64)
			(layers "F.Cu" "F.Mask" "F.Paste")
			(roundrect_rratio 0.25)
			(net 7 "+3V3")
			(pintype "passive")
		)
	)
	(footprint "antmicro-footprints:R_0603_1608Metric"
		(layer "F.Cu")
		(at 145.35 57.3 90)
		(descr "Resistor SMD 0603")
		(tags "resistor SMD 0603")
		(property "Reference" "R234"
			(at -4 0.65 90)
			(layer "F.SilkS")
			(effects
				(font
					(size 0.7 0.7)
					(thickness 0.15)
				)
				(justify left bottom)
			)
		)
		(property "Value" "R_0R_22.4A_0603"
			(at 0 1.6 90)
			(layer "F.Fab")
			(effects
				(font
					(size 0.7 0.7)
					(thickness 0.15)
				)
				(justify left bottom)
			)
		)
		(property "Datasheet" "https://fscdn.rohm.com/en/products/databook/datasheet/passive/resistor/chip_resistor/pmr-jpw-e.pdf"
			(at 0 0 90)
			(layer "F.Fab")
			(hide yes)
			(effects
				(font
					(size 1.27 1.27)
					(thickness 0.15)
				)
			)
		)
		(property "Description" "SMD Chip Resistor"
			(at 0 0 90)
			(layer "F.Fab")
			(hide yes)
			(effects
				(font
					(size 1.27 1.27)
					(thickness 0.15)
				)
			)
		)
		(property "MPN" "PMR03EZPJ000"
			(at 0 0 90)
			(unlocked yes)
			(layer "F.Fab")
			(hide yes)
			(effects
				(font
					(size 1 1)
					(thickness 0.15)
				)
			)
		)
		(property "Manufacturer" "ROHM Semiconductor"
			(at 0 0 90)
			(unlocked yes)
			(layer "F.Fab")
			(hide yes)
			(effects
				(font
					(size 1 1)
					(thickness 0.15)
				)
			)
		)
		(property "Val" "0R"
			(at 0 0 90)
			(unlocked yes)
			(layer "F.Fab")
			(hide yes)
			(effects
				(font
					(size 1 1)
					(thickness 0.15)
				)
			)
		)
		(property "Max. Curr." "22.4A"
			(at 0 0 90)
			(unlocked yes)
			(layer "F.Fab")
			(hide yes)
			(effects
				(font
					(size 1 1)
					(thickness 0.15)
				)
			)
		)
		(property "Author" "Antmicro"
			(at 0 0 90)
			(unlocked yes)
			(layer "F.Fab")
			(hide yes)
			(effects
				(font
					(size 1 1)
					(thickness 0.15)
				)
			)
		)
		(property "License" "Apache-2.0"
			(at 0 0 90)
			(unlocked yes)
			(layer "F.Fab")
			(hide yes)
			(effects
				(font
					(size 1 1)
					(thickness 0.15)
				)
			)
		)
		(property "Tolerance" "template_tolerance"
			(at 0 0 90)
			(unlocked yes)
			(layer "F.Fab")
			(hide yes)
			(effects
				(font
					(size 1 1)
					(thickness 0.15)
				)
			)
		)
		(sheetname "/Power input/")
		(sheetfile "power_input.kicad_sch")
		(attr smd)
		(fp_line
			(start -0.15 -0.4)
			(end 0.15 -0.4)
			(stroke
				(width 0.15)
				(type solid)
			)
			(layer "F.SilkS")
		)
		(fp_line
			(start -0.15 0.4)
			(end 0.15 0.4)
			(stroke
				(width 0.15)
				(type solid)
			)
			(layer "F.SilkS")
		)
		(fp_rect
			(start -1.25 -0.65)
			(end 1.25 0.65)
			(stroke
				(width 0.05)
				(type solid)
			)
			(fill no)
			(layer "F.CrtYd")
		)
		(fp_rect
			(start -0.8 -0.4)
			(end 0.8 0.4)
			(stroke
				(width 0.15)
				(type solid)
			)
			(fill no)
			(layer "F.Fab")
		)
		(fp_text user "${REFERENCE}"
			(at -1.25 3.898 90)
			(layer "F.Fab")
			(effects
				(font
					(size 0.7 0.7)
					(thickness 0.15)
				)
				(justify left bottom)
			)
		)
		(fp_text user "Author: Antmicro"
			(at -1.25 4.9 90)
			(layer "F.Fab")
			(effects
				(font
					(size 0.7 0.7)
					(thickness 0.15)
				)
				(justify left bottom)
			)
		)
		(fp_text user "License: Apache-2.0"
			(at -1.25 5.9 90)
			(layer "F.Fab")
			(effects
				(font
					(size 0.7 0.7)
					(thickness 0.15)
				)
				(justify left bottom)
			)
		)
		(pad "1" smd roundrect
			(at -0.7 0 90)
			(size 0.8 1)
			(layers "F.Cu" "F.Mask" "F.Paste")
			(roundrect_rratio 0.2)
			(net 349 "/Power input/5V_OUT")
			(pintype "passive")
		)
		(pad "2" smd roundrect
			(at 0.7 0 90)
			(size 0.8 1)
			(layers "F.Cu" "F.Mask" "F.Paste")
			(roundrect_rratio 0.2)
			(net 13 "/Power input/5V_JACK")
			(pintype "passive")
		)
	)
	(footprint "antmicro-footprints:R_0402_1005Metric"
		(layer "F.Cu")
		(at 163.6 67.8)
		(descr "Resistor SMD 0402")
		(tags "resistor SMD 0402")
		(property "Reference" "R143"
			(at -1.8 -0.6 0)
			(layer "F.SilkS")
			(effects
				(font
					(size 0.7 0.7)
					(thickness 0.15)
				)
				(justify left bottom)
			)
		)
		(property "Value" "R_2k_0402"
			(at -1.011843 1.772047 0)
			(layer "F.Fab")
			(effects
				(font
					(size 0.7 0.7)
					(thickness 0.15)
				)
				(justify left bottom)
			)
		)
		(property "Datasheet" "https://www.bourns.com/docs/product-datasheets/cr.pdf"
			(at 0 0 0)
			(layer "F.Fab")
			(hide yes)
			(effects
				(font
					(size 1.27 1.27)
					(thickness 0.15)
				)
			)
		)
		(property "Description" "SMD Chip Resistor, 2 kohm, ± 1%, 62.5 mW, 0402 [1005 Metric], Thick Film, General Purpose"
			(at 0 0 0)
			(layer "F.Fab")
			(hide yes)
			(effects
				(font
					(size 1.27 1.27)
					(thickness 0.15)
				)
			)
		)
		(property "MPN" "CR0402-FX-2001GLF"
			(at 0 0 0)
			(unlocked yes)
			(layer "F.Fab")
			(hide yes)
			(effects
				(font
					(size 1 1)
					(thickness 0.15)
				)
			)
		)
		(property "Manufacturer" "Bourns"
			(at 0 0 0)
			(unlocked yes)
			(layer "F.Fab")
			(hide yes)
			(effects
				(font
					(size 1 1)
					(thickness 0.15)
				)
			)
		)
		(property "License" "Apache-2.0"
			(at 0 0 0)
			(unlocked yes)
			(layer "F.Fab")
			(hide yes)
			(effects
				(font
					(size 1 1)
					(thickness 0.15)
				)
			)
		)
		(property "Author" "Antmicro"
			(at 0 0 0)
			(unlocked yes)
			(layer "F.Fab")
			(hide yes)
			(effects
				(font
					(size 1 1)
					(thickness 0.15)
				)
			)
		)
		(property "Val" "2k"
			(at 0 0 0)
			(unlocked yes)
			(layer "F.Fab")
			(hide yes)
			(effects
				(font
					(size 1 1)
					(thickness 0.15)
				)
			)
		)
		(property "Tolerance" "1%"
			(at 0 0 0)
			(unlocked yes)
			(layer "F.Fab")
			(hide yes)
			(effects
				(font
					(size 1 1)
					(thickness 0.15)
				)
			)
		)
		(sheetname "/X710-AT2 Misc/")
		(sheetfile "x710-at2-mics.kicad_sch")
		(attr smd)
		(fp_rect
			(start -0.925 -0.47)
			(end 0.925 0.47)
			(stroke
				(width 0.05)
				(type default)
			)
			(fill no)
			(layer "F.CrtYd")
		)
		(fp_rect
			(start -0.5 -0.25)
			(end 0.5 0.25)
			(stroke
				(width 0.15)
				(type solid)
			)
			(fill no)
			(layer "F.Fab")
		)
		(fp_text user "${REFERENCE}"
			(at -0.95 3.168 0)
			(layer "F.Fab")
			(effects
				(font
					(size 0.7 0.7)
					(thickness 0.15)
				)
				(justify left bottom)
			)
		)
		(fp_text user "Author: Antmicro"
			(at -0.95 4.169 0)
			(layer "F.Fab")
			(effects
				(font
					(size 0.7 0.7)
					(thickness 0.15)
				)
				(justify left bottom)
			)
		)
		(fp_text user "License: Apache-2.0"
			(at -0.95 5.169 0)
			(layer "F.Fab")
			(effects
				(font
					(size 0.7 0.7)
					(thickness 0.15)
				)
				(justify left bottom)
			)
		)
		(pad "1" smd roundrect
			(at -0.48 0)
			(size 0.59 0.64)
			(layers "F.Cu" "F.Mask" "F.Paste")
			(roundrect_rratio 0.25)
			(net 150 "/X710-AT2 Misc/~{PHY_RESET}")
			(pintype "passive")
		)
		(pad "2" smd roundrect
			(at 0.48 0)
			(size 0.59 0.64)
			(layers "F.Cu" "F.Mask" "F.Paste")
			(roundrect_rratio 0.25)
			(net 18 "+1V88")
			(pintype "passive")
		)
	)
	(footprint "antmicro-footprints:R_0402_1005Metric"
		(layer "F.Cu")
		(at 156.205 69.074999 90)
		(descr "Resistor SMD 0402")
		(tags "resistor SMD 0402")
		(property "Reference" "R145"
			(at 11.574999 20.295 90)
			(layer "F.SilkS")
			(effects
				(font
					(size 0.7 0.7)
					(thickness 0.15)
				)
			)
		)
		(property "Value" "R_10k_0402"
			(at -1.011843 1.772047 90)
			(layer "F.Fab")
			(effects
				(font
					(size 0.7 0.7)
					(thickness 0.15)
				)
				(justify left bottom)
			)
		)
		(property "Datasheet" "https://www.bourns.com/docs/product-datasheets/cr.pdf"
			(at 0 0 90)
			(layer "F.Fab")
			(hide yes)
			(effects
				(font
					(size 1.27 1.27)
					(thickness 0.15)
				)
			)
		)
		(property "Description" "SMD Chip Resistor, 10 kohm, ± 1%, 62.5 mW, 0402 [1005 Metric], Thick Film, General Purpose"
			(at 0 0 90)
			(layer "F.Fab")
			(hide yes)
			(effects
				(font
					(size 1.27 1.27)
					(thickness 0.15)
				)
			)
		)
		(property "MPN" "CR0402-FX-1002GLF"
			(at 0 0 90)
			(unlocked yes)
			(layer "F.Fab")
			(hide yes)
			(effects
				(font
					(size 1 1)
					(thickness 0.15)
				)
			)
		)
		(property "Manufacturer" "Bourns"
			(at 0 0 90)
			(unlocked yes)
			(layer "F.Fab")
			(hide yes)
			(effects
				(font
					(size 1 1)
					(thickness 0.15)
				)
			)
		)
		(property "License" "Apache-2.0"
			(at 0 0 90)
			(unlocked yes)
			(layer "F.Fab")
			(hide yes)
			(effects
				(font
					(size 1 1)
					(thickness 0.15)
				)
			)
		)
		(property "Author" "Antmicro"
			(at 0 0 90)
			(unlocked yes)
			(layer "F.Fab")
			(hide yes)
			(effects
				(font
					(size 1 1)
					(thickness 0.15)
				)
			)
		)
		(property "Val" "10k"
			(at 0 0 90)
			(unlocked yes)
			(layer "F.Fab")
			(hide yes)
			(effects
				(font
					(size 1 1)
					(thickness 0.15)
				)
			)
		)
		(property "Tolerance" "1%"
			(at 0 0 90)
			(unlocked yes)
			(layer "F.Fab")
			(hide yes)
			(effects
				(font
					(size 1 1)
					(thickness 0.15)
				)
			)
		)
		(sheetname "/X710-AT2 Misc/")
		(sheetfile "x710-at2-mics.kicad_sch")
		(attr smd)
		(fp_rect
			(start -0.925 -0.47)
			(end 0.925 0.47)
			(stroke
				(width 0.05)
				(type default)
			)
			(fill no)
			(layer "F.CrtYd")
		)
		(fp_rect
			(start -0.5 -0.25)
			(end 0.5 0.25)
			(stroke
				(width 0.15)
				(type solid)
			)
			(fill no)
			(layer "F.Fab")
		)
		(fp_text user "License: Apache-2.0"
			(at -0.95 5.169 90)
			(layer "F.Fab")
			(effects
				(font
					(size 0.7 0.7)
					(thickness 0.15)
				)
				(justify left bottom)
			)
		)
		(fp_text user "Author: Antmicro"
			(at -0.95 4.169 90)
			(layer "F.Fab")
			(effects
				(font
					(size 0.7 0.7)
					(thickness 0.15)
				)
				(justify left bottom)
			)
		)
		(fp_text user "${REFERENCE}"
			(at -0.95 3.168 90)
			(layer "F.Fab")
			(effects
				(font
					(size 0.7 0.7)
					(thickness 0.15)
				)
				(justify left bottom)
			)
		)
		(pad "1" smd roundrect
			(at -0.48 0 90)
			(size 0.59 0.64)
			(layers "F.Cu" "F.Mask" "F.Paste")
			(roundrect_rratio 0.25)
			(net 103 "/X710-AT2 Misc/MAIN_PWR_OK")
			(pintype "passive")
		)
		(pad "2" smd roundrect
			(at 0.48 0 90)
			(size 0.59 0.64)
			(layers "F.Cu" "F.Mask" "F.Paste")
			(roundrect_rratio 0.25)
			(net 7 "+3V3")
			(pintype "passive")
		)
	)
	(footprint "antmicro-footprints:C_0402_1005Metric"
		(layer "F.Cu")
		(at 175.822358 77 90)
		(descr "Capacitor SMD 0402")
		(tags "capacitor SMD 0402")
		(property "Reference" "C275"
			(at -1.4 1.377642 90)
			(layer "F.SilkS")
			(effects
				(font
					(size 0.7 0.7)
					(thickness 0.15)
				)
				(justify left bottom)
			)
		)
		(property "Value" "C_100n_0402"
			(at -1.022927 2.155213 90)
			(layer "F.Fab")
			(effects
				(font
					(size 0.7 0.7)
					(thickness 0.15)
				)
				(justify left bottom)
			)
		)
		(property "Datasheet" "https://www.murata.com/products/productdetail?partno=GRM155R61H104KE14%23"
			(at 0 0 90)
			(layer "F.Fab")
			(hide yes)
			(effects
				(font
					(size 1.27 1.27)
					(thickness 0.15)
				)
			)
		)
		(property "Description" "SMD Multilayer Ceramic Capacitor, 0.1 µF, 50 V, 0402 [1005 Metric], ± 10%, X5R, GRM Series"
			(at 0 0 90)
			(layer "F.Fab")
			(hide yes)
			(effects
				(font
					(size 1.27 1.27)
					(thickness 0.15)
				)
			)
		)
		(property "MPN" "GRM155R61H104KE14D"
			(at 0 0 90)
			(unlocked yes)
			(layer "F.Fab")
			(hide yes)
			(effects
				(font
					(size 1 1)
					(thickness 0.15)
				)
			)
		)
		(property "Val" "100n"
			(at 0 0 90)
			(unlocked yes)
			(layer "F.Fab")
			(hide yes)
			(effects
				(font
					(size 1 1)
					(thickness 0.15)
				)
			)
		)
		(property "Voltage" "50V"
			(at 0 0 90)
			(unlocked yes)
			(layer "F.Fab")
			(hide yes)
			(effects
				(font
					(size 1 1)
					(thickness 0.15)
				)
			)
		)
		(property "Dielectric" "X5R"
			(at 0 0 90)
			(unlocked yes)
			(layer "F.Fab")
			(hide yes)
			(effects
				(font
					(size 1 1)
					(thickness 0.15)
				)
			)
		)
		(property "Manufacturer" "Murata"
			(at 0 0 90)
			(unlocked yes)
			(layer "F.Fab")
			(hide yes)
			(effects
				(font
					(size 1 1)
					(thickness 0.15)
				)
			)
		)
		(property "License" "Apache-2.0"
			(at 0 0 90)
			(unlocked yes)
			(layer "F.Fab")
			(hide yes)
			(effects
				(font
					(size 1 1)
					(thickness 0.15)
				)
			)
		)
		(property "Author" "Antmicro"
			(at 0 0 90)
			(unlocked yes)
			(layer "F.Fab")
			(hide yes)
			(effects
				(font
					(size 1 1)
					(thickness 0.15)
				)
			)
		)
		(sheetname "/X710-AT2 Misc/")
		(sheetfile "x710-at2-mics.kicad_sch")
		(attr smd)
		(fp_rect
			(start -0.925 -0.47)
			(end 0.925 0.47)
			(stroke
				(width 0.05)
				(type default)
			)
			(fill no)
			(layer "F.CrtYd")
		)
		(fp_line
			(start 0.504 -0.25)
			(end 0.504 0.248)
			(stroke
				(width 0.15)
				(type solid)
			)
			(layer "F.Fab")
		)
		(fp_line
			(start -0.494 -0.25)
			(end 0.504 -0.25)
			(stroke
				(width 0.15)
				(type solid)
			)
			(layer "F.Fab")
		)
		(fp_line
			(start 0.504 0.248)
			(end -0.494 0.248)
			(stroke
				(width 0.15)
				(type solid)
			)
			(layer "F.Fab")
		)
		(fp_line
			(start -0.494 0.248)
			(end -0.494 -0.25)
			(stroke
				(width 0.15)
				(type solid)
			)
			(layer "F.Fab")
		)
		(fp_text user "${REFERENCE}"
			(at -0.939 4.599 90)
			(layer "F.Fab")
			(effects
				(font
					(size 0.7 0.7)
					(thickness 0.15)
				)
				(justify left bottom)
			)
		)
		(fp_text user "License: Apache-2.0"
			(at -0.939 5.799 90)
			(layer "F.Fab")
			(effects
				(font
					(size 0.7 0.7)
					(thickness 0.15)
				)
				(justify left bottom)
			)
		)
		(fp_text user "Author: Antmicro"
			(at -0.939 3.399 90)
			(layer "F.Fab")
			(effects
				(font
					(size 0.7 0.7)
					(thickness 0.15)
				)
				(justify left bottom)
			)
		)
		(pad "1" smd roundrect
			(at -0.48 0 90)
			(size 0.59 0.64)
			(layers "F.Cu" "F.Mask" "F.Paste")
			(roundrect_rratio 0.25)
			(net 23 "GND")
			(pintype "passive")
		)
		(pad "2" smd roundrect
			(at 0.48 0 90)
			(size 0.59 0.64)
			(layers "F.Cu" "F.Mask" "F.Paste")
			(roundrect_rratio 0.25)
			(net 7 "+3V3")
			(pintype "passive")
		)
	)
	(footprint "antmicro-footprints:C_0603_1608Metric_EIA"
		(layer "F.Cu")
		(at 135.1 105.600001 90)
		(descr "Capacitor SMD 0603, IPC-7351 Density Level A")
		(tags "Capacitor 0603")
		(property "Reference" "C135"
			(at -17.849995 16.849997 90)
			(layer "F.SilkS")
			(effects
				(font
					(size 0.7 0.7)
					(thickness 0.15)
				)
			)
		)
		(property "Value" "C_22u_16V_0603"
			(at -1.42757 1.770288 90)
			(layer "F.Fab")
			(effects
				(font
					(size 0.7 0.7)
					(thickness 0.15)
				)
				(justify left bottom)
			)
		)
		(property "Datasheet" "https://product.samsungsem.com/mlcc/CL10A226MO7JZN.do"
			(at 0 0 90)
			(layer "F.Fab")
			(hide yes)
			(effects
				(font
					(size 1.27 1.27)
					(thickness 0.15)
				)
			)
		)
		(property "Description" "SMD Multilayer Ceramic Capacitor"
			(at 0 0 90)
			(layer "F.Fab")
			(hide yes)
			(effects
				(font
					(size 1.27 1.27)
					(thickness 0.15)
				)
			)
		)
		(property "MPN" "CL10A226MO7JZNC"
			(at 0 0 90)
			(unlocked yes)
			(layer "F.Fab")
			(hide yes)
			(effects
				(font
					(size 1 1)
					(thickness 0.15)
				)
			)
		)
		(property "Manufacturer" "Samsung Electro-Mechanics"
			(at 0 0 90)
			(unlocked yes)
			(layer "F.Fab")
			(hide yes)
			(effects
				(font
					(size 1 1)
					(thickness 0.15)
				)
			)
		)
		(property "License" "Apache-2.0"
			(at 0 0 90)
			(unlocked yes)
			(layer "F.Fab")
			(hide yes)
			(effects
				(font
					(size 1 1)
					(thickness 0.15)
				)
			)
		)
		(property "Author" "Antmicro"
			(at 0 0 90)
			(unlocked yes)
			(layer "F.Fab")
			(hide yes)
			(effects
				(font
					(size 1 1)
					(thickness 0.15)
				)
			)
		)
		(property "Val" "22u"
			(at 0 0 90)
			(unlocked yes)
			(layer "F.Fab")
			(hide yes)
			(effects
				(font
					(size 1 1)
					(thickness 0.15)
				)
			)
		)
		(property "Voltage" "16V"
			(at 0 0 90)
			(unlocked yes)
			(layer "F.Fab")
			(hide yes)
			(effects
				(font
					(size 1 1)
					(thickness 0.15)
				)
			)
		)
		(property "Dielectric" ""
			(at 0 0 90)
			(unlocked yes)
			(layer "F.Fab")
			(hide yes)
			(effects
				(font
					(size 1 1)
					(thickness 0.15)
				)
			)
		)
		(sheetname "/X710 DCDC converters/")
		(sheetfile "DCDC_converters_X710.kicad_sch")
		(attr smd)
		(fp_line
			(start -0.15 -0.55)
			(end 0.15 -0.55)
			(stroke
				(width 0.15)
				(type solid)
			)
			(layer "F.SilkS")
		)
		(fp_line
			(start -0.15 0.55)
			(end 0.15 0.55)
			(stroke
				(width 0.15)
				(type solid)
			)
			(layer "F.SilkS")
		)
		(fp_rect
			(start -1.25 -0.65)
			(end 1.25 0.65)
			(stroke
				(width 0.05)
				(type solid)
			)
			(fill no)
			(layer "F.CrtYd")
		)
		(fp_rect
			(start -0.8 -0.45)
			(end 0.8 0.45)
			(stroke
				(width 0.15)
				(type solid)
			)
			(fill no)
			(layer "F.Fab")
		)
		(fp_text user "License: Apache-2.0"
			(at -1.682 5.895 90)
			(layer "F.Fab")
			(effects
				(font
					(size 0.7 0.7)
					(thickness 0.15)
				)
				(justify left bottom)
			)
		)
		(fp_text user "Author: Antmicro"
			(at -1.682 4.894 90)
			(layer "F.Fab")
			(effects
				(font
					(size 0.7 0.7)
					(thickness 0.15)
				)
				(justify left bottom)
			)
		)
		(fp_text user "${REFERENCE}"
			(at -1.682 3.895 90)
			(layer "F.Fab")
			(effects
				(font
					(size 0.7 0.7)
					(thickness 0.15)
				)
				(justify left bottom)
			)
		)
		(pad "1" smd roundrect
			(at -0.7 0 90)
			(size 0.8 1.1)
			(layers "F.Cu" "F.Mask" "F.Paste")
			(roundrect_rratio 0.2)
			(net 23 "GND")
			(pintype "passive")
		)
		(pad "2" smd roundrect
			(at 0.7 0 90)
			(size 0.8 1.1)
			(layers "F.Cu" "F.Mask" "F.Paste")
			(roundrect_rratio 0.2)
			(net 335 "/X710 DCDC converters/+VCCD_OUT")
			(pintype "passive")
		)
	)
	(footprint "antmicro-footprints:C_0603_1608Metric_EIA"
		(layer "F.Cu")
		(at 135.320001 91.25)
		(descr "Capacitor SMD 0603, IPC-7351 Density Level A")
		(tags "Capacitor 0603")
		(property "Reference" "C144"
			(at 36.934999 -9.199999 0)
			(layer "F.SilkS")
			(effects
				(font
					(size 0.7 0.7)
					(thickness 0.15)
				)
			)
		)
		(property "Value" "C_22u_16V_0603"
			(at -1.42757 1.770288 0)
			(layer "F.Fab")
			(effects
				(font
					(size 0.7 0.7)
					(thickness 0.15)
				)
				(justify left bottom)
			)
		)
		(property "Datasheet" "https://product.samsungsem.com/mlcc/CL10A226MO7JZN.do"
			(at 0 0 0)
			(layer "F.Fab")
			(hide yes)
			(effects
				(font
					(size 1.27 1.27)
					(thickness 0.15)
				)
			)
		)
		(property "Description" "SMD Multilayer Ceramic Capacitor"
			(at 0 0 0)
			(layer "F.Fab")
			(hide yes)
			(effects
				(font
					(size 1.27 1.27)
					(thickness 0.15)
				)
			)
		)
		(property "MPN" "CL10A226MO7JZNC"
			(at 0 0 0)
			(unlocked yes)
			(layer "F.Fab")
			(hide yes)
			(effects
				(font
					(size 1 1)
					(thickness 0.15)
				)
			)
		)
		(property "Manufacturer" "Samsung Electro-Mechanics"
			(at 0 0 0)
			(unlocked yes)
			(layer "F.Fab")
			(hide yes)
			(effects
				(font
					(size 1 1)
					(thickness 0.15)
				)
			)
		)
		(property "License" "Apache-2.0"
			(at 0 0 0)
			(unlocked yes)
			(layer "F.Fab")
			(hide yes)
			(effects
				(font
					(size 1 1)
					(thickness 0.15)
				)
			)
		)
		(property "Author" "Antmicro"
			(at 0 0 0)
			(unlocked yes)
			(layer "F.Fab")
			(hide yes)
			(effects
				(font
					(size 1 1)
					(thickness 0.15)
				)
			)
		)
		(property "Val" "22u"
			(at 0 0 0)
			(unlocked yes)
			(layer "F.Fab")
			(hide yes)
			(effects
				(font
					(size 1 1)
					(thickness 0.15)
				)
			)
		)
		(property "Voltage" "16V"
			(at 0 0 0)
			(unlocked yes)
			(layer "F.Fab")
			(hide yes)
			(effects
				(font
					(size 1 1)
					(thickness 0.15)
				)
			)
		)
		(property "Dielectric" ""
			(at 0 0 0)
			(unlocked yes)
			(layer "F.Fab")
			(hide yes)
			(effects
				(font
					(size 1 1)
					(thickness 0.15)
				)
			)
		)
		(sheetname "/X710 DCDC converters/")
		(sheetfile "DCDC_converters_X710.kicad_sch")
		(attr smd)
		(fp_line
			(start -0.15 -0.55)
			(end 0.15 -0.55)
			(stroke
				(width 0.15)
				(type solid)
			)
			(layer "F.SilkS")
		)
		(fp_line
			(start -0.15 0.55)
			(end 0.15 0.55)
			(stroke
				(width 0.15)
				(type solid)
			)
			(layer "F.SilkS")
		)
		(fp_rect
			(start -1.25 -0.65)
			(end 1.25 0.65)
			(stroke
				(width 0.05)
				(type solid)
			)
			(fill no)
			(layer "F.CrtYd")
		)
		(fp_rect
			(start -0.8 -0.45)
			(end 0.8 0.45)
			(stroke
				(width 0.15)
				(type solid)
			)
			(fill no)
			(layer "F.Fab")
		)
		(fp_text user "License: Apache-2.0"
			(at -1.682 5.895 0)
			(layer "F.Fab")
			(effects
				(font
					(size 0.7 0.7)
					(thickness 0.15)
				)
				(justify left bottom)
			)
		)
		(fp_text user "Author: Antmicro"
			(at -1.682 4.894 0)
			(layer "F.Fab")
			(effects
				(font
					(size 0.7 0.7)
					(thickness 0.15)
				)
				(justify left bottom)
			)
		)
		(fp_text user "${REFERENCE}"
			(at -1.682 3.895 0)
			(layer "F.Fab")
			(effects
				(font
					(size 0.7 0.7)
					(thickness 0.15)
				)
				(justify left bottom)
			)
		)
		(pad "1" smd roundrect
			(at -0.7 0)
			(size 0.8 1.1)
			(layers "F.Cu" "F.Mask" "F.Paste")
			(roundrect_rratio 0.2)
			(net 23 "GND")
			(pintype "passive")
		)
		(pad "2" smd roundrect
			(at 0.7 0)
			(size 0.8 1.1)
			(layers "F.Cu" "F.Mask" "F.Paste")
			(roundrect_rratio 0.2)
			(net 334 "/X710 DCDC converters/+3V3_OUT")
			(pintype "passive")
		)
	)
	(footprint "antmicro-footprints:R_0402_1005Metric"
		(layer "F.Cu")
		(at 173.6 72.1 -90)
		(descr "Resistor SMD 0402")
		(tags "resistor SMD 0402")
		(property "Reference" "R200"
			(at -0.9 -0.4 270)
			(layer "F.SilkS")
			(effects
				(font
					(size 0.7 0.7)
					(thickness 0.15)
				)
				(justify left bottom)
			)
		)
		(property "Value" "R_3k3_0402"
			(at -1.011843 1.772047 270)
			(layer "F.Fab")
			(effects
				(font
					(size 0.7 0.7)
					(thickness 0.15)
				)
				(justify left bottom)
			)
		)
		(property "Datasheet" "https://www.bourns.com/docs/product-datasheets/cr.pdf"
			(at 0 0 270)
			(layer "F.Fab")
			(hide yes)
			(effects
				(font
					(size 1.27 1.27)
					(thickness 0.15)
				)
			)
		)
		(property "Description" "SMD Chip Resistor, 3.3 kohm, ± 1%, 63 mW, 0402 [1005 Metric], Thick Film, General Purpose"
			(at 0 0 270)
			(layer "F.Fab")
			(hide yes)
			(effects
				(font
					(size 1.27 1.27)
					(thickness 0.15)
				)
			)
		)
		(property "MPN" "CR0402-FX-3301GLF"
			(at 0 0 270)
			(unlocked yes)
			(layer "F.Fab")
			(hide yes)
			(effects
				(font
					(size 1 1)
					(thickness 0.15)
				)
			)
		)
		(property "Manufacturer" "Bourns"
			(at 0 0 270)
			(unlocked yes)
			(layer "F.Fab")
			(hide yes)
			(effects
				(font
					(size 1 1)
					(thickness 0.15)
				)
			)
		)
		(property "License" "Apache-2.0"
			(at 0 0 270)
			(unlocked yes)
			(layer "F.Fab")
			(hide yes)
			(effects
				(font
					(size 1 1)
					(thickness 0.15)
				)
			)
		)
		(property "Author" "Antmicro"
			(at 0 0 270)
			(unlocked yes)
			(layer "F.Fab")
			(hide yes)
			(effects
				(font
					(size 1 1)
					(thickness 0.15)
				)
			)
		)
		(property "Val" "3k3"
			(at 0 0 270)
			(unlocked yes)
			(layer "F.Fab")
			(hide yes)
			(effects
				(font
					(size 1 1)
					(thickness 0.15)
				)
			)
		)
		(property "Tolerance" "1%"
			(at 0 0 270)
			(unlocked yes)
			(layer "F.Fab")
			(hide yes)
			(effects
				(font
					(size 1 1)
					(thickness 0.15)
				)
			)
		)
		(sheetname "/X710-AT2 10GbE/")
		(sheetfile "x710-at2-10gbe.kicad_sch")
		(attr smd)
		(fp_rect
			(start -0.925 -0.47)
			(end 0.925 0.47)
			(stroke
				(width 0.05)
				(type default)
			)
			(fill no)
			(layer "F.CrtYd")
		)
		(fp_rect
			(start -0.5 -0.25)
			(end 0.5 0.25)
			(stroke
				(width 0.15)
				(type solid)
			)
			(fill no)
			(layer "F.Fab")
		)
		(fp_text user "${REFERENCE}"
			(at -0.95 3.168 270)
			(layer "F.Fab")
			(effects
				(font
					(size 0.7 0.7)
					(thickness 0.15)
				)
				(justify left bottom)
			)
		)
		(fp_text user "License: Apache-2.0"
			(at -0.95 5.169 270)
			(layer "F.Fab")
			(effects
				(font
					(size 0.7 0.7)
					(thickness 0.15)
				)
				(justify left bottom)
			)
		)
		(fp_text user "Author: Antmicro"
			(at -0.95 4.169 270)
			(layer "F.Fab")
			(effects
				(font
					(size 0.7 0.7)
					(thickness 0.15)
				)
				(justify left bottom)
			)
		)
		(pad "1" smd roundrect
			(at -0.48 0 270)
			(size 0.59 0.64)
			(layers "F.Cu" "F.Mask" "F.Paste")
			(roundrect_rratio 0.25)
			(net 100 "/X710-AT2 10GbE/MDC0_SCL0")
			(pintype "passive")
		)
		(pad "2" smd roundrect
			(at 0.48 0 270)
			(size 0.59 0.64)
			(layers "F.Cu" "F.Mask" "F.Paste")
			(roundrect_rratio 0.25)
			(net 7 "+3V3")
			(pintype "passive")
		)
	)
	(footprint "antmicro-footprints:R_0402_1005Metric"
		(layer "F.Cu")
		(at 125.02 89.04 180)
		(descr "Resistor SMD 0402")
		(tags "resistor SMD 0402")
		(property "Reference" "R117"
			(at 1.82 0.509 180)
			(layer "F.SilkS")
			(effects
				(font
					(size 0.7 0.7)
					(thickness 0.15)
				)
				(justify left bottom)
			)
		)
		(property "Value" "R_8k2_0402"
			(at -1.011843 1.772047 180)
			(layer "F.Fab")
			(effects
				(font
					(size 0.7 0.7)
					(thickness 0.15)
				)
				(justify left bottom)
			)
		)
		(property "Datasheet" "https://www.bourns.com/docs/product-datasheets/cr.pdf"
			(at 0 0 180)
			(layer "F.Fab")
			(hide yes)
			(effects
				(font
					(size 1.27 1.27)
					(thickness 0.15)
				)
			)
		)
		(property "Description" "SMD Chip Resistor"
			(at 0 0 180)
			(layer "F.Fab")
			(hide yes)
			(effects
				(font
					(size 1.27 1.27)
					(thickness 0.15)
				)
			)
		)
		(property "MPN" "CR0402-FX-8201GLF"
			(at 0 0 180)
			(unlocked yes)
			(layer "F.Fab")
			(hide yes)
			(effects
				(font
					(size 1 1)
					(thickness 0.15)
				)
			)
		)
		(property "Manufacturer" "Bourns"
			(at 0 0 180)
			(unlocked yes)
			(layer "F.Fab")
			(hide yes)
			(effects
				(font
					(size 1 1)
					(thickness 0.15)
				)
			)
		)
		(property "License" "Apache-2.0"
			(at 0 0 180)
			(unlocked yes)
			(layer "F.Fab")
			(hide yes)
			(effects
				(font
					(size 1 1)
					(thickness 0.15)
				)
			)
		)
		(property "Author" "Antmicro"
			(at 0 0 180)
			(unlocked yes)
			(layer "F.Fab")
			(hide yes)
			(effects
				(font
					(size 1 1)
					(thickness 0.15)
				)
			)
		)
		(property "Val" "8k2"
			(at 0 0 180)
			(unlocked yes)
			(layer "F.Fab")
			(hide yes)
			(effects
				(font
					(size 1 1)
					(thickness 0.15)
				)
			)
		)
		(property "Tolerance" "1%"
			(at 0 0 180)
			(unlocked yes)
			(layer "F.Fab")
			(hide yes)
			(effects
				(font
					(size 1 1)
					(thickness 0.15)
				)
			)
		)
		(sheetname "/X710-AT2 PCIe/")
		(sheetfile "x710-at2-pcie.kicad_sch")
		(attr smd)
		(fp_rect
			(start -0.925 -0.47)
			(end 0.925 0.47)
			(stroke
				(width 0.05)
				(type default)
			)
			(fill no)
			(layer "F.CrtYd")
		)
		(fp_rect
			(start -0.5 -0.25)
			(end 0.5 0.25)
			(stroke
				(width 0.15)
				(type solid)
			)
			(fill no)
			(layer "F.Fab")
		)
		(fp_text user "License: Apache-2.0"
			(at -0.95 5.169 180)
			(layer "F.Fab")
			(effects
				(font
					(size 0.7 0.7)
					(thickness 0.15)
				)
				(justify left bottom)
			)
		)
		(fp_text user "${REFERENCE}"
			(at -0.95 3.168 180)
			(layer "F.Fab")
			(effects
				(font
					(size 0.7 0.7)
					(thickness 0.15)
				)
				(justify left bottom)
			)
		)
		(fp_text user "Author: Antmicro"
			(at -0.95 4.169 180)
			(layer "F.Fab")
			(effects
				(font
					(size 0.7 0.7)
					(thickness 0.15)
				)
				(justify left bottom)
			)
		)
		(pad "1" smd roundrect
			(at -0.48 0 180)
			(size 0.59 0.64)
			(layers "F.Cu" "F.Mask" "F.Paste")
			(roundrect_rratio 0.25)
			(net 11 "/X710-AT2 PCIe/PCIe_JTAG.JTDI")
			(pintype "passive")
		)
		(pad "2" smd roundrect
			(at 0.48 0 180)
			(size 0.59 0.64)
			(layers "F.Cu" "F.Mask" "F.Paste")
			(roundrect_rratio 0.25)
			(net 7 "+3V3")
			(pintype "passive")
		)
	)
	(footprint "antmicro-footprints:C_0402_1005Metric"
		(layer "F.Cu")
		(at 159.249999 109.15)
		(descr "Capacitor SMD 0402")
		(tags "capacitor SMD 0402")
		(property "Reference" "C122"
			(at 12.950004 17.25 0)
			(layer "F.SilkS")
			(effects
				(font
					(size 0.7 0.7)
					(thickness 0.15)
				)
			)
		)
		(property "Value" "C_1u_25V_0402"
			(at -1.022927 2.155213 0)
			(layer "F.Fab")
			(effects
				(font
					(size 0.7 0.7)
					(thickness 0.15)
				)
				(justify left bottom)
			)
		)
		(property "Datasheet" "https://www.murata.com/products/productdetail?partno=GRM155R61E105KE11%23"
			(at 0 0 0)
			(layer "F.Fab")
			(hide yes)
			(effects
				(font
					(size 1.27 1.27)
					(thickness 0.15)
				)
			)
		)
		(property "Description" "SMD Multilayer Ceramic Capacitor, 1 µF, 25 V, 0402 [1005 Metric], ± 10%, X5R, GRM Series"
			(at 0 0 0)
			(layer "F.Fab")
			(hide yes)
			(effects
				(font
					(size 1.27 1.27)
					(thickness 0.15)
				)
			)
		)
		(property "MPN" "GRM155R61E105KE11J"
			(at 0 0 0)
			(unlocked yes)
			(layer "F.Fab")
			(hide yes)
			(effects
				(font
					(size 1 1)
					(thickness 0.15)
				)
			)
		)
		(property "Manufacturer" "Murata"
			(at 0 0 0)
			(unlocked yes)
			(layer "F.Fab")
			(hide yes)
			(effects
				(font
					(size 1 1)
					(thickness 0.15)
				)
			)
		)
		(property "License" "Apache-2.0"
			(at 0 0 0)
			(unlocked yes)
			(layer "F.Fab")
			(hide yes)
			(effects
				(font
					(size 1 1)
					(thickness 0.15)
				)
			)
		)
		(property "Author" "Antmicro"
			(at 0 0 0)
			(unlocked yes)
			(layer "F.Fab")
			(hide yes)
			(effects
				(font
					(size 1 1)
					(thickness 0.15)
				)
			)
		)
		(property "Val" "1u"
			(at 0 0 0)
			(unlocked yes)
			(layer "F.Fab")
			(hide yes)
			(effects
				(font
					(size 1 1)
					(thickness 0.15)
				)
			)
		)
		(property "Voltage" "25V"
			(at 0 0 0)
			(unlocked yes)
			(layer "F.Fab")
			(hide yes)
			(effects
				(font
					(size 1 1)
					(thickness 0.15)
				)
			)
		)
		(property "Dielectric" "X5R"
			(at 0 0 0)
			(unlocked yes)
			(layer "F.Fab")
			(hide yes)
			(effects
				(font
					(size 1 1)
					(thickness 0.15)
				)
			)
		)
		(sheetname "/X710 DCDC converters/")
		(sheetfile "DCDC_converters_X710.kicad_sch")
		(attr smd)
		(fp_rect
			(start -0.925 -0.47)
			(end 0.925 0.47)
			(stroke
				(width 0.05)
				(type default)
			)
			(fill no)
			(layer "F.CrtYd")
		)
		(fp_line
			(start -0.494 -0.25)
			(end 0.504 -0.25)
			(stroke
				(width 0.15)
				(type solid)
			)
			(layer "F.Fab")
		)
		(fp_line
			(start -0.494 0.248)
			(end -0.494 -0.25)
			(stroke
				(width 0.15)
				(type solid)
			)
			(layer "F.Fab")
		)
		(fp_line
			(start 0.504 -0.25)
			(end 0.504 0.248)
			(stroke
				(width 0.15)
				(type solid)
			)
			(layer "F.Fab")
		)
		(fp_line
			(start 0.504 0.248)
			(end -0.494 0.248)
			(stroke
				(width 0.15)
				(type solid)
			)
			(layer "F.Fab")
		)
		(fp_text user "License: Apache-2.0"
			(at -0.939 5.799 0)
			(layer "F.Fab")
			(effects
				(font
					(size 0.7 0.7)
					(thickness 0.15)
				)
				(justify left bottom)
			)
		)
		(fp_text user "Author: Antmicro"
			(at -0.939 3.399 0)
			(layer "F.Fab")
			(effects
				(font
					(size 0.7 0.7)
					(thickness 0.15)
				)
				(justify left bottom)
			)
		)
		(fp_text user "${REFERENCE}"
			(at -0.939 4.599 0)
			(layer "F.Fab")
			(effects
				(font
					(size 0.7 0.7)
					(thickness 0.15)
				)
				(justify left bottom)
			)
		)
		(pad "1" smd roundrect
			(at -0.48 0)
			(size 0.59 0.64)
			(layers "F.Cu" "F.Mask" "F.Paste")
			(roundrect_rratio 0.25)
			(net 23 "GND")
			(pintype "passive")
		)
		(pad "2" smd roundrect
			(at 0.48 0)
			(size 0.59 0.64)
			(layers "F.Cu" "F.Mask" "F.Paste")
			(roundrect_rratio 0.25)
			(net 109 "/X710 DCDC converters/1V0_VCC")
			(pintype "passive")
		)
	)
	(footprint "antmicro-footprints:R_0402_1005Metric"
		(layer "F.Cu")
		(at 142.31 96.674999 180)
		(descr "Resistor SMD 0402")
		(tags "resistor SMD 0402")
		(property "Reference" "R183"
			(at -2.190001 -0.025001 180)
			(layer "F.SilkS")
			(effects
				(font
					(size 0.7 0.7)
					(thickness 0.15)
				)
			)
		)
		(property "Value" "R_8k2_0402"
			(at -1.011843 1.772047 180)
			(layer "F.Fab")
			(effects
				(font
					(size 0.7 0.7)
					(thickness 0.15)
				)
				(justify left bottom)
			)
		)
		(property "Datasheet" "https://www.bourns.com/docs/product-datasheets/cr.pdf"
			(at 0 0 180)
			(layer "F.Fab")
			(hide yes)
			(effects
				(font
					(size 1.27 1.27)
					(thickness 0.15)
				)
			)
		)
		(property "Description" "SMD Chip Resistor"
			(at 0 0 180)
			(layer "F.Fab")
			(hide yes)
			(effects
				(font
					(size 1.27 1.27)
					(thickness 0.15)
				)
			)
		)
		(property "MPN" "CR0402-FX-8201GLF"
			(at 0 0 180)
			(unlocked yes)
			(layer "F.Fab")
			(hide yes)
			(effects
				(font
					(size 1 1)
					(thickness 0.15)
				)
			)
		)
		(property "Manufacturer" "Bourns"
			(at 0 0 180)
			(unlocked yes)
			(layer "F.Fab")
			(hide yes)
			(effects
				(font
					(size 1 1)
					(thickness 0.15)
				)
			)
		)
		(property "License" "Apache-2.0"
			(at 0 0 180)
			(unlocked yes)
			(layer "F.Fab")
			(hide yes)
			(effects
				(font
					(size 1 1)
					(thickness 0.15)
				)
			)
		)
		(property "Author" "Antmicro"
			(at 0 0 180)
			(unlocked yes)
			(layer "F.Fab")
			(hide yes)
			(effects
				(font
					(size 1 1)
					(thickness 0.15)
				)
			)
		)
		(property "Val" "8k2"
			(at 0 0 180)
			(unlocked yes)
			(layer "F.Fab")
			(hide yes)
			(effects
				(font
					(size 1 1)
					(thickness 0.15)
				)
			)
		)
		(property "Tolerance" "1%"
			(at 0 0 180)
			(unlocked yes)
			(layer "F.Fab")
			(hide yes)
			(effects
				(font
					(size 1 1)
					(thickness 0.15)
				)
			)
		)
		(sheetname "/X710-AT2 Misc/")
		(sheetfile "x710-at2-mics.kicad_sch")
		(attr smd)
		(fp_rect
			(start -0.925 -0.47)
			(end 0.925 0.47)
			(stroke
				(width 0.05)
				(type default)
			)
			(fill no)
			(layer "F.CrtYd")
		)
		(fp_rect
			(start -0.5 -0.25)
			(end 0.5 0.25)
			(stroke
				(width 0.15)
				(type solid)
			)
			(fill no)
			(layer "F.Fab")
		)
		(fp_text user "License: Apache-2.0"
			(at -0.95 5.169 180)
			(layer "F.Fab")
			(effects
				(font
					(size 0.7 0.7)
					(thickness 0.15)
				)
				(justify left bottom)
			)
		)
		(fp_text user "Author: Antmicro"
			(at -0.95 4.169 180)
			(layer "F.Fab")
			(effects
				(font
					(size 0.7 0.7)
					(thickness 0.15)
				)
				(justify left bottom)
			)
		)
		(fp_text user "${REFERENCE}"
			(at -0.95 3.168 180)
			(layer "F.Fab")
			(effects
				(font
					(size 0.7 0.7)
					(thickness 0.15)
				)
				(justify left bottom)
			)
		)
		(pad "1" smd roundrect
			(at -0.48 0 180)
			(size 0.59 0.64)
			(layers "F.Cu" "F.Mask" "F.Paste")
			(roundrect_rratio 0.25)
			(net 23 "GND")
			(pintype "passive")
		)
		(pad "2" smd roundrect
			(at 0.48 0 180)
			(size 0.59 0.64)
			(layers "F.Cu" "F.Mask" "F.Paste")
			(roundrect_rratio 0.25)
			(net 353 "/X710 flash memory/FLASH.CLK")
			(pintype "passive")
		)
	)
	(footprint "antmicro-footprints:C_0603_1608Metric_EIA"
		(layer "F.Cu")
		(at 144.150001 105.600001 90)
		(descr "Capacitor SMD 0603, IPC-7351 Density Level A")
		(tags "Capacitor 0603")
		(property "Reference" "C143"
			(at -17.849995 15.649999 90)
			(layer "F.SilkS")
			(effects
				(font
					(size 0.7 0.7)
					(thickness 0.15)
				)
			)
		)
		(property "Value" "C_22u_16V_0603"
			(at -1.42757 1.770288 90)
			(layer "F.Fab")
			(effects
				(font
					(size 0.7 0.7)
					(thickness 0.15)
				)
				(justify left bottom)
			)
		)
		(property "Datasheet" "https://product.samsungsem.com/mlcc/CL10A226MO7JZN.do"
			(at 0 0 90)
			(layer "F.Fab")
			(hide yes)
			(effects
				(font
					(size 1.27 1.27)
					(thickness 0.15)
				)
			)
		)
		(property "Description" "SMD Multilayer Ceramic Capacitor"
			(at 0 0 90)
			(layer "F.Fab")
			(hide yes)
			(effects
				(font
					(size 1.27 1.27)
					(thickness 0.15)
				)
			)
		)
		(property "MPN" "CL10A226MO7JZNC"
			(at 0 0 90)
			(unlocked yes)
			(layer "F.Fab")
			(hide yes)
			(effects
				(font
					(size 1 1)
					(thickness 0.15)
				)
			)
		)
		(property "Manufacturer" "Samsung Electro-Mechanics"
			(at 0 0 90)
			(unlocked yes)
			(layer "F.Fab")
			(hide yes)
			(effects
				(font
					(size 1 1)
					(thickness 0.15)
				)
			)
		)
		(property "License" "Apache-2.0"
			(at 0 0 90)
			(unlocked yes)
			(layer "F.Fab")
			(hide yes)
			(effects
				(font
					(size 1 1)
					(thickness 0.15)
				)
			)
		)
		(property "Author" "Antmicro"
			(at 0 0 90)
			(unlocked yes)
			(layer "F.Fab")
			(hide yes)
			(effects
				(font
					(size 1 1)
					(thickness 0.15)
				)
			)
		)
		(property "Val" "22u"
			(at 0 0 90)
			(unlocked yes)
			(layer "F.Fab")
			(hide yes)
			(effects
				(font
					(size 1 1)
					(thickness 0.15)
				)
			)
		)
		(property "Voltage" "16V"
			(at 0 0 90)
			(unlocked yes)
			(layer "F.Fab")
			(hide yes)
			(effects
				(font
					(size 1 1)
					(thickness 0.15)
				)
			)
		)
		(property "Dielectric" ""
			(at 0 0 90)
			(unlocked yes)
			(layer "F.Fab")
			(hide yes)
			(effects
				(font
					(size 1 1)
					(thickness 0.15)
				)
			)
		)
		(sheetname "/X710 DCDC converters/")
		(sheetfile "DCDC_converters_X710.kicad_sch")
		(attr smd)
		(fp_line
			(start -0.15 -0.55)
			(end 0.15 -0.55)
			(stroke
				(width 0.15)
				(type solid)
			)
			(layer "F.SilkS")
		)
		(fp_line
			(start -0.15 0.55)
			(end 0.15 0.55)
			(stroke
				(width 0.15)
				(type solid)
			)
			(layer "F.SilkS")
		)
		(fp_rect
			(start -1.25 -0.65)
			(end 1.25 0.65)
			(stroke
				(width 0.05)
				(type solid)
			)
			(fill no)
			(layer "F.CrtYd")
		)
		(fp_rect
			(start -0.8 -0.45)
			(end 0.8 0.45)
			(stroke
				(width 0.15)
				(type solid)
			)
			(fill no)
			(layer "F.Fab")
		)
		(fp_text user "Author: Antmicro"
			(at -1.682 4.894 90)
			(layer "F.Fab")
			(effects
				(font
					(size 0.7 0.7)
					(thickness 0.15)
				)
				(justify left bottom)
			)
		)
		(fp_text user "License: Apache-2.0"
			(at -1.682 5.895 90)
			(layer "F.Fab")
			(effects
				(font
					(size 0.7 0.7)
					(thickness 0.15)
				)
				(justify left bottom)
			)
		)
		(fp_text user "${REFERENCE}"
			(at -1.682 3.895 90)
			(layer "F.Fab")
			(effects
				(font
					(size 0.7 0.7)
					(thickness 0.15)
				)
				(justify left bottom)
			)
		)
		(pad "1" smd roundrect
			(at -0.7 0 90)
			(size 0.8 1.1)
			(layers "F.Cu" "F.Mask" "F.Paste")
			(roundrect_rratio 0.2)
			(net 23 "GND")
			(pintype "passive")
		)
		(pad "2" smd roundrect
			(at 0.7 0 90)
			(size 0.8 1.1)
			(layers "F.Cu" "F.Mask" "F.Paste")
			(roundrect_rratio 0.2)
			(net 341 "/X710 DCDC converters/+DVDD_OUT")
			(pintype "passive")
		)
	)
	(footprint "antmicro-footprints:C_0402_1005Metric"
		(layer "F.Cu")
		(at 129.4 103.1 180)
		(descr "Capacitor SMD 0402")
		(tags "capacitor SMD 0402")
		(property "Reference" "C40"
			(at 2 0 180)
			(layer "F.SilkS")
			(effects
				(font
					(size 0.7 0.7)
					(thickness 0.15)
				)
			)
		)
		(property "Value" "C_10p_0402"
			(at -1.022927 2.155213 180)
			(layer "F.Fab")
			(effects
				(font
					(size 0.7 0.7)
					(thickness 0.15)
				)
				(justify left bottom)
			)
		)
		(property "Datasheet" "https://www.murata.com/products/productdetail?partno=GCM1555C1H100GA16%23"
			(at 0 0 180)
			(layer "F.Fab")
			(hide yes)
			(effects
				(font
					(size 1.27 1.27)
					(thickness 0.15)
				)
			)
		)
		(property "Description" "SMD Multilayer Ceramic Capacitor, 10 pF, 50 V, 0402 [1005 Metric], ± 2%, C0G / NP0, GCM"
			(at 0 0 180)
			(layer "F.Fab")
			(hide yes)
			(effects
				(font
					(size 1.27 1.27)
					(thickness 0.15)
				)
			)
		)
		(property "MPN" "GCM1555C1H100GA16D"
			(at 0 0 180)
			(unlocked yes)
			(layer "F.Fab")
			(hide yes)
			(effects
				(font
					(size 1 1)
					(thickness 0.15)
				)
			)
		)
		(property "Manufacturer" "Murata"
			(at 0 0 180)
			(unlocked yes)
			(layer "F.Fab")
			(hide yes)
			(effects
				(font
					(size 1 1)
					(thickness 0.15)
				)
			)
		)
		(property "License" "Apache-2.0"
			(at 0 0 180)
			(unlocked yes)
			(layer "F.Fab")
			(hide yes)
			(effects
				(font
					(size 1 1)
					(thickness 0.15)
				)
			)
		)
		(property "Val" "10p"
			(at 0 0 180)
			(unlocked yes)
			(layer "F.Fab")
			(hide yes)
			(effects
				(font
					(size 1 1)
					(thickness 0.15)
				)
			)
		)
		(property "Voltage" "50V"
			(at 0 0 180)
			(unlocked yes)
			(layer "F.Fab")
			(hide yes)
			(effects
				(font
					(size 1 1)
					(thickness 0.15)
				)
			)
		)
		(property "Dielectric" "C0G"
			(at 0 0 180)
			(unlocked yes)
			(layer "F.Fab")
			(hide yes)
			(effects
				(font
					(size 1 1)
					(thickness 0.15)
				)
			)
		)
		(property "Author" "Antmicro"
			(at 0 0 180)
			(unlocked yes)
			(layer "F.Fab")
			(hide yes)
			(effects
				(font
					(size 1 1)
					(thickness 0.15)
				)
			)
		)
		(sheetname "/TB Controller/")
		(sheetfile "tb.kicad_sch")
		(attr smd)
		(fp_rect
			(start -0.925 -0.47)
			(end 0.925 0.47)
			(stroke
				(width 0.05)
				(type default)
			)
			(fill no)
			(layer "F.CrtYd")
		)
		(fp_line
			(start 0.504 0.248)
			(end -0.494 0.248)
			(stroke
				(width 0.15)
				(type solid)
			)
			(layer "F.Fab")
		)
		(fp_line
			(start 0.504 -0.25)
			(end 0.504 0.248)
			(stroke
				(width 0.15)
				(type solid)
			)
			(layer "F.Fab")
		)
		(fp_line
			(start -0.494 0.248)
			(end -0.494 -0.25)
			(stroke
				(width 0.15)
				(type solid)
			)
			(layer "F.Fab")
		)
		(fp_line
			(start -0.494 -0.25)
			(end 0.504 -0.25)
			(stroke
				(width 0.15)
				(type solid)
			)
			(layer "F.Fab")
		)
		(fp_text user "${REFERENCE}"
			(at -0.939 4.599 180)
			(layer "F.Fab")
			(effects
				(font
					(size 0.7 0.7)
					(thickness 0.15)
				)
				(justify left bottom)
			)
		)
		(fp_text user "Author: Antmicro"
			(at -0.939 3.399 180)
			(layer "F.Fab")
			(effects
				(font
					(size 0.7 0.7)
					(thickness 0.15)
				)
				(justify left bottom)
			)
		)
		(fp_text user "License: Apache-2.0"
			(at -0.939 5.799 180)
			(layer "F.Fab")
			(effects
				(font
					(size 0.7 0.7)
					(thickness 0.15)
				)
				(justify left bottom)
			)
		)
		(pad "1" smd roundrect
			(at -0.48 0 180)
			(size 0.59 0.64)
			(layers "F.Cu" "F.Mask" "F.Paste")
			(roundrect_rratio 0.25)
			(net 23 "GND")
			(pintype "passive")
		)
		(pad "2" smd roundrect
			(at 0.48 0 180)
			(size 0.59 0.64)
			(layers "F.Cu" "F.Mask" "F.Paste")
			(roundrect_rratio 0.25)
			(net 401 "Net-(U5-XIN{slash}CLKIN)")
			(pintype "passive")
		)
	)
	(footprint "antmicro-footprints:USB-C_Receptacle_JAE_DX07S024JJ2"
		(layer "F.Cu")
		(at 122.375 151.315)
		(property "Reference" "J1"
			(at 1.825 -5.315 0)
			(layer "F.SilkS")
			(effects
				(font
					(size 0.7 0.7)
					(thickness 0.15)
				)
				(justify left bottom)
			)
		)
		(property "Value" "USB-C_JAE_DX07S024JJ2"
			(at -5 5.6 0)
			(layer "F.Fab")
			(effects
				(font
					(size 0.7 0.7)
					(thickness 0.15)
				)
				(justify left bottom)
			)
		)
		(property "Datasheet" "https://www.jae.com/en/connectors/series/detail/product/id=66508"
			(at 0 0 0)
			(layer "F.Fab")
			(hide yes)
			(effects
				(font
					(size 1.27 1.27)
					(thickness 0.15)
				)
			)
		)
		(property "Description" "USB-C (USB TYPE-C) USB 3.2 Gen 2 (USB 3.1 Gen 2, Superspeed + (USB 3.1)) Receptacle Connector 24 Position Surface Mount, Right Angle"
			(at 0 0 0)
			(layer "F.Fab")
			(hide yes)
			(effects
				(font
					(size 1.27 1.27)
					(thickness 0.15)
				)
			)
		)
		(property "MPN" "DX07S024JJ2"
			(at 0 0 0)
			(unlocked yes)
			(layer "F.Fab")
			(hide yes)
			(effects
				(font
					(size 1 1)
					(thickness 0.15)
				)
			)
		)
		(property "Manufacturer" "JAE Electronics"
			(at 0 0 0)
			(unlocked yes)
			(layer "F.Fab")
			(hide yes)
			(effects
				(font
					(size 1 1)
					(thickness 0.15)
				)
			)
		)
		(property "Author" "Antmicro"
			(at 0 0 0)
			(unlocked yes)
			(layer "F.Fab")
			(hide yes)
			(effects
				(font
					(size 1 1)
					(thickness 0.15)
				)
			)
		)
		(property "License" "Apache-2.0"
			(at 0 0 0)
			(unlocked yes)
			(layer "F.Fab")
			(hide yes)
			(effects
				(font
					(size 1 1)
					(thickness 0.15)
				)
			)
		)
		(sheetname "/USB-C connector/")
		(sheetfile "USB-C_connector.kicad_sch")
		(attr smd)
		(fp_line
			(start -4.47 -1.645)
			(end -4.47 0.313)
			(stroke
				(width 0.15)
				(type solid)
			)
			(layer "F.SilkS")
		)
		(fp_line
			(start 4.469 -1.645)
			(end 4.469 0.313)
			(stroke
				(width 0.15)
				(type solid)
			)
			(layer "F.SilkS")
		)
		(fp_circle
			(center -2.625 -4.885)
			(end -2.576 -4.885)
			(stroke
				(width 0.15)
				(type solid)
			)
			(fill yes)
			(layer "F.SilkS")
		)
		(fp_rect
			(start -5.571 -4.885)
			(end 5.669 4.584)
			(stroke
				(width 0.05)
				(type solid)
			)
			(fill no)
			(layer "F.CrtYd")
		)
		(fp_line
			(start -4.96 -4.4)
			(end -4.81 -4.55)
			(stroke
				(width 0.15)
				(type solid)
			)
			(layer "F.Fab")
		)
		(fp_rect
			(start -4.971 -4.575)
			(end 4.969 4.084)
			(stroke
				(width 0.15)
				(type solid)
			)
			(fill no)
			(layer "F.Fab")
		)
		(fp_text user "Author: Antmicro"
			(at -5.571 7.6 0)
			(layer "F.Fab")
			(effects
				(font
					(size 0.7 0.7)
					(thickness 0.15)
				)
				(justify left bottom)
			)
		)
		(fp_text user "License: Apache-2.0"
			(at -5.571 8.8 0)
			(layer "F.Fab")
			(effects
				(font
					(size 0.7 0.7)
					(thickness 0.15)
				)
				(justify left bottom)
			)
		)
		(fp_text user "${REFERENCE}"
			(at -5.571 10 0)
			(layer "F.Fab")
			(effects
				(font
					(size 0.7 0.7)
					(thickness 0.15)
				)
				(justify left bottom)
			)
		)
		(pad "" np_thru_hole circle
			(at -3.601 -1.115)
			(size 0.63 0.63)
			(drill 0.63)
			(layers "*.Cu" "*.Mask")
		)
		(pad "" np_thru_hole oval
			(at 3.6 -1.18)
			(size 0.88 0.53)
			(drill oval 0.88 0.53)
			(layers "*.Cu" "*.Mask")
		)
		(pad "A1" smd rect
			(at -2.625 -3.817)
			(size 0.27 0.9)
			(layers "F.Cu" "F.Mask" "F.Paste")
			(net 23 "GND")
			(pinfunction "GND")
			(pintype "power_in")
		)
		(pad "A2" smd rect
			(at -2.125 -3.817)
			(size 0.27 0.9)
			(layers "F.Cu" "F.Mask" "F.Paste")
			(net 308 "/PD and TB DC-DC/USB3.TX0_P")
			(pinfunction "TX_{1}+")
			(pintype "bidirectional")
		)
		(pad "A3" smd rect
			(at -1.625 -3.817)
			(size 0.27 0.9)
			(layers "F.Cu" "F.Mask" "F.Paste")
			(net 311 "/PD and TB DC-DC/USB3.TX0_N")
			(pinfunction "TX_{1}-")
			(pintype "bidirectional")
		)
		(pad "A4" smd rect
			(at -1.125 -3.817)
			(size 0.27 0.9)
			(layers "F.Cu" "F.Mask" "F.Paste")
			(net 215 "/USB-C connector/VBUS")
			(pinfunction "VBUS")
			(pintype "power_in")
		)
		(pad "A5" smd rect
			(at -0.625 -3.817)
			(size 0.27 0.9)
			(layers "F.Cu" "F.Mask" "F.Paste")
			(net 306 "/PD and TB DC-DC/USB3.CC1")
			(pinfunction "CC_{1}")
			(pintype "bidirectional")
		)
		(pad "A6" smd rect
			(at -0.125 -3.817)
			(size 0.27 0.9)
			(layers "F.Cu" "F.Mask" "F.Paste")
			(net 368 "/PD and TB DC-DC/USB3.D_A_P")
			(pinfunction "D_{A}+")
			(pintype "bidirectional")
		)
		(pad "A7" smd rect
			(at 0.374 -3.817)
			(size 0.27 0.9)
			(layers "F.Cu" "F.Mask" "F.Paste")
			(net 366 "/PD and TB DC-DC/USB3.D_A_N")
			(pinfunction "D_{A}-")
			(pintype "bidirectional")
		)
		(pad "A8" smd rect
			(at 0.874 -3.817)
			(size 0.27 0.9)
			(layers "F.Cu" "F.Mask" "F.Paste")
			(net 369 "/PD and TB DC-DC/USB3.SBU1")
			(pinfunction "SBU_{1}")
			(pintype "bidirectional")
		)
		(pad "A9" smd rect
			(at 1.374 -3.817)
			(size 0.27 0.9)
			(layers "F.Cu" "F.Mask" "F.Paste")
			(net 215 "/USB-C connector/VBUS")
			(pinfunction "VBUS")
			(pintype "passive")
		)
		(pad "A10" smd rect
			(at 1.874 -3.817)
			(size 0.27 0.9)
			(layers "F.Cu" "F.Mask" "F.Paste")
			(net 364 "/PD and TB DC-DC/USB3.RX1_N")
			(pinfunction "RX_{2}-")
			(pintype "bidirectional")
		)
		(pad "A11" smd rect
			(at 2.374 -3.817)
			(size 0.27 0.9)
			(layers "F.Cu" "F.Mask" "F.Paste")
			(net 362 "/PD and TB DC-DC/USB3.RX1_P")
			(pinfunction "RX_{2}+")
			(pintype "bidirectional")
		)
		(pad "A12" smd rect
			(at 2.874 -3.817)
			(size 0.27 0.9)
			(layers "F.Cu" "F.Mask" "F.Paste")
			(net 23 "GND")
			(pinfunction "GND")
			(pintype "passive")
		)
		(pad "B1" smd rect
			(at 2.624 -2.215)
			(size 0.27 0.8)
			(layers "F.Cu" "F.Mask" "F.Paste")
			(net 23 "GND")
			(pinfunction "GND")
			(pintype "passive")
		)
		(pad "B2" smd rect
			(at 2.124 -2.215)
			(size 0.27 0.8)
			(layers "F.Cu" "F.Mask" "F.Paste")
			(net 309 "/PD and TB DC-DC/USB3.TX1_P")
			(pinfunction "TX_{2}+")
			(pintype "bidirectional")
		)
		(pad "B3" smd rect
			(at 1.624 -2.215)
			(size 0.27 0.8)
			(layers "F.Cu" "F.Mask" "F.Paste")
			(net 312 "/PD and TB DC-DC/USB3.TX1_N")
			(pinfunction "TX_{2}-")
			(pintype "bidirectional")
		)
		(pad "B4" smd rect
			(at 1.124 -2.215)
			(size 0.27 0.8)
			(layers "F.Cu" "F.Mask" "F.Paste")
			(net 215 "/USB-C connector/VBUS")
			(pinfunction "VBUS")
			(pintype "passive")
		)
		(pad "B5" smd rect
			(at 0.624 -2.215)
			(size 0.27 0.8)
			(layers "F.Cu" "F.Mask" "F.Paste")
			(net 305 "/PD and TB DC-DC/USB3.CC2")
			(pinfunction "CC_{2}")
			(pintype "bidirectional")
		)
		(pad "B6" smd rect
			(at 0.124 -2.215)
			(size 0.27 0.8)
			(layers "F.Cu" "F.Mask" "F.Paste")
			(net 365 "/PD and TB DC-DC/USB3.D_B_P")
			(pinfunction "D_{B}+")
			(pintype "bidirectional")
		)
		(pad "B7" smd rect
			(at -0.375 -2.215)
			(size 0.27 0.8)
			(layers "F.Cu" "F.Mask" "F.Paste")
			(net 367 "/PD and TB DC-DC/USB3.D_B_N")
			(pinfunction "D_{B}-")
			(pintype "bidirectional")
		)
		(pad "B8" smd rect
			(at -0.875 -2.215)
			(size 0.27 0.8)
			(layers "F.Cu" "F.Mask" "F.Paste")
			(net 361 "/PD and TB DC-DC/USB3.SBU2")
			(pinfunction "SBU_{2}")
			(pintype "bidirectional")
		)
		(pad "B9" smd rect
			(at -1.375 -2.215)
			(size 0.27 0.8)
			(layers "F.Cu" "F.Mask" "F.Paste")
			(net 215 "/USB-C connector/VBUS")
			(pinfunction "VBUS")
			(pintype "passive")
		)
		(pad "B10" smd rect
			(at -1.875 -2.215)
			(size 0.27 0.8)
			(layers "F.Cu" "F.Mask" "F.Paste")
			(net 363 "/PD and TB DC-DC/USB3.RX0_N")
			(pinfunction "RX_{1}-")
			(pintype "bidirectional")
		)
		(pad "B11" smd rect
			(at -2.375 -2.215)
			(size 0.27 0.8)
			(layers "F.Cu" "F.Mask" "F.Paste")
			(net 360 "/PD and TB DC-DC/USB3.RX0_P")
			(pinfunction "RX_{1}+")
			(pintype "bidirectional")
		)
		(pad "B12" smd rect
			(at -2.875 -2.215)
			(size 0.27 0.8)
			(layers "F.Cu" "F.Mask" "F.Paste")
			(net 23 "GND")
			(pinfunction "GND")
			(pintype "passive")
		)
		(pad "SH" thru_hole oval
			(at -4.321 1.933)
			(size 1.3 2.6)
			(drill oval 0.75 2.05)
			(layers "*.Cu" "*.Mask")
			(remove_unused_layers no)
			(net 23 "GND")
			(pinfunction "SH")
			(pintype "passive")
		)
		(pad "SH" thru_hole custom
			(at -4.32 -3.12)
			(size 1.2 1.2)
			(drill oval 0.6 1.9)
			(layers "*.Cu" "*.Mask")
			(remove_unused_layers no)
			(net 23 "GND")
			(pinfunction "SH")
			(pintype "passive")
			(thermal_bridge_angle 90)
			(options
				(clearance outline)
				(anchor circle)
			)
			(primitives
				(gr_line
					(start 0.6 0.6)
					(end 0 0.6)
					(width 1.1)
				)
				(gr_line
					(start 0 -0.55)
					(end 0 0.55)
					(width 1.2)
				)
			)
		)
		(pad "SH" thru_hole oval
			(at -3.99 -2.52 90)
			(size 1 1.55)
			(drill oval 0.7 1.25)
			(layers "*.Cu" "*.Mask")
			(remove_unused_layers no)
			(net 23 "GND")
			(pinfunction "SH")
			(pintype "passive")
		)
		(pad "SH" thru_hole oval
			(at 3.99 -2.52 270)
			(size 1 1.55)
			(drill oval 0.7 1.25)
			(layers "*.Cu" "*.Mask")
			(remove_unused_layers no)
			(net 23 "GND")
			(pinfunction "SH")
			(pintype "passive")
		)
		(pad "SH" thru_hole custom
			(at 4.32 -3.12)
			(size 1.2 1.2)
			(drill oval 0.6 1.9)
			(layers "*.Cu" "*.Mask")
			(remove_unused_layers no)
			(net 23 "GND")
			(pinfunction "SH")
			(pintype "passive")
			(thermal_bridge_angle 90)
			(options
				(clearance outline)
				(anchor circle)
			)
			(primitives
				(gr_line
					(start -0.6 0.6)
					(end 0 0.6)
					(width 1.1)
				)
				(gr_line
					(start 0 -0.55)
					(end 0 0.55)
					(width 1.2)
				)
			)
		)
		(pad "SH" thru_hole oval
			(at 4.32 1.933)
			(size 1.3 2.6)
			(drill oval 0.75 2.05)
			(layers "*.Cu" "*.Mask")
			(remove_unused_layers no)
			(net 23 "GND")
			(pinfunction "SH")
			(pintype "passive")
		)
		(zone
			(net 0)
			(net_name "")
			(layer "F.Cu")
			(name "TOP_KEEPOUT")
			(hatch full 0.508)
			(connect_pads
				(clearance 0)
			)
			(min_thickness 0.01)
			(filled_areas_thickness no)
			(keepout
				(tracks not_allowed)
				(vias not_allowed)
				(pads not_allowed)
				(copperpour not_allowed)
				(footprints allowed)
			)
			(placement
				(enabled no)
				(sheetname "")
			)
			(fill
				(thermal_gap 0.508)
				(thermal_bridge_width 0.508)
			)
			(polygon
				(pts
					(xy 126.274008 150.484992) (xy 125.474736 150.485073) (xy 125.473728 149.799081) (xy 119.135 149.799)
					(xy 119.135 150.565) (xy 118.475 150.565) (xy 118.475 151.948) (xy 118.824 151.948) (xy 118.824 154.548)
					(xy 118.475 154.548) (xy 118.475 155.048) (xy 126.274 155.048) (xy 126.274 154.548) (xy 125.925 154.548)
					(xy 125.925 151.948) (xy 126.274 151.948)
				)
			)
		)
	)
	(footprint "antmicro-footprints:C_0402_1005Metric"
		(layer "F.Cu")
		(at 125.75 134.75 90)
		(descr "Capacitor SMD 0402")
		(tags "capacitor SMD 0402")
		(property "Reference" "C36"
			(at -3.05 0.45 90)
			(layer "F.SilkS")
			(effects
				(font
					(size 0.7 0.7)
					(thickness 0.15)
				)
				(justify left bottom)
			)
		)
		(property "Value" "C_220n_0402"
			(at -1.022927 2.155213 90)
			(layer "F.Fab")
			(effects
				(font
					(size 0.7 0.7)
					(thickness 0.15)
				)
				(justify left bottom)
			)
		)
		(property "Datasheet" "https://www.yageo.com/en/Chart/Download/pdf/CC0402KRX5R6BB224"
			(at 0 0 90)
			(layer "F.Fab")
			(hide yes)
			(effects
				(font
					(size 1.27 1.27)
					(thickness 0.15)
				)
			)
		)
		(property "Description" "SMD Multilayer Ceramic Capacitor, 0.22 µF, 10 V, 0402 [1005 Metric], ± 10%, X5R, CC Series"
			(at 0 0 90)
			(layer "F.Fab")
			(hide yes)
			(effects
				(font
					(size 1.27 1.27)
					(thickness 0.15)
				)
			)
		)
		(property "MPN" "CC0402KRX5R6BB224"
			(at 0 0 90)
			(unlocked yes)
			(layer "F.Fab")
			(hide yes)
			(effects
				(font
					(size 1 1)
					(thickness 0.15)
				)
			)
		)
		(property "Manufacturer" "YAGEO"
			(at 0 0 90)
			(unlocked yes)
			(layer "F.Fab")
			(hide yes)
			(effects
				(font
					(size 1 1)
					(thickness 0.15)
				)
			)
		)
		(property "License" "Apache-2.0"
			(at 0 0 90)
			(unlocked yes)
			(layer "F.Fab")
			(hide yes)
			(effects
				(font
					(size 1 1)
					(thickness 0.15)
				)
			)
		)
		(property "Val" "220n"
			(at 0 0 90)
			(unlocked yes)
			(layer "F.Fab")
			(hide yes)
			(effects
				(font
					(size 1 1)
					(thickness 0.15)
				)
			)
		)
		(property "Voltage" ""
			(at 0 0 90)
			(unlocked yes)
			(layer "F.Fab")
			(hide yes)
			(effects
				(font
					(size 1 1)
					(thickness 0.15)
				)
			)
		)
		(property "Dielectric" ""
			(at 0 0 90)
			(unlocked yes)
			(layer "F.Fab")
			(hide yes)
			(effects
				(font
					(size 1 1)
					(thickness 0.15)
				)
			)
		)
		(property "Author" "Antmicro"
			(at 0 0 90)
			(unlocked yes)
			(layer "F.Fab")
			(hide yes)
			(effects
				(font
					(size 1 1)
					(thickness 0.15)
				)
			)
		)
		(sheetname "/TB Controller/")
		(sheetfile "tb.kicad_sch")
		(attr smd)
		(fp_rect
			(start -0.925 -0.47)
			(end 0.925 0.47)
			(stroke
				(width 0.05)
				(type default)
			)
			(fill no)
			(layer "F.CrtYd")
		)
		(fp_line
			(start 0.504 -0.25)
			(end 0.504 0.248)
			(stroke
				(width 0.15)
				(type solid)
			)
			(layer "F.Fab")
		)
		(fp_line
			(start -0.494 -0.25)
			(end 0.504 -0.25)
			(stroke
				(width 0.15)
				(type solid)
			)
			(layer "F.Fab")
		)
		(fp_line
			(start 0.504 0.248)
			(end -0.494 0.248)
			(stroke
				(width 0.15)
				(type solid)
			)
			(layer "F.Fab")
		)
		(fp_line
			(start -0.494 0.248)
			(end -0.494 -0.25)
			(stroke
				(width 0.15)
				(type solid)
			)
			(layer "F.Fab")
		)
		(fp_text user "${REFERENCE}"
			(at -0.939 4.599 90)
			(layer "F.Fab")
			(effects
				(font
					(size 0.7 0.7)
					(thickness 0.15)
				)
				(justify left bottom)
			)
		)
		(fp_text user "License: Apache-2.0"
			(at -0.939 5.799 90)
			(layer "F.Fab")
			(effects
				(font
					(size 0.7 0.7)
					(thickness 0.15)
				)
				(justify left bottom)
			)
		)
		(fp_text user "Author: Antmicro"
			(at -0.939 3.399 90)
			(layer "F.Fab")
			(effects
				(font
					(size 0.7 0.7)
					(thickness 0.15)
				)
				(justify left bottom)
			)
		)
		(pad "1" smd roundrect
			(at -0.48 0 90)
			(size 0.59 0.64)
			(layers "F.Cu" "F.Mask" "F.Paste")
			(roundrect_rratio 0.25)
			(net 311 "/PD and TB DC-DC/USB3.TX0_N")
			(pintype "passive")
		)
		(pad "2" smd roundrect
			(at 0.48 0 90)
			(size 0.59 0.64)
			(layers "F.Cu" "F.Mask" "F.Paste")
			(roundrect_rratio 0.25)
			(net 169 "/TB Controller/PA_TX0_N")
			(pintype "passive")
		)
	)
	(footprint "antmicro-footprints:C_0805_2012Metric"
		(layer "F.Cu")
		(at 119.65 107.75 180)
		(descr "Capacitor SMD 0805")
		(tags "capacitor SMD 0805")
		(property "Reference" "C7"
			(at -6.55 -6.35 180)
			(layer "F.SilkS")
			(effects
				(font
					(size 0.7 0.7)
					(thickness 0.15)
				)
			)
		)
		(property "Value" "C_22u_25V_0805"
			(at -2.055717 1.963152 180)
			(layer "F.Fab")
			(effects
				(font
					(size 0.7 0.7)
					(thickness 0.15)
				)
				(justify left bottom)
			)
		)
		(property "Datasheet" "https://product.samsungsem.com/mlcc/CL21A226MAYNNN.do"
			(at 0 0 180)
			(layer "F.Fab")
			(hide yes)
			(effects
				(font
					(size 1.27 1.27)
					(thickness 0.15)
				)
			)
		)
		(property "Description" "SMT Multilayer Ceramic Capacitor, 22uF, +/-20%, 25V, X5R, 0805 [2012 Metric]"
			(at 0 0 180)
			(layer "F.Fab")
			(hide yes)
			(effects
				(font
					(size 1.27 1.27)
					(thickness 0.15)
				)
			)
		)
		(property "MPN" "CL21A226MAYNNNE"
			(at 0 0 180)
			(unlocked yes)
			(layer "F.Fab")
			(hide yes)
			(effects
				(font
					(size 1 1)
					(thickness 0.15)
				)
			)
		)
		(property "Manufacturer" "Samsung Electro-Mechanics"
			(at 0 0 180)
			(unlocked yes)
			(layer "F.Fab")
			(hide yes)
			(effects
				(font
					(size 1 1)
					(thickness 0.15)
				)
			)
		)
		(property "License" "Apache-2.0"
			(at 0 0 180)
			(unlocked yes)
			(layer "F.Fab")
			(hide yes)
			(effects
				(font
					(size 1 1)
					(thickness 0.15)
				)
			)
		)
		(property "Author" "Antmicro"
			(at 0 0 180)
			(unlocked yes)
			(layer "F.Fab")
			(hide yes)
			(effects
				(font
					(size 1 1)
					(thickness 0.15)
				)
			)
		)
		(property "Val" "22u"
			(at 0 0 180)
			(unlocked yes)
			(layer "F.Fab")
			(hide yes)
			(effects
				(font
					(size 1 1)
					(thickness 0.15)
				)
			)
		)
		(property "Voltage" "25V"
			(at 0 0 180)
			(unlocked yes)
			(layer "F.Fab")
			(hide yes)
			(effects
				(font
					(size 1 1)
					(thickness 0.15)
				)
			)
		)
		(property "Dielectric" "X5R"
			(at 0 0 180)
			(unlocked yes)
			(layer "F.Fab")
			(hide yes)
			(effects
				(font
					(size 1 1)
					(thickness 0.15)
				)
			)
		)
		(property "Public" "False"
			(at 0 0 180)
			(unlocked yes)
			(layer "F.Fab")
			(hide yes)
			(effects
				(font
					(size 1 1)
					(thickness 0.15)
				)
			)
		)
		(sheetname "/PD and TB DC-DC/")
		(sheetfile "PD_and_TB_DC_DC.kicad_sch")
		(attr smd)
		(fp_line
			(start -0.3 0.7)
			(end 0.3 0.7)
			(stroke
				(width 0.15)
				(type solid)
			)
			(layer "F.SilkS")
		)
		(fp_line
			(start -0.3 -0.7)
			(end 0.3 -0.7)
			(stroke
				(width 0.15)
				(type solid)
			)
			(layer "F.SilkS")
		)
		(fp_rect
			(start 1.95 -0.9)
			(end -1.95 0.9)
			(stroke
				(width 0.05)
				(type default)
			)
			(fill no)
			(layer "F.CrtYd")
		)
		(fp_rect
			(start -0.95 -0.675)
			(end 0.95 0.675)
			(stroke
				(width 0.15)
				(type solid)
			)
			(fill no)
			(layer "F.Fab")
		)
		(fp_text user "License: Apache-2.0"
			(at -1.9 4.947 180)
			(layer "F.Fab")
			(effects
				(font
					(size 0.7 0.7)
					(thickness 0.15)
				)
				(justify left bottom)
			)
		)
		(fp_text user "Author: Antmicro"
			(at -1.9 5.947 180)
			(layer "F.Fab")
			(effects
				(font
					(size 0.7 0.7)
					(thickness 0.15)
				)
				(justify left bottom)
			)
		)
		(fp_text user "${REFERENCE}"
			(at -1.9 3.947 180)
			(layer "F.Fab")
			(effects
				(font
					(size 0.7 0.7)
					(thickness 0.15)
				)
				(justify left bottom)
			)
		)
		(pad "1" smd roundrect
			(at -1.1 0 180)
			(size 1.2 1.3)
			(layers "F.Cu" "F.Mask" "F.Paste")
			(roundrect_rratio 0.25)
			(net 23 "GND")
			(pintype "passive")
		)
		(pad "2" smd roundrect
			(at 1.1 0 180)
			(size 1.2 1.3)
			(layers "F.Cu" "F.Mask" "F.Paste")
			(roundrect_rratio 0.25)
			(net 161 "Net-(U2-VIN)")
			(pintype "passive")
		)
	)
	(footprint "antmicro-footprints:C_0603_1608Metric_EIA"
		(layer "F.Cu")
		(at 130.949999 96.25 -90)
		(descr "Capacitor SMD 0603, IPC-7351 Density Level A")
		(tags "Capacitor 0603")
		(property "Reference" "C109"
			(at -9.249999 -37.685 270)
			(layer "F.SilkS")
			(effects
				(font
					(size 0.7 0.7)
					(thickness 0.15)
				)
			)
		)
		(property "Value" "C_22u_16V_0603"
			(at -1.42757 1.770288 270)
			(layer "F.Fab")
			(effects
				(font
					(size 0.7 0.7)
					(thickness 0.15)
				)
				(justify left bottom)
			)
		)
		(property "Datasheet" "https://product.samsungsem.com/mlcc/CL10A226MO7JZN.do"
			(at 0 0 270)
			(layer "F.Fab")
			(hide yes)
			(effects
				(font
					(size 1.27 1.27)
					(thickness 0.15)
				)
			)
		)
		(property "Description" "SMD Multilayer Ceramic Capacitor"
			(at 0 0 270)
			(layer "F.Fab")
			(hide yes)
			(effects
				(font
					(size 1.27 1.27)
					(thickness 0.15)
				)
			)
		)
		(property "MPN" "CL10A226MO7JZNC"
			(at 0 0 270)
			(unlocked yes)
			(layer "F.Fab")
			(hide yes)
			(effects
				(font
					(size 1 1)
					(thickness 0.15)
				)
			)
		)
		(property "Manufacturer" "Samsung Electro-Mechanics"
			(at 0 0 270)
			(unlocked yes)
			(layer "F.Fab")
			(hide yes)
			(effects
				(font
					(size 1 1)
					(thickness 0.15)
				)
			)
		)
		(property "License" "Apache-2.0"
			(at 0 0 270)
			(unlocked yes)
			(layer "F.Fab")
			(hide yes)
			(effects
				(font
					(size 1 1)
					(thickness 0.15)
				)
			)
		)
		(property "Author" "Antmicro"
			(at 0 0 270)
			(unlocked yes)
			(layer "F.Fab")
			(hide yes)
			(effects
				(font
					(size 1 1)
					(thickness 0.15)
				)
			)
		)
		(property "Val" "22u"
			(at 0 0 270)
			(unlocked yes)
			(layer "F.Fab")
			(hide yes)
			(effects
				(font
					(size 1 1)
					(thickness 0.15)
				)
			)
		)
		(property "Voltage" "16V"
			(at 0 0 270)
			(unlocked yes)
			(layer "F.Fab")
			(hide yes)
			(effects
				(font
					(size 1 1)
					(thickness 0.15)
				)
			)
		)
		(property "Dielectric" ""
			(at 0 0 270)
			(unlocked yes)
			(layer "F.Fab")
			(hide yes)
			(effects
				(font
					(size 1 1)
					(thickness 0.15)
				)
			)
		)
		(sheetname "/X710 DCDC converters/")
		(sheetfile "DCDC_converters_X710.kicad_sch")
		(attr smd)
		(fp_line
			(start -0.15 0.55)
			(end 0.15 0.55)
			(stroke
				(width 0.15)
				(type solid)
			)
			(layer "F.SilkS")
		)
		(fp_line
			(start -0.15 -0.55)
			(end 0.15 -0.55)
			(stroke
				(width 0.15)
				(type solid)
			)
			(layer "F.SilkS")
		)
		(fp_rect
			(start -1.25 -0.65)
			(end 1.25 0.65)
			(stroke
				(width 0.05)
				(type solid)
			)
			(fill no)
			(layer "F.CrtYd")
		)
		(fp_rect
			(start -0.8 -0.45)
			(end 0.8 0.45)
			(stroke
				(width 0.15)
				(type solid)
			)
			(fill no)
			(layer "F.Fab")
		)
		(fp_text user "Author: Antmicro"
			(at -1.682 4.894 270)
			(layer "F.Fab")
			(effects
				(font
					(size 0.7 0.7)
					(thickness 0.15)
				)
				(justify left bottom)
			)
		)
		(fp_text user "License: Apache-2.0"
			(at -1.682 5.895 270)
			(layer "F.Fab")
			(effects
				(font
					(size 0.7 0.7)
					(thickness 0.15)
				)
				(justify left bottom)
			)
		)
		(fp_text user "${REFERENCE}"
			(at -1.682 3.895 270)
			(layer "F.Fab")
			(effects
				(font
					(size 0.7 0.7)
					(thickness 0.15)
				)
				(justify left bottom)
			)
		)
		(pad "1" smd roundrect
			(at -0.7 0 270)
			(size 0.8 1.1)
			(layers "F.Cu" "F.Mask" "F.Paste")
			(roundrect_rratio 0.2)
			(net 23 "GND")
			(pintype "passive")
		)
		(pad "2" smd roundrect
			(at 0.7 0 270)
			(size 0.8 1.1)
			(layers "F.Cu" "F.Mask" "F.Paste")
			(roundrect_rratio 0.2)
			(net 40 "+5V")
			(pintype "passive")
		)
	)
	(footprint "antmicro-footprints:C_0402_1005Metric"
		(layer "F.Cu")
		(at 135 84.2 90)
		(descr "Capacitor SMD 0402")
		(tags "capacitor SMD 0402")
		(property "Reference" "C274"
			(at -1.2 -4.2 90)
			(layer "F.SilkS")
			(effects
				(font
					(size 0.7 0.7)
					(thickness 0.15)
				)
				(justify left bottom)
			)
		)
		(property "Value" "C_100n_0402"
			(at -1.022927 2.155213 90)
			(layer "F.Fab")
			(effects
				(font
					(size 0.7 0.7)
					(thickness 0.15)
				)
				(justify left bottom)
			)
		)
		(property "Datasheet" "https://www.murata.com/products/productdetail?partno=GRM155R61H104KE14%23"
			(at 0 0 90)
			(layer "F.Fab")
			(hide yes)
			(effects
				(font
					(size 1.27 1.27)
					(thickness 0.15)
				)
			)
		)
		(property "Description" "SMD Multilayer Ceramic Capacitor, 0.1 µF, 50 V, 0402 [1005 Metric], ± 10%, X5R, GRM Series"
			(at 0 0 90)
			(layer "F.Fab")
			(hide yes)
			(effects
				(font
					(size 1.27 1.27)
					(thickness 0.15)
				)
			)
		)
		(property "MPN" "GRM155R61H104KE14D"
			(at 0 0 90)
			(unlocked yes)
			(layer "F.Fab")
			(hide yes)
			(effects
				(font
					(size 1 1)
					(thickness 0.15)
				)
			)
		)
		(property "Val" "100n"
			(at 0 0 90)
			(unlocked yes)
			(layer "F.Fab")
			(hide yes)
			(effects
				(font
					(size 1 1)
					(thickness 0.15)
				)
			)
		)
		(property "Voltage" "50V"
			(at 0 0 90)
			(unlocked yes)
			(layer "F.Fab")
			(hide yes)
			(effects
				(font
					(size 1 1)
					(thickness 0.15)
				)
			)
		)
		(property "Dielectric" "X5R"
			(at 0 0 90)
			(unlocked yes)
			(layer "F.Fab")
			(hide yes)
			(effects
				(font
					(size 1 1)
					(thickness 0.15)
				)
			)
		)
		(property "Manufacturer" "Murata"
			(at 0 0 90)
			(unlocked yes)
			(layer "F.Fab")
			(hide yes)
			(effects
				(font
					(size 1 1)
					(thickness 0.15)
				)
			)
		)
		(property "License" "Apache-2.0"
			(at 0 0 90)
			(unlocked yes)
			(layer "F.Fab")
			(hide yes)
			(effects
				(font
					(size 1 1)
					(thickness 0.15)
				)
			)
		)
		(property "Author" "Antmicro"
			(at 0 0 90)
			(unlocked yes)
			(layer "F.Fab")
			(hide yes)
			(effects
				(font
					(size 1 1)
					(thickness 0.15)
				)
			)
		)
		(sheetname "/X710-AT2 Misc/")
		(sheetfile "x710-at2-mics.kicad_sch")
		(attr smd)
		(fp_rect
			(start -0.925 -0.47)
			(end 0.925 0.47)
			(stroke
				(width 0.05)
				(type default)
			)
			(fill no)
			(layer "F.CrtYd")
		)
		(fp_line
			(start 0.504 -0.25)
			(end 0.504 0.248)
			(stroke
				(width 0.15)
				(type solid)
			)
			(layer "F.Fab")
		)
		(fp_line
			(start -0.494 -0.25)
			(end 0.504 -0.25)
			(stroke
				(width 0.15)
				(type solid)
			)
			(layer "F.Fab")
		)
		(fp_line
			(start 0.504 0.248)
			(end -0.494 0.248)
			(stroke
				(width 0.15)
				(type solid)
			)
			(layer "F.Fab")
		)
		(fp_line
			(start -0.494 0.248)
			(end -0.494 -0.25)
			(stroke
				(width 0.15)
				(type solid)
			)
			(layer "F.Fab")
		)
		(fp_text user "Author: Antmicro"
			(at -0.939 3.399 90)
			(layer "F.Fab")
			(effects
				(font
					(size 0.7 0.7)
					(thickness 0.15)
				)
				(justify left bottom)
			)
		)
		(fp_text user "${REFERENCE}"
			(at -0.939 4.599 90)
			(layer "F.Fab")
			(effects
				(font
					(size 0.7 0.7)
					(thickness 0.15)
				)
				(justify left bottom)
			)
		)
		(fp_text user "License: Apache-2.0"
			(at -0.939 5.799 90)
			(layer "F.Fab")
			(effects
				(font
					(size 0.7 0.7)
					(thickness 0.15)
				)
				(justify left bottom)
			)
		)
		(pad "1" smd roundrect
			(at -0.48 0 90)
			(size 0.59 0.64)
			(layers "F.Cu" "F.Mask" "F.Paste")
			(roundrect_rratio 0.25)
			(net 23 "GND")
			(pintype "passive")
		)
		(pad "2" smd roundrect
			(at 0.48 0 90)
			(size 0.59 0.64)
			(layers "F.Cu" "F.Mask" "F.Paste")
			(roundrect_rratio 0.25)
			(net 7 "+3V3")
			(pintype "passive")
		)
	)
	(footprint "antmicro-footprints:L_Bourns-SRP2512A"
		(layer "F.Cu")
		(at 151.955 96.374999 90)
		(property "Reference" "L9"
			(at -19.625001 23.294999 270)
			(layer "F.SilkS")
			(effects
				(font
					(size 0.7 0.7)
					(thickness 0.15)
				)
			)
		)
		(property "Value" "L_4u7_1.55A_Bourns-SRP2512A"
			(at 0 2.25 270)
			(layer "F.Fab")
			(effects
				(font
					(size 0.7 0.7)
					(thickness 0.15)
				)
				(justify left bottom)
			)
		)
		(property "Datasheet" "https://www.bourns.com/docs/Product-Datasheets/srp2512a.pdf"
			(at 0 0 90)
			(layer "F.Fab")
			(hide yes)
			(effects
				(font
					(size 1.27 1.27)
					(thickness 0.15)
				)
			)
		)
		(property "Description" "4.7 µH Shielded Drum Core, Wirewound Inductor 1.55 A 235mOhm Max 1008 (2520 Metric)"
			(at 0 0 90)
			(layer "F.Fab")
			(hide yes)
			(effects
				(font
					(size 1.27 1.27)
					(thickness 0.15)
				)
			)
		)
		(property "Val" "4u7/1.55A"
			(at 0 0 90)
			(unlocked yes)
			(layer "F.Fab")
			(hide yes)
			(effects
				(font
					(size 1 1)
					(thickness 0.15)
				)
			)
		)
		(property "Manufacturer" "Bourns"
			(at 0 0 90)
			(unlocked yes)
			(layer "F.Fab")
			(hide yes)
			(effects
				(font
					(size 1 1)
					(thickness 0.15)
				)
			)
		)
		(property "MPN" "SRP2512A-4R7M"
			(at 0 0 90)
			(unlocked yes)
			(layer "F.Fab")
			(hide yes)
			(effects
				(font
					(size 1 1)
					(thickness 0.15)
				)
			)
		)
		(property "ISat" "1.9 A"
			(at 0 0 90)
			(unlocked yes)
			(layer "F.Fab")
			(hide yes)
			(effects
				(font
					(size 1 1)
					(thickness 0.15)
				)
			)
		)
		(property "IMax" "1.55 A"
			(at 0 0 90)
			(unlocked yes)
			(layer "F.Fab")
			(hide yes)
			(effects
				(font
					(size 1 1)
					(thickness 0.15)
				)
			)
		)
		(property "Size" "2.5x2.0"
			(at 0 0 90)
			(unlocked yes)
			(layer "F.Fab")
			(hide yes)
			(effects
				(font
					(size 1 1)
					(thickness 0.15)
				)
			)
		)
		(property "Author" "Antmicro"
			(at 0 0 90)
			(unlocked yes)
			(layer "F.Fab")
			(hide yes)
			(effects
				(font
					(size 1 1)
					(thickness 0.15)
				)
			)
		)
		(property "License" "Apache-2.0"
			(at 0 0 90)
			(unlocked yes)
			(layer "F.Fab")
			(hide yes)
			(effects
				(font
					(size 1 1)
					(thickness 0.15)
				)
			)
		)
		(sheetname "/X710-AT2 power/")
		(sheetfile "x710-at2-power.kicad_sch")
		(attr smd)
		(fp_line
			(start -0.35 -1)
			(end 0.35 -1)
			(stroke
				(width 0.15)
				(type solid)
			)
			(layer "F.SilkS")
		)
		(fp_line
			(start -0.351 1)
			(end 0.349 1)
			(stroke
				(width 0.15)
				(type solid)
			)
			(layer "F.SilkS")
		)
		(fp_rect
			(start -1.65 -1.3)
			(end 1.65 1.3)
			(stroke
				(width 0.05)
				(type solid)
			)
			(fill no)
			(layer "F.CrtYd")
		)
		(fp_text user "License: Apache-2.0"
			(at -2.575 5.875 90)
			(layer "F.Fab")
			(effects
				(font
					(size 0.7 0.7)
					(thickness 0.15)
				)
				(justify left bottom)
			)
		)
		(fp_text user "${REFERENCE}"
			(at -2.575 3.475 90)
			(layer "F.Fab")
			(effects
				(font
					(size 0.7 0.7)
					(thickness 0.15)
				)
				(justify left bottom)
			)
		)
		(fp_text user "Author: Antmicro"
			(at -2.575 4.675 90)
			(layer "F.Fab")
			(effects
				(font
					(size 0.7 0.7)
					(thickness 0.15)
				)
				(justify left bottom)
			)
		)
		(pad "1" smd roundrect
			(at -1 0 180)
			(size 2 0.8)
			(layers "F.Cu" "F.Mask" "F.Paste")
			(roundrect_rratio 0.1)
			(net 136 "+1V0")
			(pintype "passive")
		)
		(pad "2" smd roundrect
			(at 1 0 180)
			(size 2 0.8)
			(layers "F.Cu" "F.Mask" "F.Paste")
			(roundrect_rratio 0.1)
			(net 12 "XFI_VDD")
			(pintype "passive")
		)
	)
	(footprint "antmicro-footprints:R_0402_1005Metric"
		(layer "F.Cu")
		(at 147.1 128.2 -90)
		(descr "Resistor SMD 0402")
		(tags "resistor SMD 0402")
		(property "Reference" "R79"
			(at 3.2 -0.4 270)
			(layer "F.SilkS")
			(effects
				(font
					(size 0.7 0.7)
					(thickness 0.15)
				)
				(justify left bottom)
			)
		)
		(property "Value" "R_3k3_0402"
			(at -1.011843 1.772047 270)
			(layer "F.Fab")
			(effects
				(font
					(size 0.7 0.7)
					(thickness 0.15)
				)
				(justify left bottom)
			)
		)
		(property "Datasheet" "https://www.bourns.com/docs/product-datasheets/cr.pdf"
			(at 0 0 270)
			(layer "F.Fab")
			(hide yes)
			(effects
				(font
					(size 1.27 1.27)
					(thickness 0.15)
				)
			)
		)
		(property "Description" "SMD Chip Resistor, 3.3 kohm, ± 1%, 63 mW, 0402 [1005 Metric], Thick Film, General Purpose"
			(at 0 0 270)
			(layer "F.Fab")
			(hide yes)
			(effects
				(font
					(size 1.27 1.27)
					(thickness 0.15)
				)
			)
		)
		(property "MPN" "CR0402-FX-3301GLF"
			(at 0 0 270)
			(unlocked yes)
			(layer "F.Fab")
			(hide yes)
			(effects
				(font
					(size 1 1)
					(thickness 0.15)
				)
			)
		)
		(property "Manufacturer" "Bourns"
			(at 0 0 270)
			(unlocked yes)
			(layer "F.Fab")
			(hide yes)
			(effects
				(font
					(size 1 1)
					(thickness 0.15)
				)
			)
		)
		(property "License" "Apache-2.0"
			(at 0 0 270)
			(unlocked yes)
			(layer "F.Fab")
			(hide yes)
			(effects
				(font
					(size 1 1)
					(thickness 0.15)
				)
			)
		)
		(property "Val" "3k3"
			(at 0 0 270)
			(unlocked yes)
			(layer "F.Fab")
			(hide yes)
			(effects
				(font
					(size 1 1)
					(thickness 0.15)
				)
			)
		)
		(property "Tolerance" "1%"
			(at 0 0 270)
			(unlocked yes)
			(layer "F.Fab")
			(hide yes)
			(effects
				(font
					(size 1 1)
					(thickness 0.15)
				)
			)
		)
		(property "Author" "Antmicro"
			(at 0 0 270)
			(unlocked yes)
			(layer "F.Fab")
			(hide yes)
			(effects
				(font
					(size 1 1)
					(thickness 0.15)
				)
			)
		)
		(sheetname "/TB flash memory/")
		(sheetfile "flash-memory.kicad_sch")
		(attr smd)
		(fp_rect
			(start -0.925 -0.47)
			(end 0.925 0.47)
			(stroke
				(width 0.05)
				(type default)
			)
			(fill no)
			(layer "F.CrtYd")
		)
		(fp_rect
			(start -0.5 -0.25)
			(end 0.5 0.25)
			(stroke
				(width 0.15)
				(type solid)
			)
			(fill no)
			(layer "F.Fab")
		)
		(fp_text user "Author: Antmicro"
			(at -0.95 4.169 270)
			(layer "F.Fab")
			(effects
				(font
					(size 0.7 0.7)
					(thickness 0.15)
				)
				(justify left bottom)
			)
		)
		(fp_text user "License: Apache-2.0"
			(at -0.95 5.169 270)
			(layer "F.Fab")
			(effects
				(font
					(size 0.7 0.7)
					(thickness 0.15)
				)
				(justify left bottom)
			)
		)
		(fp_text user "${REFERENCE}"
			(at -0.95 3.168 270)
			(layer "F.Fab")
			(effects
				(font
					(size 0.7 0.7)
					(thickness 0.15)
				)
				(justify left bottom)
			)
		)
		(pad "1" smd roundrect
			(at -0.48 0 270)
			(size 0.59 0.64)
			(layers "F.Cu" "F.Mask" "F.Paste")
			(roundrect_rratio 0.25)
			(net 357 "/PD and TB DC-DC/TB_FLASH.MISO")
			(pintype "passive")
		)
		(pad "2" smd roundrect
			(at 0.48 0 270)
			(size 0.59 0.64)
			(layers "F.Cu" "F.Mask" "F.Paste")
			(roundrect_rratio 0.25)
			(net 57 "+3V3_TB")
			(pintype "passive")
		)
	)
	(footprint "antmicro-footprints:L_Bourns-SRP2512A"
		(layer "F.Cu")
		(at 154.675 96.385 90)
		(property "Reference" "L10"
			(at -19.625001 23.294999 270)
			(layer "F.SilkS")
			(effects
				(font
					(size 0.7 0.7)
					(thickness 0.15)
				)
			)
		)
		(property "Value" "L_4u7_1.55A_Bourns-SRP2512A"
			(at 0 2.25 270)
			(layer "F.Fab")
			(effects
				(font
					(size 0.7 0.7)
					(thickness 0.15)
				)
				(justify left bottom)
			)
		)
		(property "Datasheet" "https://www.bourns.com/docs/Product-Datasheets/srp2512a.pdf"
			(at 0 0 90)
			(layer "F.Fab")
			(hide yes)
			(effects
				(font
					(size 1.27 1.27)
					(thickness 0.15)
				)
			)
		)
		(property "Description" "4.7 µH Shielded Drum Core, Wirewound Inductor 1.55 A 235mOhm Max 1008 (2520 Metric)"
			(at 0 0 90)
			(layer "F.Fab")
			(hide yes)
			(effects
				(font
					(size 1.27 1.27)
					(thickness 0.15)
				)
			)
		)
		(property "Val" "4u7/1.55A"
			(at 0 0 90)
			(unlocked yes)
			(layer "F.Fab")
			(hide yes)
			(effects
				(font
					(size 1 1)
					(thickness 0.15)
				)
			)
		)
		(property "Manufacturer" "Bourns"
			(at 0 0 90)
			(unlocked yes)
			(layer "F.Fab")
			(hide yes)
			(effects
				(font
					(size 1 1)
					(thickness 0.15)
				)
			)
		)
		(property "MPN" "SRP2512A-4R7M"
			(at 0 0 90)
			(unlocked yes)
			(layer "F.Fab")
			(hide yes)
			(effects
				(font
					(size 1 1)
					(thickness 0.15)
				)
			)
		)
		(property "ISat" "1.9 A"
			(at 0 0 90)
			(unlocked yes)
			(layer "F.Fab")
			(hide yes)
			(effects
				(font
					(size 1 1)
					(thickness 0.15)
				)
			)
		)
		(property "IMax" "1.55 A"
			(at 0 0 90)
			(unlocked yes)
			(layer "F.Fab")
			(hide yes)
			(effects
				(font
					(size 1 1)
					(thickness 0.15)
				)
			)
		)
		(property "Size" "2.5x2.0"
			(at 0 0 90)
			(unlocked yes)
			(layer "F.Fab")
			(hide yes)
			(effects
				(font
					(size 1 1)
					(thickness 0.15)
				)
			)
		)
		(property "Author" "Antmicro"
			(at 0 0 90)
			(unlocked yes)
			(layer "F.Fab")
			(hide yes)
			(effects
				(font
					(size 1 1)
					(thickness 0.15)
				)
			)
		)
		(property "License" "Apache-2.0"
			(at 0 0 90)
			(unlocked yes)
			(layer "F.Fab")
			(hide yes)
			(effects
				(font
					(size 1 1)
					(thickness 0.15)
				)
			)
		)
		(sheetname "/X710-AT2 power/")
		(sheetfile "x710-at2-power.kicad_sch")
		(attr smd)
		(fp_line
			(start -0.35 -1)
			(end 0.35 -1)
			(stroke
				(width 0.15)
				(type solid)
			)
			(layer "F.SilkS")
		)
		(fp_line
			(start -0.351 1)
			(end 0.349 1)
			(stroke
				(width 0.15)
				(type solid)
			)
			(layer "F.SilkS")
		)
		(fp_rect
			(start -1.65 -1.3)
			(end 1.65 1.3)
			(stroke
				(width 0.05)
				(type solid)
			)
			(fill no)
			(layer "F.CrtYd")
		)
		(fp_text user "${REFERENCE}"
			(at -2.575 3.475 90)
			(layer "F.Fab")
			(effects
				(font
					(size 0.7 0.7)
					(thickness 0.15)
				)
				(justify left bottom)
			)
		)
		(fp_text user "Author: Antmicro"
			(at -2.575 4.675 90)
			(layer "F.Fab")
			(effects
				(font
					(size 0.7 0.7)
					(thickness 0.15)
				)
				(justify left bottom)
			)
		)
		(fp_text user "License: Apache-2.0"
			(at -2.575 5.875 90)
			(layer "F.Fab")
			(effects
				(font
					(size 0.7 0.7)
					(thickness 0.15)
				)
				(justify left bottom)
			)
		)
		(pad "1" smd roundrect
			(at -1 0 180)
			(size 2 0.8)
			(layers "F.Cu" "F.Mask" "F.Paste")
			(roundrect_rratio 0.1)
			(net 136 "+1V0")
			(pintype "passive")
		)
		(pad "2" smd roundrect
			(at 1 0 180)
			(size 2 0.8)
			(layers "F.Cu" "F.Mask" "F.Paste")
			(roundrect_rratio 0.1)
			(net 21 "XFI_PVDD")
			(pintype "passive")
		)
	)
	(footprint "antmicro-footprints:R_0402_1005Metric"
		(layer "F.Cu")
		(at 171.6 72.1 90)
		(descr "Resistor SMD 0402")
		(tags "resistor SMD 0402")
		(property "Reference" "R185"
			(at 0.9 0.4 90)
			(layer "F.SilkS")
			(effects
				(font
					(size 0.7 0.7)
					(thickness 0.15)
				)
				(justify left bottom)
			)
		)
		(property "Value" "R_10R_0402"
			(at -1.011843 1.772047 90)
			(layer "F.Fab")
			(effects
				(font
					(size 0.7 0.7)
					(thickness 0.15)
				)
				(justify left bottom)
			)
		)
		(property "Datasheet" "https://www.bourns.com/docs/product-datasheets/cr.pdf"
			(at 0 0 90)
			(layer "F.Fab")
			(hide yes)
			(effects
				(font
					(size 1.27 1.27)
					(thickness 0.15)
				)
			)
		)
		(property "Description" "SMD Chip Resistor, 10 ohm, ± 1%, 62.5 mW, 0402 [1005 Metric], Thick Film, General Purpose"
			(at 0 0 90)
			(layer "F.Fab")
			(hide yes)
			(effects
				(font
					(size 1.27 1.27)
					(thickness 0.15)
				)
			)
		)
		(property "MPN" "CR0402-FX-10R0GLF"
			(at 0 0 90)
			(unlocked yes)
			(layer "F.Fab")
			(hide yes)
			(effects
				(font
					(size 1 1)
					(thickness 0.15)
				)
			)
		)
		(property "Manufacturer" "Bourns"
			(at 0 0 90)
			(unlocked yes)
			(layer "F.Fab")
			(hide yes)
			(effects
				(font
					(size 1 1)
					(thickness 0.15)
				)
			)
		)
		(property "License" "Apache-2.0"
			(at 0 0 90)
			(unlocked yes)
			(layer "F.Fab")
			(hide yes)
			(effects
				(font
					(size 1 1)
					(thickness 0.15)
				)
			)
		)
		(property "Author" "Antmicro"
			(at 0 0 90)
			(unlocked yes)
			(layer "F.Fab")
			(hide yes)
			(effects
				(font
					(size 1 1)
					(thickness 0.15)
				)
			)
		)
		(property "Val" "10R"
			(at 0 0 90)
			(unlocked yes)
			(layer "F.Fab")
			(hide yes)
			(effects
				(font
					(size 1 1)
					(thickness 0.15)
				)
			)
		)
		(property "Tolerance" "1%"
			(at 0 0 90)
			(unlocked yes)
			(layer "F.Fab")
			(hide yes)
			(effects
				(font
					(size 1 1)
					(thickness 0.15)
				)
			)
		)
		(sheetname "/X710-AT2 10GbE/")
		(sheetfile "x710-at2-10gbe.kicad_sch")
		(attr smd)
		(fp_rect
			(start -0.925 -0.47)
			(end 0.925 0.47)
			(stroke
				(width 0.05)
				(type default)
			)
			(fill no)
			(layer "F.CrtYd")
		)
		(fp_rect
			(start -0.5 -0.25)
			(end 0.5 0.25)
			(stroke
				(width 0.15)
				(type solid)
			)
			(fill no)
			(layer "F.Fab")
		)
		(fp_text user "${REFERENCE}"
			(at -0.95 3.168 90)
			(layer "F.Fab")
			(effects
				(font
					(size 0.7 0.7)
					(thickness 0.15)
				)
				(justify left bottom)
			)
		)
		(fp_text user "License: Apache-2.0"
			(at -0.95 5.169 90)
			(layer "F.Fab")
			(effects
				(font
					(size 0.7 0.7)
					(thickness 0.15)
				)
				(justify left bottom)
			)
		)
		(fp_text user "Author: Antmicro"
			(at -0.95 4.169 90)
			(layer "F.Fab")
			(effects
				(font
					(size 0.7 0.7)
					(thickness 0.15)
				)
				(justify left bottom)
			)
		)
		(pad "1" smd roundrect
			(at -0.48 0 90)
			(size 0.59 0.64)
			(layers "F.Cu" "F.Mask" "F.Paste")
			(roundrect_rratio 0.25)
			(net 122 "/X710-AT2 10GbE/MDIO0_I2C0.MDIO")
			(pintype "passive")
		)
		(pad "2" smd roundrect
			(at 0.48 0 90)
			(size 0.59 0.64)
			(layers "F.Cu" "F.Mask" "F.Paste")
			(roundrect_rratio 0.25)
			(net 102 "/X710-AT2 10GbE/MDIO0_SDA0")
			(pintype "passive")
		)
	)
	(footprint "antmicro-footprints:Mech_Lightpipe_Mentor_1271.1001"
		(layer "F.Cu")
		(at 135 147.813534 180)
		(descr "1x1  Horizontal Light Guide with transparent pipe")
		(tags "Horizontal, THT, MECHANICAL, MODULE")
		(property "Reference" "H3"
			(at 1.85 -3.386466 0)
			(unlocked yes)
			(layer "F.SilkS")
			(effects
				(font
					(size 0.7 0.7)
					(thickness 0.15)
				)
				(justify left bottom)
			)
		)
		(property "Value" "Lightpipe_Mentor_1271.1001"
			(at 0 9 180)
			(unlocked yes)
			(layer "F.Fab")
			(effects
				(font
					(size 0.7 0.7)
					(thickness 0.15)
				)
				(justify left bottom)
			)
		)
		(property "Datasheet" "https://www.mentor.de.com/productpdfs/ll/ll14-20.pdf"
			(at 0 0 180)
			(layer "F.Fab")
			(hide yes)
			(effects
				(font
					(size 1.27 1.27)
					(thickness 0.15)
				)
			)
		)
		(property "Description" "Light Pipe, 14.45 mm, 1 Pipe, Circular, PC Board, Transparent"
			(at 0 0 180)
			(layer "F.Fab")
			(hide yes)
			(effects
				(font
					(size 1.27 1.27)
					(thickness 0.15)
				)
			)
		)
		(property "MPN" "1271.1001"
			(at 0 0 180)
			(unlocked yes)
			(layer "F.Fab")
			(hide yes)
			(effects
				(font
					(size 1 1)
					(thickness 0.15)
				)
			)
		)
		(property "Manufacturer" "Mentor Worldwide"
			(at 0 0 180)
			(unlocked yes)
			(layer "F.Fab")
			(hide yes)
			(effects
				(font
					(size 1 1)
					(thickness 0.15)
				)
			)
		)
		(property "Author" "Antmicro"
			(at 0 0 180)
			(unlocked yes)
			(layer "F.Fab")
			(hide yes)
			(effects
				(font
					(size 1 1)
					(thickness 0.15)
				)
			)
		)
		(property "License" "Apache-2.0"
			(at 0 0 180)
			(unlocked yes)
			(layer "F.Fab")
			(hide yes)
			(effects
				(font
					(size 1 1)
					(thickness 0.15)
				)
			)
		)
		(sheetname "/")
		(sheetfile "thunderbolt-to-10gbe-adapter.kicad_sch")
		(attr through_hole)
		(fp_rect
			(start -1.55 -2.1)
			(end 1.55 1.3)
			(stroke
				(width 0.05)
				(type solid)
			)
			(fill no)
			(layer "F.SilkS")
		)
		(fp_rect
			(start -1.75 -2.3)
			(end 1.75 1.475)
			(stroke
				(width 0.05)
				(type solid)
			)
			(fill no)
			(layer "F.CrtYd")
		)
		(fp_rect
			(start -1.4732 -8.128)
			(end 1.4732 6.2484)
			(stroke
				(width 0.15)
				(type solid)
			)
			(fill no)
			(layer "F.Fab")
		)
		(fp_text user "License: Apache-2.0"
			(at -1.8 11.7 180)
			(layer "F.Fab")
			(effects
				(font
					(size 0.7 0.7)
					(thickness 0.15)
				)
				(justify left bottom)
			)
		)
		(fp_text user "Author: Antmicro"
			(at -1.8 10.5 180)
			(layer "F.Fab")
			(effects
				(font
					(size 0.7 0.7)
					(thickness 0.15)
				)
				(justify left bottom)
			)
		)
		(fp_text user "${REFERENCE}"
			(at -1.8 12.9 180)
			(layer "F.Fab")
			(effects
				(font
					(size 0.7 0.7)
					(thickness 0.15)
				)
				(justify left bottom)
			)
		)
		(pad "" np_thru_hole circle
			(at 0 0 180)
			(size 2.3 2.3)
			(drill 2.3)
			(layers "*.Cu" "*.Mask")
		)
	)
	(footprint "antmicro-footprints:R_0402_1005Metric"
		(layer "F.Cu")
		(at 136.15 113.15)
		(descr "Resistor SMD 0402")
		(tags "resistor SMD 0402")
		(property "Reference" "R92"
			(at 16.549997 17.25 0)
			(layer "F.SilkS")
			(effects
				(font
					(size 0.7 0.7)
					(thickness 0.15)
				)
			)
		)
		(property "Value" "R_0R_0402"
			(at -1.011843 1.772047 0)
			(layer "F.Fab")
			(effects
				(font
					(size 0.7 0.7)
					(thickness 0.15)
				)
				(justify left bottom)
			)
		)
		(property "Datasheet" "https://industrial.panasonic.com/cdbs/www-data/pdf/RDA0000/AOA0000C301.pdf"
			(at 0 0 0)
			(layer "F.Fab")
			(hide yes)
			(effects
				(font
					(size 1.27 1.27)
					(thickness 0.15)
				)
			)
		)
		(property "Description" "SMD Chip Resistor, Jumper, 0 ohm, 100 mW, 0402 [1005 Metric], Thick Film, General Purpose"
			(at 0 0 0)
			(layer "F.Fab")
			(hide yes)
			(effects
				(font
					(size 1.27 1.27)
					(thickness 0.15)
				)
			)
		)
		(property "MPN" "ERJ2GE0R00X"
			(at 0 0 0)
			(unlocked yes)
			(layer "F.Fab")
			(hide yes)
			(effects
				(font
					(size 1 1)
					(thickness 0.15)
				)
			)
		)
		(property "Manufacturer" "Panasonic"
			(at 0 0 0)
			(unlocked yes)
			(layer "F.Fab")
			(hide yes)
			(effects
				(font
					(size 1 1)
					(thickness 0.15)
				)
			)
		)
		(property "License" "Apache-2.0"
			(at 0 0 0)
			(unlocked yes)
			(layer "F.Fab")
			(hide yes)
			(effects
				(font
					(size 1 1)
					(thickness 0.15)
				)
			)
		)
		(property "Author" "Antmicro"
			(at 0 0 0)
			(unlocked yes)
			(layer "F.Fab")
			(hide yes)
			(effects
				(font
					(size 1 1)
					(thickness 0.15)
				)
			)
		)
		(property "Val" "0R"
			(at 0 0 0)
			(unlocked yes)
			(layer "F.Fab")
			(hide yes)
			(effects
				(font
					(size 1 1)
					(thickness 0.15)
				)
			)
		)
		(property "Tolerance" "~"
			(at 0 0 0)
			(unlocked yes)
			(layer "F.Fab")
			(hide yes)
			(effects
				(font
					(size 1 1)
					(thickness 0.15)
				)
			)
		)
		(property "Current" "1A"
			(at 0 0 0)
			(unlocked yes)
			(layer "F.Fab")
			(hide yes)
			(effects
				(font
					(size 1 1)
					(thickness 0.15)
				)
			)
		)
		(sheetname "/X710 DCDC converters/")
		(sheetfile "DCDC_converters_X710.kicad_sch")
		(attr smd)
		(fp_rect
			(start -0.925 -0.47)
			(end 0.925 0.47)
			(stroke
				(width 0.05)
				(type default)
			)
			(fill no)
			(layer "F.CrtYd")
		)
		(fp_rect
			(start -0.5 -0.25)
			(end 0.5 0.25)
			(stroke
				(width 0.15)
				(type solid)
			)
			(fill no)
			(layer "F.Fab")
		)
		(fp_text user "Author: Antmicro"
			(at -0.95 4.169 0)
			(layer "F.Fab")
			(effects
				(font
					(size 0.7 0.7)
					(thickness 0.15)
				)
				(justify left bottom)
			)
		)
		(fp_text user "License: Apache-2.0"
			(at -0.95 5.169 0)
			(layer "F.Fab")
			(effects
				(font
					(size 0.7 0.7)
					(thickness 0.15)
				)
				(justify left bottom)
			)
		)
		(fp_text user "${REFERENCE}"
			(at -0.95 3.168 0)
			(layer "F.Fab")
			(effects
				(font
					(size 0.7 0.7)
					(thickness 0.15)
				)
				(justify left bottom)
			)
		)
		(pad "1" smd roundrect
			(at -0.48 0)
			(size 0.59 0.64)
			(layers "F.Cu" "F.Mask" "F.Paste")
			(roundrect_rratio 0.25)
			(net 378 "/X710 DCDC converters/3V3_PG")
			(pintype "passive")
		)
		(pad "2" smd roundrect
			(at 0.48 0)
			(size 0.59 0.64)
			(layers "F.Cu" "F.Mask" "F.Paste")
			(roundrect_rratio 0.25)
			(net 382 "/X710 DCDC converters/VCCD_EN")
			(pintype "passive")
		)
	)
	(footprint "antmicro-footprints:C_0805_2012Metric"
		(layer "F.Cu")
		(at 152.95 56.8 -90)
		(descr "Capacitor SMD 0805")
		(tags "capacitor SMD 0805")
		(property "Reference" "C321"
			(at 4.6 -0.65 270)
			(layer "F.SilkS")
			(effects
				(font
					(size 0.7 0.7)
					(thickness 0.15)
				)
				(justify left bottom)
			)
		)
		(property "Value" "C_22u_25V_0805"
			(at -2.055717 1.963152 270)
			(layer "F.Fab")
			(effects
				(font
					(size 0.7 0.7)
					(thickness 0.15)
				)
				(justify left bottom)
			)
		)
		(property "Datasheet" "https://product.samsungsem.com/mlcc/CL21A226MAYNNN.do"
			(at 0 0 270)
			(layer "F.Fab")
			(hide yes)
			(effects
				(font
					(size 1.27 1.27)
					(thickness 0.15)
				)
			)
		)
		(property "Description" "SMT Multilayer Ceramic Capacitor, 22uF, +/-20%, 25V, X5R, 0805 [2012 Metric]"
			(at 0 0 270)
			(layer "F.Fab")
			(hide yes)
			(effects
				(font
					(size 1.27 1.27)
					(thickness 0.15)
				)
			)
		)
		(property "MPN" "CL21A226MAYNNNE"
			(at 0 0 270)
			(unlocked yes)
			(layer "F.Fab")
			(hide yes)
			(effects
				(font
					(size 1 1)
					(thickness 0.15)
				)
			)
		)
		(property "Manufacturer" "Samsung Electro-Mechanics"
			(at 0 0 270)
			(unlocked yes)
			(layer "F.Fab")
			(hide yes)
			(effects
				(font
					(size 1 1)
					(thickness 0.15)
				)
			)
		)
		(property "License" "Apache-2.0"
			(at 0 0 270)
			(unlocked yes)
			(layer "F.Fab")
			(hide yes)
			(effects
				(font
					(size 1 1)
					(thickness 0.15)
				)
			)
		)
		(property "Author" "Antmicro"
			(at 0 0 270)
			(unlocked yes)
			(layer "F.Fab")
			(hide yes)
			(effects
				(font
					(size 1 1)
					(thickness 0.15)
				)
			)
		)
		(property "Val" "22u"
			(at 0 0 270)
			(unlocked yes)
			(layer "F.Fab")
			(hide yes)
			(effects
				(font
					(size 1 1)
					(thickness 0.15)
				)
			)
		)
		(property "Voltage" "25V"
			(at 0 0 270)
			(unlocked yes)
			(layer "F.Fab")
			(hide yes)
			(effects
				(font
					(size 1 1)
					(thickness 0.15)
				)
			)
		)
		(property "Dielectric" "X5R"
			(at 0 0 270)
			(unlocked yes)
			(layer "F.Fab")
			(hide yes)
			(effects
				(font
					(size 1 1)
					(thickness 0.15)
				)
			)
		)
		(property "Public" "False"
			(at 0 0 270)
			(unlocked yes)
			(layer "F.Fab")
			(hide yes)
			(effects
				(font
					(size 1 1)
					(thickness 0.15)
				)
			)
		)
		(sheetname "/Power input/")
		(sheetfile "power_input.kicad_sch")
		(attr smd)
		(fp_line
			(start -0.3 0.7)
			(end 0.3 0.7)
			(stroke
				(width 0.15)
				(type solid)
			)
			(layer "F.SilkS")
		)
		(fp_line
			(start -0.3 -0.7)
			(end 0.3 -0.7)
			(stroke
				(width 0.15)
				(type solid)
			)
			(layer "F.SilkS")
		)
		(fp_rect
			(start 1.95 -0.9)
			(end -1.95 0.9)
			(stroke
				(width 0.05)
				(type default)
			)
			(fill no)
			(layer "F.CrtYd")
		)
		(fp_rect
			(start -0.95 -0.675)
			(end 0.95 0.675)
			(stroke
				(width 0.15)
				(type solid)
			)
			(fill no)
			(layer "F.Fab")
		)
		(fp_text user "${REFERENCE}"
			(at -1.9 3.947 270)
			(layer "F.Fab")
			(effects
				(font
					(size 0.7 0.7)
					(thickness 0.15)
				)
				(justify left bottom)
			)
		)
		(fp_text user "License: Apache-2.0"
			(at -1.9 4.947 270)
			(layer "F.Fab")
			(effects
				(font
					(size 0.7 0.7)
					(thickness 0.15)
				)
				(justify left bottom)
			)
		)
		(fp_text user "Author: Antmicro"
			(at -1.9 5.947 270)
			(layer "F.Fab")
			(effects
				(font
					(size 0.7 0.7)
					(thickness 0.15)
				)
				(justify left bottom)
			)
		)
		(pad "1" smd roundrect
			(at -1.1 0 270)
			(size 1.2 1.3)
			(layers "F.Cu" "F.Mask" "F.Paste")
			(roundrect_rratio 0.25)
			(net 23 "GND")
			(pintype "passive")
		)
		(pad "2" smd roundrect
			(at 1.1 0 270)
			(size 1.2 1.3)
			(layers "F.Cu" "F.Mask" "F.Paste")
			(roundrect_rratio 0.25)
			(net 349 "/Power input/5V_OUT")
			(pintype "passive")
		)
	)
	(footprint "antmicro-footprints:L_Bourns-SRP4021HMT"
		(layer "F.Cu")
		(at 154.850001 106.000001 -90)
		(property "Reference" "L6"
			(at 17.549996 -13.650003 270)
			(layer "F.SilkS")
			(effects
				(font
					(size 0.7 0.7)
					(thickness 0.15)
				)
			)
		)
		(property "Value" "L_1u_10A_Bourns-SRP4021HMT"
			(at -2.85 3.4 270)
			(layer "F.Fab")
			(effects
				(font
					(size 0.7 0.7)
					(thickness 0.15)
				)
				(justify left bottom)
			)
		)
		(property "Datasheet" "https://www.mouser.com/datasheet/2/54/Bourns_04_01_2025_SRP4021HMT_Datasheet-3580094.pdf"
			(at 0 0 270)
			(layer "F.Fab")
			(effects
				(font
					(size 0.7 0.7)
					(thickness 0.15)
				)
				(justify left bottom)
			)
		)
		(property "Description" "Power Inductors - SMD Ind,4.1x4.2x1.9mm,1uH+/-20%,10A, Shielded"
			(at 0 0 270)
			(layer "F.Fab")
			(effects
				(font
					(size 0.7 0.7)
					(thickness 0.15)
				)
				(justify left bottom)
			)
		)
		(property "Val" "1u/10A"
			(at 0 0 270)
			(unlocked yes)
			(layer "F.Fab")
			(hide yes)
			(effects
				(font
					(size 1 1)
					(thickness 0.15)
				)
			)
		)
		(property "Manufacturer" "Bourns"
			(at 0 0 270)
			(unlocked yes)
			(layer "F.Fab")
			(hide yes)
			(effects
				(font
					(size 1 1)
					(thickness 0.15)
				)
			)
		)
		(property "MPN" "SRP4021HMT-1R0M"
			(at 0 0 270)
			(unlocked yes)
			(layer "F.Fab")
			(hide yes)
			(effects
				(font
					(size 1 1)
					(thickness 0.15)
				)
			)
		)
		(property "ISat" ""
			(at 0 0 270)
			(unlocked yes)
			(layer "F.Fab")
			(hide yes)
			(effects
				(font
					(size 1 1)
					(thickness 0.15)
				)
			)
		)
		(property "Isat" "8A"
			(at 0 0 270)
			(unlocked yes)
			(layer "F.Fab")
			(hide yes)
			(effects
				(font
					(size 1 1)
					(thickness 0.15)
				)
			)
		)
		(property "IMax" ""
			(at 0 0 270)
			(unlocked yes)
			(layer "F.Fab")
			(hide yes)
			(effects
				(font
					(size 1 1)
					(thickness 0.15)
				)
			)
		)
		(property "Imax" "10A"
			(at 0 0 270)
			(unlocked yes)
			(layer "F.Fab")
			(hide yes)
			(effects
				(font
					(size 1 1)
					(thickness 0.15)
				)
			)
		)
		(property "Size" "4.2x4.1"
			(at 0 0 270)
			(unlocked yes)
			(layer "F.Fab")
			(hide yes)
			(effects
				(font
					(size 1 1)
					(thickness 0.15)
				)
			)
		)
		(property "Author" "Antmicro"
			(at 0 0 270)
			(unlocked yes)
			(layer "F.Fab")
			(hide yes)
			(effects
				(font
					(size 1 1)
					(thickness 0.15)
				)
			)
		)
		(property "License" "Apache-2.0"
			(at 0 0 270)
			(unlocked yes)
			(layer "F.Fab")
			(hide yes)
			(effects
				(font
					(size 1 1)
					(thickness 0.15)
				)
			)
		)
		(sheetname "/X710 DCDC converters/")
		(sheetfile "DCDC_converters_X710.kicad_sch")
		(attr smd)
		(fp_line
			(start -0.8 2.05)
			(end 0.8 2.05)
			(stroke
				(width 0.15)
				(type solid)
			)
			(layer "F.SilkS")
		)
		(fp_line
			(start -0.8 -2.05)
			(end 0.8 -2.05)
			(stroke
				(width 0.15)
				(type solid)
			)
			(layer "F.SilkS")
		)
		(fp_rect
			(start -2.85 -2.3)
			(end 2.85 2.3)
			(stroke
				(width 0.05)
				(type solid)
			)
			(fill no)
			(layer "F.CrtYd")
		)
		(fp_rect
			(start -2 -2.05)
			(end 2 2.05)
			(stroke
				(width 0.15)
				(type solid)
			)
			(fill no)
			(layer "F.Fab")
		)
		(fp_text user "${REFERENCE}"
			(at -2.85 5.8 270)
			(layer "F.Fab")
			(effects
				(font
					(size 0.7 0.7)
					(thickness 0.15)
				)
				(justify left bottom)
			)
		)
		(fp_text user "License: Apache-2.0"
			(at -2.85 7 270)
			(layer "F.Fab")
			(effects
				(font
					(size 0.7 0.7)
					(thickness 0.15)
				)
				(justify left bottom)
			)
		)
		(fp_text user "Author: Antmicro"
			(at -2.85 4.6 270)
			(layer "F.Fab")
			(effects
				(font
					(size 0.7 0.7)
					(thickness 0.15)
				)
				(justify left bottom)
			)
		)
		(pad "1" smd rect
			(at 1.85 0 90)
			(size 1.5 3.5)
			(layers "F.Cu" "F.Mask" "F.Paste")
			(net 241 "/X710 DCDC converters/1V88_SW")
			(pintype "passive")
		)
		(pad "2" smd rect
			(at -1.85 0 90)
			(size 1.5 3.5)
			(layers "F.Cu" "F.Mask" "F.Paste")
			(net 338 "/X710 DCDC converters/+1V88_OUT")
			(pintype "passive")
		)
	)
	(footprint "antmicro-footprints:C_0402_1005Metric"
		(layer "F.Cu")
		(at 134.85 129.15 -90)
		(descr "Capacitor SMD 0402")
		(tags "capacitor SMD 0402")
		(property "Reference" "C102"
			(at -0.450004 -7.15 270)
			(layer "F.SilkS")
			(effects
				(font
					(size 0.7 0.7)
					(thickness 0.15)
				)
				(justify left bottom)
			)
		)
		(property "Value" "C_10u_0402"
			(at -1.022927 2.155213 270)
			(layer "F.Fab")
			(effects
				(font
					(size 0.7 0.7)
					(thickness 0.15)
				)
				(justify left bottom)
			)
		)
		(property "Datasheet" "https://www.yageo.com/en/Chart/Download/pdf/CC0402MRX5R5BB106"
			(at 0 0 270)
			(layer "F.Fab")
			(hide yes)
			(effects
				(font
					(size 1.27 1.27)
					(thickness 0.15)
				)
			)
		)
		(property "Description" "SMD Multilayer Ceramic Capacitor, 10 µF, 6.3 V, 0402 [1005 Metric], ± 20%, X5R, CC Series"
			(at 0 0 270)
			(layer "F.Fab")
			(hide yes)
			(effects
				(font
					(size 1.27 1.27)
					(thickness 0.15)
				)
			)
		)
		(property "MPN" "CC0402MRX5R5BB106"
			(at 0 0 270)
			(unlocked yes)
			(layer "F.Fab")
			(hide yes)
			(effects
				(font
					(size 1 1)
					(thickness 0.15)
				)
			)
		)
		(property "Manufacturer" "YAGEO"
			(at 0 0 270)
			(unlocked yes)
			(layer "F.Fab")
			(hide yes)
			(effects
				(font
					(size 1 1)
					(thickness 0.15)
				)
			)
		)
		(property "License" "Apache-2.0"
			(at 0 0 270)
			(unlocked yes)
			(layer "F.Fab")
			(hide yes)
			(effects
				(font
					(size 1 1)
					(thickness 0.15)
				)
			)
		)
		(property "Val" "10u"
			(at 0 0 270)
			(unlocked yes)
			(layer "F.Fab")
			(hide yes)
			(effects
				(font
					(size 1 1)
					(thickness 0.15)
				)
			)
		)
		(property "Voltage" ""
			(at 0 0 270)
			(unlocked yes)
			(layer "F.Fab")
			(hide yes)
			(effects
				(font
					(size 1 1)
					(thickness 0.15)
				)
			)
		)
		(property "Dielectric" ""
			(at 0 0 270)
			(unlocked yes)
			(layer "F.Fab")
			(hide yes)
			(effects
				(font
					(size 1 1)
					(thickness 0.15)
				)
			)
		)
		(property "Author" "Antmicro"
			(at 0 0 270)
			(unlocked yes)
			(layer "F.Fab")
			(hide yes)
			(effects
				(font
					(size 1 1)
					(thickness 0.15)
				)
			)
		)
		(sheetname "/TB Controller - Power/")
		(sheetfile "tb-power.kicad_sch")
		(attr smd)
		(fp_rect
			(start -0.925 -0.47)
			(end 0.925 0.47)
			(stroke
				(width 0.05)
				(type default)
			)
			(fill no)
			(layer "F.CrtYd")
		)
		(fp_line
			(start -0.494 0.248)
			(end -0.494 -0.25)
			(stroke
				(width 0.15)
				(type solid)
			)
			(layer "F.Fab")
		)
		(fp_line
			(start 0.504 0.248)
			(end -0.494 0.248)
			(stroke
				(width 0.15)
				(type solid)
			)
			(layer "F.Fab")
		)
		(fp_line
			(start -0.494 -0.25)
			(end 0.504 -0.25)
			(stroke
				(width 0.15)
				(type solid)
			)
			(layer "F.Fab")
		)
		(fp_line
			(start 0.504 -0.25)
			(end 0.504 0.248)
			(stroke
				(width 0.15)
				(type solid)
			)
			(layer "F.Fab")
		)
		(fp_text user "Author: Antmicro"
			(at -0.939 3.399 270)
			(layer "F.Fab")
			(effects
				(font
					(size 0.7 0.7)
					(thickness 0.15)
				)
				(justify left bottom)
			)
		)
		(fp_text user "License: Apache-2.0"
			(at -0.939 5.799 270)
			(layer "F.Fab")
			(effects
				(font
					(size 0.7 0.7)
					(thickness 0.15)
				)
				(justify left bottom)
			)
		)
		(fp_text user "${REFERENCE}"
			(at -0.939 4.599 270)
			(layer "F.Fab")
			(effects
				(font
					(size 0.7 0.7)
					(thickness 0.15)
				)
				(justify left bottom)
			)
		)
		(pad "1" smd roundrect
			(at -0.48 0 270)
			(size 0.59 0.64)
			(layers "F.Cu" "F.Mask" "F.Paste")
			(roundrect_rratio 0.25)
			(net 23 "GND")
			(pintype "passive")
		)
		(pad "2" smd roundrect
			(at 0.48 0 270)
			(size 0.59 0.64)
			(layers "F.Cu" "F.Mask" "F.Paste")
			(roundrect_rratio 0.25)
			(net 57 "+3V3_TB")
			(pintype "passive")
		)
	)
	(footprint "antmicro-footprints:R_0402_1005Metric"
		(layer "F.Cu")
		(at 117.4 138.72 -90)
		(descr "Resistor SMD 0402")
		(tags "resistor SMD 0402")
		(property "Reference" "R2"
			(at 1.03 -2.6 270)
			(layer "F.SilkS")
			(effects
				(font
					(size 0.7 0.7)
					(thickness 0.15)
				)
				(justify left bottom)
			)
		)
		(property "Value" "R_470R_0402"
			(at -1.011843 1.772047 270)
			(layer "F.Fab")
			(effects
				(font
					(size 0.7 0.7)
					(thickness 0.15)
				)
				(justify left bottom)
			)
		)
		(property "Datasheet" "https://www.bourns.com/docs/product-datasheets/cr.pdf"
			(at 0 0 270)
			(layer "F.Fab")
			(hide yes)
			(effects
				(font
					(size 1.27 1.27)
					(thickness 0.15)
				)
			)
		)
		(property "Description" "SMD Chip Resistor, 470 ohm, ± 1%, 62.5 mW, 0402 [1005 Metric], Thick Film, General Purpose"
			(at 0 0 270)
			(layer "F.Fab")
			(hide yes)
			(effects
				(font
					(size 1.27 1.27)
					(thickness 0.15)
				)
			)
		)
		(property "MPN" "CR0402-FX-4700GLF"
			(at 0 0 270)
			(unlocked yes)
			(layer "F.Fab")
			(hide yes)
			(effects
				(font
					(size 1 1)
					(thickness 0.15)
				)
			)
		)
		(property "Manufacturer" "Bourns"
			(at 0 0 270)
			(unlocked yes)
			(layer "F.Fab")
			(hide yes)
			(effects
				(font
					(size 1 1)
					(thickness 0.15)
				)
			)
		)
		(property "License" "Apache-2.0"
			(at 0 0 270)
			(unlocked yes)
			(layer "F.Fab")
			(hide yes)
			(effects
				(font
					(size 1 1)
					(thickness 0.15)
				)
			)
		)
		(property "Author" "Antmicro"
			(at 0 0 270)
			(unlocked yes)
			(layer "F.Fab")
			(hide yes)
			(effects
				(font
					(size 1 1)
					(thickness 0.15)
				)
			)
		)
		(property "Val" "470R"
			(at 0 0 270)
			(unlocked yes)
			(layer "F.Fab")
			(hide yes)
			(effects
				(font
					(size 1 1)
					(thickness 0.15)
				)
			)
		)
		(property "Tolerance" "1%"
			(at 0 0 270)
			(unlocked yes)
			(layer "F.Fab")
			(hide yes)
			(effects
				(font
					(size 1 1)
					(thickness 0.15)
				)
			)
		)
		(sheetname "/USB-C connector/")
		(sheetfile "USB-C_connector.kicad_sch")
		(attr smd)
		(fp_rect
			(start -0.925 -0.47)
			(end 0.925 0.47)
			(stroke
				(width 0.05)
				(type default)
			)
			(fill no)
			(layer "F.CrtYd")
		)
		(fp_rect
			(start -0.5 -0.25)
			(end 0.5 0.25)
			(stroke
				(width 0.15)
				(type solid)
			)
			(fill no)
			(layer "F.Fab")
		)
		(fp_text user "License: Apache-2.0"
			(at -0.95 5.169 270)
			(layer "F.Fab")
			(effects
				(font
					(size 0.7 0.7)
					(thickness 0.15)
				)
				(justify left bottom)
			)
		)
		(fp_text user "Author: Antmicro"
			(at -0.95 4.169 270)
			(layer "F.Fab")
			(effects
				(font
					(size 0.7 0.7)
					(thickness 0.15)
				)
				(justify left bottom)
			)
		)
		(fp_text user "${REFERENCE}"
			(at -0.95 3.168 270)
			(layer "F.Fab")
			(effects
				(font
					(size 0.7 0.7)
					(thickness 0.15)
				)
				(justify left bottom)
			)
		)
		(pad "1" smd roundrect
			(at -0.48 0 270)
			(size 0.59 0.64)
			(layers "F.Cu" "F.Mask" "F.Paste")
			(roundrect_rratio 0.25)
			(net 164 "Net-(D2-A)")
			(pintype "passive")
		)
		(pad "2" smd roundrect
			(at 0.48 0 270)
			(size 0.59 0.64)
			(layers "F.Cu" "F.Mask" "F.Paste")
			(roundrect_rratio 0.25)
			(net 53 "+5V_USB")
			(pintype "passive")
		)
	)
	(footprint "antmicro-footprints:SOIC-8_3.9x4.9x1.75mm_P1.27mm"
		(layer "F.Cu")
		(at 147.8 122.2 90)
		(property "Reference" "U7"
			(at 4.7 4 90)
			(layer "F.SilkS")
			(effects
				(font
					(size 0.7 0.7)
					(thickness 0.15)
				)
				(justify left bottom)
			)
		)
		(property "Value" "MX25L8006EM1I-12G"
			(at 0 3.65 90)
			(layer "F.Fab")
			(effects
				(font
					(size 0.7 0.7)
					(thickness 0.15)
				)
				(justify left bottom)
			)
		)
		(property "Datasheet" "https://www.macronix.com/Lists/Datasheet/Attachments/8680/MX25L8006E,%203V,%208Mb,%20v1.6.pdf"
			(at 0 0 90)
			(layer "F.Fab")
			(hide yes)
			(effects
				(font
					(size 1.27 1.27)
					(thickness 0.15)
				)
			)
		)
		(property "Description" "FLASH - NOR Memory IC 8Mbit SPI 86 MHz 8-SOP"
			(at 0 0 90)
			(layer "F.Fab")
			(hide yes)
			(effects
				(font
					(size 1.27 1.27)
					(thickness 0.15)
				)
			)
		)
		(property "MPN" "MX25L8006EM1I-12G"
			(at 0 0 90)
			(unlocked yes)
			(layer "F.Fab")
			(hide yes)
			(effects
				(font
					(size 1 1)
					(thickness 0.15)
				)
			)
		)
		(property "Manufacturer" "Macronix"
			(at 0 0 90)
			(unlocked yes)
			(layer "F.Fab")
			(hide yes)
			(effects
				(font
					(size 1 1)
					(thickness 0.15)
				)
			)
		)
		(property "License" "Apache-2.0"
			(at 0 0 90)
			(unlocked yes)
			(layer "F.Fab")
			(hide yes)
			(effects
				(font
					(size 1 1)
					(thickness 0.15)
				)
			)
		)
		(property "Author" "Antmicro"
			(at 0 0 90)
			(unlocked yes)
			(layer "F.Fab")
			(hide yes)
			(effects
				(font
					(size 1 1)
					(thickness 0.15)
				)
			)
		)
		(sheetname "/TB flash memory/")
		(sheetfile "flash-memory.kicad_sch")
		(attr smd)
		(fp_line
			(start -1.95 -2.452)
			(end 1.95 -2.45)
			(stroke
				(width 0.15)
				(type solid)
			)
			(layer "F.SilkS")
		)
		(fp_line
			(start -1.95 2.45)
			(end 1.95 2.45)
			(stroke
				(width 0.15)
				(type solid)
			)
			(layer "F.SilkS")
		)
		(fp_circle
			(center -2.4 -2.45)
			(end -2.35 -2.4)
			(stroke
				(width 0.15)
				(type solid)
			)
			(fill yes)
			(layer "F.SilkS")
		)
		(fp_rect
			(start -3.625 -2.7)
			(end 3.625 2.7)
			(stroke
				(width 0.05)
				(type solid)
			)
			(fill no)
			(layer "F.CrtYd")
		)
		(fp_line
			(start 1.949 -2.452)
			(end 1.949 2.45)
			(stroke
				(width 0.15)
				(type solid)
			)
			(layer "F.Fab")
		)
		(fp_line
			(start -0.683 -2.452)
			(end 1.949 -2.452)
			(stroke
				(width 0.15)
				(type solid)
			)
			(layer "F.Fab")
		)
		(fp_line
			(start -1.95 -1.18)
			(end -0.683 -2.452)
			(stroke
				(width 0.15)
				(type solid)
			)
			(layer "F.Fab")
		)
		(fp_line
			(start 1.949 2.45)
			(end -1.95 2.45)
			(stroke
				(width 0.15)
				(type solid)
			)
			(layer "F.Fab")
		)
		(fp_line
			(start -1.95 2.45)
			(end -1.95 -1.18)
			(stroke
				(width 0.15)
				(type solid)
			)
			(layer "F.Fab")
		)
		(fp_text user "${REFERENCE}"
			(at -3.476 7.099 90)
			(layer "F.Fab")
			(effects
				(font
					(size 0.7 0.7)
					(thickness 0.15)
				)
				(justify left bottom)
			)
		)
		(fp_text user "Author: Antmicro"
			(at -3.476 6.099 90)
			(layer "F.Fab")
			(effects
				(font
					(size 0.7 0.7)
					(thickness 0.15)
				)
				(justify left bottom)
			)
		)
		(fp_text user "License: Apache-2.0"
			(at -3.476 5.099 90)
			(layer "F.Fab")
			(effects
				(font
					(size 0.7 0.7)
					(thickness 0.15)
				)
				(justify left bottom)
			)
		)
		(pad "1" smd roundrect
			(at -2.714 -1.905 180)
			(size 0.65 1.525)
			(layers "F.Cu" "F.Mask" "F.Paste")
			(roundrect_rratio 0.25)
			(net 359 "/PD and TB DC-DC/TB_FLASH.~{CE}")
			(pinfunction "~{CS}")
			(pintype "input")
		)
		(pad "2" smd roundrect
			(at -2.714 -0.635 180)
			(size 0.65 1.525)
			(layers "F.Cu" "F.Mask" "F.Paste")
			(roundrect_rratio 0.25)
			(net 357 "/PD and TB DC-DC/TB_FLASH.MISO")
			(pinfunction "SO/IO1")
			(pintype "input")
		)
		(pad "3" smd roundrect
			(at -2.714 0.632 180)
			(size 0.65 1.525)
			(layers "F.Cu" "F.Mask" "F.Paste")
			(roundrect_rratio 0.25)
			(net 358 "/TB flash memory/FLASH_WP")
			(pinfunction "~{WP}")
			(pintype "input")
		)
		(pad "4" smd roundrect
			(at -2.714 1.902 180)
			(size 0.65 1.525)
			(layers "F.Cu" "F.Mask" "F.Paste")
			(roundrect_rratio 0.25)
			(net 23 "GND")
			(pinfunction "GND")
			(pintype "power_in")
		)
		(pad "5" smd roundrect
			(at 2.712 1.902 180)
			(size 0.65 1.525)
			(layers "F.Cu" "F.Mask" "F.Paste")
			(roundrect_rratio 0.25)
			(net 398 "/PD and TB DC-DC/TB_FLASH.MOSI")
			(pinfunction "SI/IO0")
			(pintype "input")
		)
		(pad "6" smd roundrect
			(at 2.712 0.632 180)
			(size 0.65 1.525)
			(layers "F.Cu" "F.Mask" "F.Paste")
			(roundrect_rratio 0.25)
			(net 397 "/PD and TB DC-DC/TB_FLASH.CLK")
			(pinfunction "SCLK")
			(pintype "input")
		)
		(pad "7" smd roundrect
			(at 2.712 -0.635 180)
			(size 0.65 1.525)
			(layers "F.Cu" "F.Mask" "F.Paste")
			(roundrect_rratio 0.25)
			(net 370 "/TB flash memory/FLASH_HOLD")
			(pinfunction "~{HOLD}")
			(pintype "input")
		)
		(pad "8" smd roundrect
			(at 2.712 -1.905 180)
			(size 0.65 1.525)
			(layers "F.Cu" "F.Mask" "F.Paste")
			(roundrect_rratio 0.25)
			(net 57 "+3V3_TB")
			(pinfunction "VCC")
			(pintype "power_in")
		)
	)
	(footprint "antmicro-footprints:R_0402_1005Metric"
		(layer "F.Cu")
		(at 132.8 71.4 180)
		(descr "Resistor SMD 0402")
		(tags "resistor SMD 0402")
		(property "Reference" "R224"
			(at 0.8 2 180)
			(layer "F.SilkS")
			(effects
				(font
					(size 0.7 0.7)
					(thickness 0.15)
				)
				(justify left bottom)
			)
		)
		(property "Value" "R_10k_0402"
			(at -1.011843 1.772047 180)
			(layer "F.Fab")
			(effects
				(font
					(size 0.7 0.7)
					(thickness 0.15)
				)
				(justify left bottom)
			)
		)
		(property "Datasheet" "https://www.bourns.com/docs/product-datasheets/cr.pdf"
			(at 0 0 180)
			(layer "F.Fab")
			(hide yes)
			(effects
				(font
					(size 1.27 1.27)
					(thickness 0.15)
				)
			)
		)
		(property "Description" "SMD Chip Resistor, 10 kohm, ± 1%, 62.5 mW, 0402 [1005 Metric], Thick Film, General Purpose"
			(at 0 0 180)
			(layer "F.Fab")
			(hide yes)
			(effects
				(font
					(size 1.27 1.27)
					(thickness 0.15)
				)
			)
		)
		(property "MPN" "CR0402-FX-1002GLF"
			(at 0 0 180)
			(unlocked yes)
			(layer "F.Fab")
			(hide yes)
			(effects
				(font
					(size 1 1)
					(thickness 0.15)
				)
			)
		)
		(property "Manufacturer" "Bourns"
			(at 0 0 180)
			(unlocked yes)
			(layer "F.Fab")
			(hide yes)
			(effects
				(font
					(size 1 1)
					(thickness 0.15)
				)
			)
		)
		(property "License" "Apache-2.0"
			(at 0 0 180)
			(unlocked yes)
			(layer "F.Fab")
			(hide yes)
			(effects
				(font
					(size 1 1)
					(thickness 0.15)
				)
			)
		)
		(property "Author" "Antmicro"
			(at 0 0 180)
			(unlocked yes)
			(layer "F.Fab")
			(hide yes)
			(effects
				(font
					(size 1 1)
					(thickness 0.15)
				)
			)
		)
		(property "Val" "10k"
			(at 0 0 180)
			(unlocked yes)
			(layer "F.Fab")
			(hide yes)
			(effects
				(font
					(size 1 1)
					(thickness 0.15)
				)
			)
		)
		(property "Tolerance" "1%"
			(at 0 0 180)
			(unlocked yes)
			(layer "F.Fab")
			(hide yes)
			(effects
				(font
					(size 1 1)
					(thickness 0.15)
				)
			)
		)
		(sheetname "/X710 flash memory/")
		(sheetfile "flash_x710.kicad_sch")
		(attr smd)
		(fp_rect
			(start -0.925 -0.47)
			(end 0.925 0.47)
			(stroke
				(width 0.05)
				(type default)
			)
			(fill no)
			(layer "F.CrtYd")
		)
		(fp_rect
			(start -0.5 -0.25)
			(end 0.5 0.25)
			(stroke
				(width 0.15)
				(type solid)
			)
			(fill no)
			(layer "F.Fab")
		)
		(fp_text user "Author: Antmicro"
			(at -0.95 4.169 180)
			(layer "F.Fab")
			(effects
				(font
					(size 0.7 0.7)
					(thickness 0.15)
				)
				(justify left bottom)
			)
		)
		(fp_text user "License: Apache-2.0"
			(at -0.95 5.169 180)
			(layer "F.Fab")
			(effects
				(font
					(size 0.7 0.7)
					(thickness 0.15)
				)
				(justify left bottom)
			)
		)
		(fp_text user "${REFERENCE}"
			(at -0.95 3.168 180)
			(layer "F.Fab")
			(effects
				(font
					(size 0.7 0.7)
					(thickness 0.15)
				)
				(justify left bottom)
			)
		)
		(pad "1" smd roundrect
			(at -0.48 0 180)
			(size 0.59 0.64)
			(layers "F.Cu" "F.Mask" "F.Paste")
			(roundrect_rratio 0.25)
			(net 387 "/X710 flash memory/~{HOLD}")
			(pintype "passive")
		)
		(pad "2" smd roundrect
			(at 0.48 0 180)
			(size 0.59 0.64)
			(layers "F.Cu" "F.Mask" "F.Paste")
			(roundrect_rratio 0.25)
			(net 343 "/X710 flash memory/+3V3_FLASH")
			(pintype "passive")
		)
	)
	(footprint "antmicro-footprints:FB_0603_1608Metric"
		(layer "F.Cu")
		(at 148.755 97.374999 90)
		(property "Reference" "FB5"
			(at -19.625001 23.294999 90)
			(layer "F.SilkS")
			(effects
				(font
					(size 0.7 0.7)
					(thickness 0.15)
				)
			)
		)
		(property "Value" "FB_33Z_3A_Murata-BLM18PG_0603"
			(at 0 1.5 90)
			(layer "F.Fab")
			(effects
				(font
					(size 0.7 0.7)
					(thickness 0.15)
				)
				(justify left bottom)
			)
		)
		(property "Datasheet" "https://www.murata.com/products/productdata/8796737273886/QNFA9101.pdf?1649080818000"
			(at 0 0 90)
			(layer "F.Fab")
			(hide yes)
			(effects
				(font
					(size 1.27 1.27)
					(thickness 0.15)
				)
			)
		)
		(property "Description" "Ferrite Bead, 0603 [1608 Metric], 33 ohm, 3 A, BLM18PG, 0.025 ohm, ± 25%, DC power line"
			(at 0 0 90)
			(layer "F.Fab")
			(hide yes)
			(effects
				(font
					(size 1.27 1.27)
					(thickness 0.15)
				)
			)
		)
		(property "Val" "33Z/3A"
			(at 0 0 90)
			(unlocked yes)
			(layer "F.Fab")
			(hide yes)
			(effects
				(font
					(size 1 1)
					(thickness 0.15)
				)
			)
		)
		(property "MPN" "BLM18PG330SH1D"
			(at 0 0 90)
			(unlocked yes)
			(layer "F.Fab")
			(hide yes)
			(effects
				(font
					(size 1 1)
					(thickness 0.15)
				)
			)
		)
		(property "Manufacturer" "Murata"
			(at 0 0 90)
			(unlocked yes)
			(layer "F.Fab")
			(hide yes)
			(effects
				(font
					(size 1 1)
					(thickness 0.15)
				)
			)
		)
		(property "Current" ""
			(at 0 0 90)
			(unlocked yes)
			(layer "F.Fab")
			(hide yes)
			(effects
				(font
					(size 1 1)
					(thickness 0.15)
				)
			)
		)
		(property "Author" "Antmicro"
			(at 0 0 90)
			(unlocked yes)
			(layer "F.Fab")
			(hide yes)
			(effects
				(font
					(size 1 1)
					(thickness 0.15)
				)
			)
		)
		(property "License" "Apache-2.0"
			(at 0 0 90)
			(unlocked yes)
			(layer "F.Fab")
			(hide yes)
			(effects
				(font
					(size 1 1)
					(thickness 0.15)
				)
			)
		)
		(sheetname "/X710-AT2 power/")
		(sheetfile "x710-at2-power.kicad_sch")
		(attr smd)
		(fp_line
			(start -0.15 -0.4)
			(end 0.15 -0.4)
			(stroke
				(width 0.15)
				(type solid)
			)
			(layer "F.SilkS")
		)
		(fp_line
			(start -0.15 0.4)
			(end 0.15 0.4)
			(stroke
				(width 0.15)
				(type solid)
			)
			(layer "F.SilkS")
		)
		(fp_rect
			(start -1.25 -0.65)
			(end 1.25 0.65)
			(stroke
				(width 0.05)
				(type solid)
			)
			(fill no)
			(layer "F.CrtYd")
		)
		(fp_line
			(start 0.8 -0.408)
			(end -0.803 -0.408)
			(stroke
				(width 0.15)
				(type solid)
			)
			(layer "F.Fab")
		)
		(fp_line
			(start 0.8 -0.408)
			(end 0.8 0.406)
			(stroke
				(width 0.15)
				(type solid)
			)
			(layer "F.Fab")
		)
		(fp_line
			(start 0.8 0.406)
			(end -0.803 0.406)
			(stroke
				(width 0.15)
				(type solid)
			)
			(layer "F.Fab")
		)
		(fp_line
			(start -0.803 0.406)
			(end -0.803 -0.408)
			(stroke
				(width 0.15)
				(type solid)
			)
			(layer "F.Fab")
		)
		(fp_text user "Author: Antmicro"
			(at -1.653 3.162 90)
			(layer "F.Fab")
			(effects
				(font
					(size 0.7 0.7)
					(thickness 0.15)
				)
				(justify left bottom)
			)
		)
		(fp_text user "License: Apache-2.0"
			(at -1.653 5.9 90)
			(layer "F.Fab")
			(effects
				(font
					(size 0.7 0.7)
					(thickness 0.15)
				)
				(justify left bottom)
			)
		)
		(fp_text user "${REFERENCE}"
			(at -1.653 4.6 90)
			(layer "F.Fab")
			(effects
				(font
					(size 0.7 0.7)
					(thickness 0.15)
				)
				(justify left bottom)
			)
		)
		(pad "1" smd roundrect
			(at -0.7 0 90)
			(size 0.8 1)
			(layers "F.Cu" "F.Mask" "F.Paste")
			(roundrect_rratio 0.2)
			(net 18 "+1V88")
			(pintype "passive")
		)
		(pad "2" smd roundrect
			(at 0.7 0 90)
			(size 0.8 1)
			(layers "F.Cu" "F.Mask" "F.Paste")
			(roundrect_rratio 0.2)
			(net 10 "AVDDH")
			(pintype "passive")
		)
	)
	(footprint "antmicro-footprints:C_0402_1005Metric"
		(layer "F.Cu")
		(at 154.705001 98.574999 180)
		(descr "Capacitor SMD 0402")
		(tags "capacitor SMD 0402")
		(property "Reference" "C159"
			(at -23.294999 -19.625001 180)
			(layer "F.SilkS")
			(effects
				(font
					(size 0.7 0.7)
					(thickness 0.15)
				)
			)
		)
		(property "Value" "C_100n_0402"
			(at -1.022927 2.155213 180)
			(layer "F.Fab")
			(effects
				(font
					(size 0.7 0.7)
					(thickness 0.15)
				)
				(justify left bottom)
			)
		)
		(property "Datasheet" "https://www.murata.com/products/productdetail?partno=GRM155R61H104KE14%23"
			(at 0 0 180)
			(layer "F.Fab")
			(hide yes)
			(effects
				(font
					(size 1.27 1.27)
					(thickness 0.15)
				)
			)
		)
		(property "Description" "SMD Multilayer Ceramic Capacitor, 0.1 µF, 50 V, 0402 [1005 Metric], ± 10%, X5R, GRM Series"
			(at 0 0 180)
			(layer "F.Fab")
			(hide yes)
			(effects
				(font
					(size 1.27 1.27)
					(thickness 0.15)
				)
			)
		)
		(property "MPN" "GRM155R61H104KE14D"
			(at 0 0 180)
			(unlocked yes)
			(layer "F.Fab")
			(hide yes)
			(effects
				(font
					(size 1 1)
					(thickness 0.15)
				)
			)
		)
		(property "Val" "100n"
			(at 0 0 180)
			(unlocked yes)
			(layer "F.Fab")
			(hide yes)
			(effects
				(font
					(size 1 1)
					(thickness 0.15)
				)
			)
		)
		(property "Voltage" "50V"
			(at 0 0 180)
			(unlocked yes)
			(layer "F.Fab")
			(hide yes)
			(effects
				(font
					(size 1 1)
					(thickness 0.15)
				)
			)
		)
		(property "Dielectric" "X5R"
			(at 0 0 180)
			(unlocked yes)
			(layer "F.Fab")
			(hide yes)
			(effects
				(font
					(size 1 1)
					(thickness 0.15)
				)
			)
		)
		(property "Manufacturer" "Murata"
			(at 0 0 180)
			(unlocked yes)
			(layer "F.Fab")
			(hide yes)
			(effects
				(font
					(size 1 1)
					(thickness 0.15)
				)
			)
		)
		(property "License" "Apache-2.0"
			(at 0 0 180)
			(unlocked yes)
			(layer "F.Fab")
			(hide yes)
			(effects
				(font
					(size 1 1)
					(thickness 0.15)
				)
			)
		)
		(property "Author" "Antmicro"
			(at 0 0 180)
			(unlocked yes)
			(layer "F.Fab")
			(hide yes)
			(effects
				(font
					(size 1 1)
					(thickness 0.15)
				)
			)
		)
		(sheetname "/X710-AT2 power/")
		(sheetfile "x710-at2-power.kicad_sch")
		(attr smd)
		(fp_rect
			(start -0.925 -0.47)
			(end 0.925 0.47)
			(stroke
				(width 0.05)
				(type default)
			)
			(fill no)
			(layer "F.CrtYd")
		)
		(fp_line
			(start 0.504 0.248)
			(end -0.494 0.248)
			(stroke
				(width 0.15)
				(type solid)
			)
			(layer "F.Fab")
		)
		(fp_line
			(start 0.504 -0.25)
			(end 0.504 0.248)
			(stroke
				(width 0.15)
				(type solid)
			)
			(layer "F.Fab")
		)
		(fp_line
			(start -0.494 0.248)
			(end -0.494 -0.25)
			(stroke
				(width 0.15)
				(type solid)
			)
			(layer "F.Fab")
		)
		(fp_line
			(start -0.494 -0.25)
			(end 0.504 -0.25)
			(stroke
				(width 0.15)
				(type solid)
			)
			(layer "F.Fab")
		)
		(fp_text user "${REFERENCE}"
			(at -0.939 4.599 180)
			(layer "F.Fab")
			(effects
				(font
					(size 0.7 0.7)
					(thickness 0.15)
				)
				(justify left bottom)
			)
		)
		(fp_text user "Author: Antmicro"
			(at -0.939 3.399 180)
			(layer "F.Fab")
			(effects
				(font
					(size 0.7 0.7)
					(thickness 0.15)
				)
				(justify left bottom)
			)
		)
		(fp_text user "License: Apache-2.0"
			(at -0.939 5.799 180)
			(layer "F.Fab")
			(effects
				(font
					(size 0.7 0.7)
					(thickness 0.15)
				)
				(justify left bottom)
			)
		)
		(pad "1" smd roundrect
			(at -0.48 0 180)
			(size 0.59 0.64)
			(layers "F.Cu" "F.Mask" "F.Paste")
			(roundrect_rratio 0.25)
			(net 23 "GND")
			(pintype "passive")
		)
		(pad "2" smd roundrect
			(at 0.48 0 180)
			(size 0.59 0.64)
			(layers "F.Cu" "F.Mask" "F.Paste")
			(roundrect_rratio 0.25)
			(net 136 "+1V0")
			(pintype "passive")
		)
	)
	(footprint "antmicro-footprints:R_0402_1005Metric"
		(layer "F.Cu")
		(at 160.105 67.125 -90)
		(descr "Resistor SMD 0402")
		(tags "resistor SMD 0402")
		(property "Reference" "R189"
			(at -12.324999 -20.295 270)
			(layer "F.SilkS")
			(effects
				(font
					(size 0.7 0.7)
					(thickness 0.15)
				)
			)
		)
		(property "Value" "R_22R_0402"
			(at -1.011843 1.772047 270)
			(layer "F.Fab")
			(effects
				(font
					(size 0.7 0.7)
					(thickness 0.15)
				)
				(justify left bottom)
			)
		)
		(property "Datasheet" "https://www.bourns.com/docs/product-datasheets/cr.pdf"
			(at 0 0 270)
			(layer "F.Fab")
			(hide yes)
			(effects
				(font
					(size 1.27 1.27)
					(thickness 0.15)
				)
			)
		)
		(property "Description" "SMD Chip Resistor, 22 ohm, ± 1%, 62.5 mW, 0402 [1005 Metric], Thick Film, General Purpose"
			(at 0 0 270)
			(layer "F.Fab")
			(hide yes)
			(effects
				(font
					(size 1.27 1.27)
					(thickness 0.15)
				)
			)
		)
		(property "MPN" "CR0402-FX-22R0GLF"
			(at 0 0 270)
			(unlocked yes)
			(layer "F.Fab")
			(hide yes)
			(effects
				(font
					(size 1 1)
					(thickness 0.15)
				)
			)
		)
		(property "Manufacturer" "Bourns"
			(at 0 0 270)
			(unlocked yes)
			(layer "F.Fab")
			(hide yes)
			(effects
				(font
					(size 1 1)
					(thickness 0.15)
				)
			)
		)
		(property "License" "Apache-2.0"
			(at 0 0 270)
			(unlocked yes)
			(layer "F.Fab")
			(hide yes)
			(effects
				(font
					(size 1 1)
					(thickness 0.15)
				)
			)
		)
		(property "Author" "Antmicro"
			(at 0 0 270)
			(unlocked yes)
			(layer "F.Fab")
			(hide yes)
			(effects
				(font
					(size 1 1)
					(thickness 0.15)
				)
			)
		)
		(property "Val" "22R"
			(at 0 0 270)
			(unlocked yes)
			(layer "F.Fab")
			(hide yes)
			(effects
				(font
					(size 1 1)
					(thickness 0.15)
				)
			)
		)
		(property "Tolerance" "1%"
			(at 0 0 270)
			(unlocked yes)
			(layer "F.Fab")
			(hide yes)
			(effects
				(font
					(size 1 1)
					(thickness 0.15)
				)
			)
		)
		(sheetname "/X710-AT2 10GbE/")
		(sheetfile "x710-at2-10gbe.kicad_sch")
		(attr smd)
		(fp_rect
			(start -0.925 -0.47)
			(end 0.925 0.47)
			(stroke
				(width 0.05)
				(type default)
			)
			(fill no)
			(layer "F.CrtYd")
		)
		(fp_rect
			(start -0.5 -0.25)
			(end 0.5 0.25)
			(stroke
				(width 0.15)
				(type solid)
			)
			(fill no)
			(layer "F.Fab")
		)
		(fp_text user "${REFERENCE}"
			(at -0.95 3.168 270)
			(layer "F.Fab")
			(effects
				(font
					(size 0.7 0.7)
					(thickness 0.15)
				)
				(justify left bottom)
			)
		)
		(fp_text user "License: Apache-2.0"
			(at -0.95 5.169 270)
			(layer "F.Fab")
			(effects
				(font
					(size 0.7 0.7)
					(thickness 0.15)
				)
				(justify left bottom)
			)
		)
		(fp_text user "Author: Antmicro"
			(at -0.95 4.169 270)
			(layer "F.Fab")
			(effects
				(font
					(size 0.7 0.7)
					(thickness 0.15)
				)
				(justify left bottom)
			)
		)
		(pad "1" smd roundrect
			(at -0.48 0 270)
			(size 0.59 0.64)
			(layers "F.Cu" "F.Mask" "F.Paste")
			(roundrect_rratio 0.25)
			(net 114 "/X710-AT2 10GbE/25MHZ_OSC_R.-")
			(pintype "passive")
		)
		(pad "2" smd roundrect
			(at 0.48 0 270)
			(size 0.59 0.64)
			(layers "F.Cu" "F.Mask" "F.Paste")
			(roundrect_rratio 0.25)
			(net 55 "/X710-AT2 10GbE/25MHZ_OSC_AC.-")
			(pintype "passive")
		)
	)
	(footprint "antmicro-footprints:Resonator_SMD_Abracon_ABM8G_3.2x2.5mm"
		(layer "F.Cu")
		(at 117.5 130.25 180)
		(property "Reference" "Y2"
			(at -2.1 -0.95 0)
			(layer "F.SilkS")
			(effects
				(font
					(size 0.7 0.7)
					(thickness 0.15)
				)
				(justify left bottom)
			)
		)
		(property "Value" "Resonator_25MHz_ABM8G"
			(at -1.75 2.548 180)
			(layer "F.Fab")
			(effects
				(font
					(size 0.7 0.7)
					(thickness 0.15)
				)
				(justify left bottom)
			)
		)
		(property "Datasheet" "https://abracon.com/Resonators/ABM8G.pdf"
			(at 0 0 180)
			(layer "F.Fab")
			(hide yes)
			(effects
				(font
					(size 1.27 1.27)
					(thickness 0.15)
				)
			)
		)
		(property "Description" "Crystal, 25 MHz, SMD, 3.2mm x 2.5mm, 30 ppm, 18 pF, 20 ppm, ABM8G"
			(at 0 0 180)
			(layer "F.Fab")
			(hide yes)
			(effects
				(font
					(size 1.27 1.27)
					(thickness 0.15)
				)
			)
		)
		(property "MPN" "ABM8G-25.000MHZ-18-D2Y-T3"
			(at 0 0 180)
			(unlocked yes)
			(layer "F.Fab")
			(hide yes)
			(effects
				(font
					(size 1 1)
					(thickness 0.15)
				)
			)
		)
		(property "Manufacturer" "Abracon"
			(at 0 0 180)
			(unlocked yes)
			(layer "F.Fab")
			(hide yes)
			(effects
				(font
					(size 1 1)
					(thickness 0.15)
				)
			)
		)
		(property "License" "Apache-2.0"
			(at 0 0 180)
			(unlocked yes)
			(layer "F.Fab")
			(hide yes)
			(effects
				(font
					(size 1 1)
					(thickness 0.15)
				)
			)
		)
		(property "Author" "Antmicro"
			(at 0 0 180)
			(unlocked yes)
			(layer "F.Fab")
			(hide yes)
			(effects
				(font
					(size 1 1)
					(thickness 0.15)
				)
			)
		)
		(property "Val" "25 MHz"
			(at 0 0 180)
			(unlocked yes)
			(layer "F.Fab")
			(hide yes)
			(effects
				(font
					(size 1 1)
					(thickness 0.15)
				)
			)
		)
		(sheetname "/TB Controller/")
		(sheetfile "tb.kicad_sch")
		(attr smd)
		(fp_line
			(start 1.6 0.3)
			(end 1.6 -0.2)
			(stroke
				(width 0.15)
				(type solid)
			)
			(layer "F.SilkS")
		)
		(fp_line
			(start -0.35 1.25)
			(end 0.45 1.25)
			(stroke
				(width 0.15)
				(type solid)
			)
			(layer "F.SilkS")
		)
		(fp_line
			(start -0.35 -1.25)
			(end 0.45 -1.25)
			(stroke
				(width 0.15)
				(type solid)
			)
			(layer "F.SilkS")
		)
		(fp_line
			(start -1.6 0.3)
			(end -1.6 -0.2)
			(stroke
				(width 0.15)
				(type solid)
			)
			(layer "F.SilkS")
		)
		(fp_circle
			(center -1.75 1.5)
			(end -1.7 1.5)
			(stroke
				(width 0.15)
				(type solid)
			)
			(fill no)
			(layer "F.SilkS")
		)
		(fp_rect
			(start -1.907 -1.55)
			(end 2.006 1.649)
			(stroke
				(width 0.05)
				(type solid)
			)
			(fill no)
			(layer "F.CrtYd")
		)
		(fp_text user "Author: Antmicro"
			(at -1.75 5 180)
			(layer "F.Fab")
			(effects
				(font
					(size 0.7 0.7)
					(thickness 0.15)
				)
				(justify left bottom)
			)
		)
		(fp_text user "${REFERENCE}"
			(at -1.75 3.75 180)
			(layer "F.Fab")
			(effects
				(font
					(size 0.7 0.7)
					(thickness 0.15)
				)
				(justify left bottom)
			)
		)
		(fp_text user "License: Apache-2.0"
			(at -1.75 6.5 180)
			(layer "F.Fab")
			(effects
				(font
					(size 0.7 0.7)
					(thickness 0.15)
				)
				(justify left bottom)
			)
		)
		(pad "1" smd roundrect
			(at -1.101 0.949 180)
			(size 1.3 1.1)
			(layers "F.Cu" "F.Mask" "F.Paste")
			(roundrect_rratio 0)
			(chamfer_ratio 0.2)
			(chamfer bottom_left)
			(net 331 "/TB Controller/XTAL_25_OUT")
			(pintype "passive")
		)
		(pad "2" smd rect
			(at 1.199 0.949 180)
			(size 1.3 1.1)
			(layers "F.Cu" "F.Mask" "F.Paste")
			(net 23 "GND")
			(pinfunction "SH")
			(pintype "passive")
		)
		(pad "3" smd rect
			(at 1.199 -0.85 180)
			(size 1.3 1.1)
			(layers "F.Cu" "F.Mask" "F.Paste")
			(net 330 "/TB Controller/XTAL_25_IN")
			(pintype "passive")
		)
		(pad "4" smd rect
			(at -1.101 -0.85 180)
			(size 1.3 1.1)
			(layers "F.Cu" "F.Mask" "F.Paste")
			(net 23 "GND")
			(pinfunction "SH")
			(pintype "passive")
		)
	)
	(footprint "antmicro-footprints:C_0603_1608Metric_EIA"
		(layer "F.Cu")
		(at 162.555 99.224999 -90)
		(descr "Capacitor SMD 0603, IPC-7351 Density Level A")
		(tags "Capacitor 0603")
		(property "Reference" "C155"
			(at 0 -7.695 270)
			(layer "F.SilkS")
			(effects
				(font
					(size 0.7 0.7)
					(thickness 0.15)
				)
			)
		)
		(property "Value" "C_22u_16V_0603"
			(at -1.42757 1.770288 270)
			(layer "F.Fab")
			(effects
				(font
					(size 0.7 0.7)
					(thickness 0.15)
				)
				(justify left bottom)
			)
		)
		(property "Datasheet" "https://product.samsungsem.com/mlcc/CL10A226MO7JZN.do"
			(at 0 0 270)
			(layer "F.Fab")
			(hide yes)
			(effects
				(font
					(size 1.27 1.27)
					(thickness 0.15)
				)
			)
		)
		(property "Description" "SMD Multilayer Ceramic Capacitor"
			(at 0 0 270)
			(layer "F.Fab")
			(hide yes)
			(effects
				(font
					(size 1.27 1.27)
					(thickness 0.15)
				)
			)
		)
		(property "MPN" "CL10A226MO7JZNC"
			(at 0 0 270)
			(unlocked yes)
			(layer "F.Fab")
			(hide yes)
			(effects
				(font
					(size 1 1)
					(thickness 0.15)
				)
			)
		)
		(property "Manufacturer" "Samsung Electro-Mechanics"
			(at 0 0 270)
			(unlocked yes)
			(layer "F.Fab")
			(hide yes)
			(effects
				(font
					(size 1 1)
					(thickness 0.15)
				)
			)
		)
		(property "License" "Apache-2.0"
			(at 0 0 270)
			(unlocked yes)
			(layer "F.Fab")
			(hide yes)
			(effects
				(font
					(size 1 1)
					(thickness 0.15)
				)
			)
		)
		(property "Author" "Antmicro"
			(at 0 0 270)
			(unlocked yes)
			(layer "F.Fab")
			(hide yes)
			(effects
				(font
					(size 1 1)
					(thickness 0.15)
				)
			)
		)
		(property "Val" "22u"
			(at 0 0 270)
			(unlocked yes)
			(layer "F.Fab")
			(hide yes)
			(effects
				(font
					(size 1 1)
					(thickness 0.15)
				)
			)
		)
		(property "Voltage" "16V"
			(at 0 0 270)
			(unlocked yes)
			(layer "F.Fab")
			(hide yes)
			(effects
				(font
					(size 1 1)
					(thickness 0.15)
				)
			)
		)
		(property "Dielectric" ""
			(at 0 0 270)
			(unlocked yes)
			(layer "F.Fab")
			(hide yes)
			(effects
				(font
					(size 1 1)
					(thickness 0.15)
				)
			)
		)
		(sheetname "/X710-AT2 power/")
		(sheetfile "x710-at2-power.kicad_sch")
		(attr smd)
		(fp_line
			(start -0.15 0.55)
			(end 0.15 0.55)
			(stroke
				(width 0.15)
				(type solid)
			)
			(layer "F.SilkS")
		)
		(fp_line
			(start -0.15 -0.55)
			(end 0.15 -0.55)
			(stroke
				(width 0.15)
				(type solid)
			)
			(layer "F.SilkS")
		)
		(fp_rect
			(start -1.25 -0.65)
			(end 1.25 0.65)
			(stroke
				(width 0.05)
				(type solid)
			)
			(fill no)
			(layer "F.CrtYd")
		)
		(fp_rect
			(start -0.8 -0.45)
			(end 0.8 0.45)
			(stroke
				(width 0.15)
				(type solid)
			)
			(fill no)
			(layer "F.Fab")
		)
		(fp_text user "License: Apache-2.0"
			(at -1.682 5.895 270)
			(layer "F.Fab")
			(effects
				(font
					(size 0.7 0.7)
					(thickness 0.15)
				)
				(justify left bottom)
			)
		)
		(fp_text user "${REFERENCE}"
			(at -1.682 3.895 270)
			(layer "F.Fab")
			(effects
				(font
					(size 0.7 0.7)
					(thickness 0.15)
				)
				(justify left bottom)
			)
		)
		(fp_text user "Author: Antmicro"
			(at -1.682 4.894 270)
			(layer "F.Fab")
			(effects
				(font
					(size 0.7 0.7)
					(thickness 0.15)
				)
				(justify left bottom)
			)
		)
		(pad "1" smd roundrect
			(at -0.7 0 270)
			(size 0.8 1.1)
			(layers "F.Cu" "F.Mask" "F.Paste")
			(roundrect_rratio 0.2)
			(net 23 "GND")
			(pintype "passive")
		)
		(pad "2" smd roundrect
			(at 0.7 0 270)
			(size 0.8 1.1)
			(layers "F.Cu" "F.Mask" "F.Paste")
			(roundrect_rratio 0.2)
			(net 136 "+1V0")
			(pintype "passive")
		)
	)
	(footprint "antmicro-footprints:R_0402_1005Metric"
		(layer "F.Cu")
		(at 140.4 139.55 180)
		(descr "Resistor SMD 0402")
		(tags "resistor SMD 0402")
		(property "Reference" "R16"
			(at 1.2 1.75 180)
			(layer "F.SilkS")
			(effects
				(font
					(size 0.7 0.7)
					(thickness 0.15)
				)
				(justify left bottom)
			)
		)
		(property "Value" "R_0R_0402"
			(at -1.011843 1.772047 180)
			(layer "F.Fab")
			(effects
				(font
					(size 0.7 0.7)
					(thickness 0.15)
				)
				(justify left bottom)
			)
		)
		(property "Datasheet" "https://industrial.panasonic.com/cdbs/www-data/pdf/RDA0000/AOA0000C301.pdf"
			(at 0 0 180)
			(layer "F.Fab")
			(hide yes)
			(effects
				(font
					(size 1.27 1.27)
					(thickness 0.15)
				)
			)
		)
		(property "Description" "SMD Chip Resistor, Jumper, 0 ohm, 100 mW, 0402 [1005 Metric], Thick Film, General Purpose"
			(at 0 0 180)
			(layer "F.Fab")
			(hide yes)
			(effects
				(font
					(size 1.27 1.27)
					(thickness 0.15)
				)
			)
		)
		(property "MPN" "ERJ2GE0R00X"
			(at 0 0 180)
			(unlocked yes)
			(layer "F.Fab")
			(hide yes)
			(effects
				(font
					(size 1 1)
					(thickness 0.15)
				)
			)
		)
		(property "Manufacturer" "Panasonic"
			(at 0 0 180)
			(unlocked yes)
			(layer "F.Fab")
			(hide yes)
			(effects
				(font
					(size 1 1)
					(thickness 0.15)
				)
			)
		)
		(property "License" "Apache-2.0"
			(at 0 0 180)
			(unlocked yes)
			(layer "F.Fab")
			(hide yes)
			(effects
				(font
					(size 1 1)
					(thickness 0.15)
				)
			)
		)
		(property "Val" "0R"
			(at 0 0 180)
			(unlocked yes)
			(layer "F.Fab")
			(hide yes)
			(effects
				(font
					(size 1 1)
					(thickness 0.15)
				)
			)
		)
		(property "Tolerance" "~"
			(at 0 0 180)
			(unlocked yes)
			(layer "F.Fab")
			(hide yes)
			(effects
				(font
					(size 1 1)
					(thickness 0.15)
				)
			)
		)
		(property "Current" "1A"
			(at 0 0 180)
			(unlocked yes)
			(layer "F.Fab")
			(hide yes)
			(effects
				(font
					(size 1 1)
					(thickness 0.15)
				)
			)
		)
		(property "Author" "Antmicro"
			(at 0 0 180)
			(unlocked yes)
			(layer "F.Fab")
			(hide yes)
			(effects
				(font
					(size 1 1)
					(thickness 0.15)
				)
			)
		)
		(sheetname "/PD and TB DC-DC/")
		(sheetfile "PD_and_TB_DC_DC.kicad_sch")
		(attr smd)
		(fp_rect
			(start -0.925 -0.47)
			(end 0.925 0.47)
			(stroke
				(width 0.05)
				(type default)
			)
			(fill no)
			(layer "F.CrtYd")
		)
		(fp_rect
			(start -0.5 -0.25)
			(end 0.5 0.25)
			(stroke
				(width 0.15)
				(type solid)
			)
			(fill no)
			(layer "F.Fab")
		)
		(fp_text user "License: Apache-2.0"
			(at -0.95 5.169 180)
			(layer "F.Fab")
			(effects
				(font
					(size 0.7 0.7)
					(thickness 0.15)
				)
				(justify left bottom)
			)
		)
		(fp_text user "${REFERENCE}"
			(at -0.95 3.168 180)
			(layer "F.Fab")
			(effects
				(font
					(size 0.7 0.7)
					(thickness 0.15)
				)
				(justify left bottom)
			)
		)
		(fp_text user "Author: Antmicro"
			(at -0.95 4.169 180)
			(layer "F.Fab")
			(effects
				(font
					(size 0.7 0.7)
					(thickness 0.15)
				)
				(justify left bottom)
			)
		)
		(pad "1" smd roundrect
			(at -0.48 0 180)
			(size 0.59 0.64)
			(layers "F.Cu" "F.Mask" "F.Paste")
			(roundrect_rratio 0.25)
			(net 374 "/PD and TB DC-DC/HPD")
			(pintype "passive")
		)
		(pad "2" smd roundrect
			(at 0.48 0 180)
			(size 0.59 0.64)
			(layers "F.Cu" "F.Mask" "F.Paste")
			(roundrect_rratio 0.25)
			(net 202 "Net-(U3-GPIO4(HPD_TXRX))")
			(pintype "passive")
		)
	)
	(footprint "antmicro-footprints:C_0402_1005Metric"
		(layer "F.Cu")
		(at 117.8 118 180)
		(descr "Capacitor SMD 0402")
		(tags "capacitor SMD 0402")
		(property "Reference" "C44"
			(at -0.8 -0.2 180)
			(layer "F.SilkS")
			(effects
				(font
					(size 0.7 0.7)
					(thickness 0.15)
				)
				(justify left bottom)
			)
		)
		(property "Value" "C_220n_0402"
			(at -1.022927 2.155213 180)
			(layer "F.Fab")
			(effects
				(font
					(size 0.7 0.7)
					(thickness 0.15)
				)
				(justify left bottom)
			)
		)
		(property "Datasheet" "https://www.yageo.com/en/Chart/Download/pdf/CC0402KRX5R6BB224"
			(at 0 0 180)
			(layer "F.Fab")
			(hide yes)
			(effects
				(font
					(size 1.27 1.27)
					(thickness 0.15)
				)
			)
		)
		(property "Description" "SMD Multilayer Ceramic Capacitor, 0.22 µF, 10 V, 0402 [1005 Metric], ± 10%, X5R, CC Series"
			(at 0 0 180)
			(layer "F.Fab")
			(hide yes)
			(effects
				(font
					(size 1.27 1.27)
					(thickness 0.15)
				)
			)
		)
		(property "MPN" "CC0402KRX5R6BB224"
			(at 0 0 180)
			(unlocked yes)
			(layer "F.Fab")
			(hide yes)
			(effects
				(font
					(size 1 1)
					(thickness 0.15)
				)
			)
		)
		(property "Manufacturer" "YAGEO"
			(at 0 0 180)
			(unlocked yes)
			(layer "F.Fab")
			(hide yes)
			(effects
				(font
					(size 1 1)
					(thickness 0.15)
				)
			)
		)
		(property "License" "Apache-2.0"
			(at 0 0 180)
			(unlocked yes)
			(layer "F.Fab")
			(hide yes)
			(effects
				(font
					(size 1 1)
					(thickness 0.15)
				)
			)
		)
		(property "Val" "220n"
			(at 0 0 180)
			(unlocked yes)
			(layer "F.Fab")
			(hide yes)
			(effects
				(font
					(size 1 1)
					(thickness 0.15)
				)
			)
		)
		(property "Voltage" ""
			(at 0 0 180)
			(unlocked yes)
			(layer "F.Fab")
			(hide yes)
			(effects
				(font
					(size 1 1)
					(thickness 0.15)
				)
			)
		)
		(property "Dielectric" ""
			(at 0 0 180)
			(unlocked yes)
			(layer "F.Fab")
			(hide yes)
			(effects
				(font
					(size 1 1)
					(thickness 0.15)
				)
			)
		)
		(property "Author" "Antmicro"
			(at 0 0 180)
			(unlocked yes)
			(layer "F.Fab")
			(hide yes)
			(effects
				(font
					(size 1 1)
					(thickness 0.15)
				)
			)
		)
		(sheetname "/TB Controller/")
		(sheetfile "tb.kicad_sch")
		(attr smd)
		(fp_rect
			(start -0.925 -0.47)
			(end 0.925 0.47)
			(stroke
				(width 0.05)
				(type default)
			)
			(fill no)
			(layer "F.CrtYd")
		)
		(fp_line
			(start 0.504 0.248)
			(end -0.494 0.248)
			(stroke
				(width 0.15)
				(type solid)
			)
			(layer "F.Fab")
		)
		(fp_line
			(start 0.504 -0.25)
			(end 0.504 0.248)
			(stroke
				(width 0.15)
				(type solid)
			)
			(layer "F.Fab")
		)
		(fp_line
			(start -0.494 0.248)
			(end -0.494 -0.25)
			(stroke
				(width 0.15)
				(type solid)
			)
			(layer "F.Fab")
		)
		(fp_line
			(start -0.494 -0.25)
			(end 0.504 -0.25)
			(stroke
				(width 0.15)
				(type solid)
			)
			(layer "F.Fab")
		)
		(fp_text user "License: Apache-2.0"
			(at -0.939 5.799 180)
			(layer "F.Fab")
			(effects
				(font
					(size 0.7 0.7)
					(thickness 0.15)
				)
				(justify left bottom)
			)
		)
		(fp_text user "${REFERENCE}"
			(at -0.939 4.599 180)
			(layer "F.Fab")
			(effects
				(font
					(size 0.7 0.7)
					(thickness 0.15)
				)
				(justify left bottom)
			)
		)
		(fp_text user "Author: Antmicro"
			(at -0.939 3.399 180)
			(layer "F.Fab")
			(effects
				(font
					(size 0.7 0.7)
					(thickness 0.15)
				)
				(justify left bottom)
			)
		)
		(pad "1" smd roundrect
			(at -0.48 0 180)
			(size 0.59 0.64)
			(layers "F.Cu" "F.Mask" "F.Paste")
			(roundrect_rratio 0.25)
			(net 323 "/TB Controller/TB_PCIE_TX0_P")
			(pintype "passive")
		)
		(pad "2" smd roundrect
			(at 0.48 0 180)
			(size 0.59 0.64)
			(layers "F.Cu" "F.Mask" "F.Paste")
			(roundrect_rratio 0.25)
			(net 314 "/TB Controller/PCIex4.RX0+")
			(pintype "passive")
		)
	)
	(footprint "antmicro-footprints:C_0402_1005Metric"
		(layer "F.Cu")
		(at 153.8 50.2 90)
		(descr "Capacitor SMD 0402")
		(tags "capacitor SMD 0402")
		(property "Reference" "C314"
			(at -2.1 -0.7 90)
			(layer "F.SilkS")
			(effects
				(font
					(size 0.7 0.7)
					(thickness 0.15)
				)
				(justify left bottom)
			)
		)
		(property "Value" "C_100n_0402"
			(at -1.022927 2.155213 90)
			(layer "F.Fab")
			(effects
				(font
					(size 0.7 0.7)
					(thickness 0.15)
				)
				(justify left bottom)
			)
		)
		(property "Datasheet" "https://www.murata.com/products/productdetail?partno=GRM155R61H104KE14%23"
			(at 0 0 90)
			(layer "F.Fab")
			(hide yes)
			(effects
				(font
					(size 1.27 1.27)
					(thickness 0.15)
				)
			)
		)
		(property "Description" "SMD Multilayer Ceramic Capacitor, 0.1 µF, 50 V, 0402 [1005 Metric], ± 10%, X5R, GRM Series"
			(at 0 0 90)
			(layer "F.Fab")
			(hide yes)
			(effects
				(font
					(size 1.27 1.27)
					(thickness 0.15)
				)
			)
		)
		(property "MPN" "GRM155R61H104KE14D"
			(at 0 0 90)
			(unlocked yes)
			(layer "F.Fab")
			(hide yes)
			(effects
				(font
					(size 1 1)
					(thickness 0.15)
				)
			)
		)
		(property "Manufacturer" "Murata"
			(at 0 0 90)
			(unlocked yes)
			(layer "F.Fab")
			(hide yes)
			(effects
				(font
					(size 1 1)
					(thickness 0.15)
				)
			)
		)
		(property "License" "Apache-2.0"
			(at 0 0 90)
			(unlocked yes)
			(layer "F.Fab")
			(hide yes)
			(effects
				(font
					(size 1 1)
					(thickness 0.15)
				)
			)
		)
		(property "Author" "Antmicro"
			(at 0 0 90)
			(unlocked yes)
			(layer "F.Fab")
			(hide yes)
			(effects
				(font
					(size 1 1)
					(thickness 0.15)
				)
			)
		)
		(property "Val" "100n"
			(at 0 0 90)
			(unlocked yes)
			(layer "F.Fab")
			(hide yes)
			(effects
				(font
					(size 1 1)
					(thickness 0.15)
				)
			)
		)
		(property "Voltage" "50V"
			(at 0 0 90)
			(unlocked yes)
			(layer "F.Fab")
			(hide yes)
			(effects
				(font
					(size 1 1)
					(thickness 0.15)
				)
			)
		)
		(property "Dielectric" "X5R"
			(at 0 0 90)
			(unlocked yes)
			(layer "F.Fab")
			(hide yes)
			(effects
				(font
					(size 1 1)
					(thickness 0.15)
				)
			)
		)
		(sheetname "/Power input/")
		(sheetfile "power_input.kicad_sch")
		(attr smd)
		(fp_rect
			(start -0.925 -0.47)
			(end 0.925 0.47)
			(stroke
				(width 0.05)
				(type default)
			)
			(fill no)
			(layer "F.CrtYd")
		)
		(fp_line
			(start 0.504 -0.25)
			(end 0.504 0.248)
			(stroke
				(width 0.15)
				(type solid)
			)
			(layer "F.Fab")
		)
		(fp_line
			(start -0.494 -0.25)
			(end 0.504 -0.25)
			(stroke
				(width 0.15)
				(type solid)
			)
			(layer "F.Fab")
		)
		(fp_line
			(start 0.504 0.248)
			(end -0.494 0.248)
			(stroke
				(width 0.15)
				(type solid)
			)
			(layer "F.Fab")
		)
		(fp_line
			(start -0.494 0.248)
			(end -0.494 -0.25)
			(stroke
				(width 0.15)
				(type solid)
			)
			(layer "F.Fab")
		)
		(fp_text user "${REFERENCE}"
			(at -0.939 4.599 90)
			(layer "F.Fab")
			(effects
				(font
					(size 0.7 0.7)
					(thickness 0.15)
				)
				(justify left bottom)
			)
		)
		(fp_text user "License: Apache-2.0"
			(at -0.939 5.799 90)
			(layer "F.Fab")
			(effects
				(font
					(size 0.7 0.7)
					(thickness 0.15)
				)
				(justify left bottom)
			)
		)
		(fp_text user "Author: Antmicro"
			(at -0.939 3.399 90)
			(layer "F.Fab")
			(effects
				(font
					(size 0.7 0.7)
					(thickness 0.15)
				)
				(justify left bottom)
			)
		)
		(pad "1" smd roundrect
			(at -0.48 0 90)
			(size 0.59 0.64)
			(layers "F.Cu" "F.Mask" "F.Paste")
			(roundrect_rratio 0.25)
			(net 23 "GND")
			(pintype "passive")
		)
		(pad "2" smd roundrect
			(at 0.48 0 90)
			(size 0.59 0.64)
			(layers "F.Cu" "F.Mask" "F.Paste")
			(roundrect_rratio 0.25)
			(net 412 "Net-(D15-C)")
			(pintype "passive")
		)
	)
	(footprint "antmicro-footprints:C_0402_1005Metric"
		(layer "F.Cu")
		(at 161.355001 99.204999 -90)
		(descr "Capacitor SMD 0402")
		(tags "capacitor SMD 0402")
		(property "Reference" "C163"
			(at 0 -7.695 270)
			(layer "F.SilkS")
			(effects
				(font
					(size 0.7 0.7)
					(thickness 0.15)
				)
			)
		)
		(property "Value" "C_100n_0402"
			(at -1.022927 2.155213 270)
			(layer "F.Fab")
			(effects
				(font
					(size 0.7 0.7)
					(thickness 0.15)
				)
				(justify left bottom)
			)
		)
		(property "Datasheet" "https://www.murata.com/products/productdetail?partno=GRM155R61H104KE14%23"
			(at 0 0 270)
			(layer "F.Fab")
			(hide yes)
			(effects
				(font
					(size 1.27 1.27)
					(thickness 0.15)
				)
			)
		)
		(property "Description" "SMD Multilayer Ceramic Capacitor, 0.1 µF, 50 V, 0402 [1005 Metric], ± 10%, X5R, GRM Series"
			(at 0 0 270)
			(layer "F.Fab")
			(hide yes)
			(effects
				(font
					(size 1.27 1.27)
					(thickness 0.15)
				)
			)
		)
		(property "MPN" "GRM155R61H104KE14D"
			(at 0 0 270)
			(unlocked yes)
			(layer "F.Fab")
			(hide yes)
			(effects
				(font
					(size 1 1)
					(thickness 0.15)
				)
			)
		)
		(property "Val" "100n"
			(at 0 0 270)
			(unlocked yes)
			(layer "F.Fab")
			(hide yes)
			(effects
				(font
					(size 1 1)
					(thickness 0.15)
				)
			)
		)
		(property "Voltage" "50V"
			(at 0 0 270)
			(unlocked yes)
			(layer "F.Fab")
			(hide yes)
			(effects
				(font
					(size 1 1)
					(thickness 0.15)
				)
			)
		)
		(property "Dielectric" "X5R"
			(at 0 0 270)
			(unlocked yes)
			(layer "F.Fab")
			(hide yes)
			(effects
				(font
					(size 1 1)
					(thickness 0.15)
				)
			)
		)
		(property "Manufacturer" "Murata"
			(at 0 0 270)
			(unlocked yes)
			(layer "F.Fab")
			(hide yes)
			(effects
				(font
					(size 1 1)
					(thickness 0.15)
				)
			)
		)
		(property "License" "Apache-2.0"
			(at 0 0 270)
			(unlocked yes)
			(layer "F.Fab")
			(hide yes)
			(effects
				(font
					(size 1 1)
					(thickness 0.15)
				)
			)
		)
		(property "Author" "Antmicro"
			(at 0 0 270)
			(unlocked yes)
			(layer "F.Fab")
			(hide yes)
			(effects
				(font
					(size 1 1)
					(thickness 0.15)
				)
			)
		)
		(sheetname "/X710-AT2 power/")
		(sheetfile "x710-at2-power.kicad_sch")
		(attr smd)
		(fp_rect
			(start -0.925 -0.47)
			(end 0.925 0.47)
			(stroke
				(width 0.05)
				(type default)
			)
			(fill no)
			(layer "F.CrtYd")
		)
		(fp_line
			(start -0.494 0.248)
			(end -0.494 -0.25)
			(stroke
				(width 0.15)
				(type solid)
			)
			(layer "F.Fab")
		)
		(fp_line
			(start 0.504 0.248)
			(end -0.494 0.248)
			(stroke
				(width 0.15)
				(type solid)
			)
			(layer "F.Fab")
		)
		(fp_line
			(start -0.494 -0.25)
			(end 0.504 -0.25)
			(stroke
				(width 0.15)
				(type solid)
			)
			(layer "F.Fab")
		)
		(fp_line
			(start 0.504 -0.25)
			(end 0.504 0.248)
			(stroke
				(width 0.15)
				(type solid)
			)
			(layer "F.Fab")
		)
		(fp_text user "License: Apache-2.0"
			(at -0.939 5.799 270)
			(layer "F.Fab")
			(effects
				(font
					(size 0.7 0.7)
					(thickness 0.15)
				)
				(justify left bottom)
			)
		)
		(fp_text user "${REFERENCE}"
			(at -0.939 4.599 270)
			(layer "F.Fab")
			(effects
				(font
					(size 0.7 0.7)
					(thickness 0.15)
				)
				(justify left bottom)
			)
		)
		(fp_text user "Author: Antmicro"
			(at -0.939 3.399 270)
			(layer "F.Fab")
			(effects
				(font
					(size 0.7 0.7)
					(thickness 0.15)
				)
				(justify left bottom)
			)
		)
		(pad "1" smd roundrect
			(at -0.48 0 270)
			(size 0.59 0.64)
			(layers "F.Cu" "F.Mask" "F.Paste")
			(roundrect_rratio 0.25)
			(net 23 "GND")
			(pintype "passive")
		)
		(pad "2" smd roundrect
			(at 0.48 0 270)
			(size 0.59 0.64)
			(layers "F.Cu" "F.Mask" "F.Paste")
			(roundrect_rratio 0.25)
			(net 136 "+1V0")
			(pintype "passive")
		)
	)
	(footprint "antmicro-footprints:C_0603_1608Metric_EIA"
		(layer "F.Cu")
		(at 144.404999 99.774999 -90)
		(descr "Capacitor SMD 0603, IPC-7351 Density Level A")
		(tags "Capacitor 0603")
		(property "Reference" "C165"
			(at -9.274999 -34.845001 270)
			(layer "F.SilkS")
			(effects
				(font
					(size 0.7 0.7)
					(thickness 0.15)
				)
			)
		)
		(property "Value" "C_22u_16V_0603"
			(at -1.42757 1.770288 270)
			(layer "F.Fab")
			(effects
				(font
					(size 0.7 0.7)
					(thickness 0.15)
				)
				(justify left bottom)
			)
		)
		(property "Datasheet" "https://product.samsungsem.com/mlcc/CL10A226MO7JZN.do"
			(at 0 0 270)
			(layer "F.Fab")
			(hide yes)
			(effects
				(font
					(size 1.27 1.27)
					(thickness 0.15)
				)
			)
		)
		(property "Description" "SMD Multilayer Ceramic Capacitor"
			(at 0 0 270)
			(layer "F.Fab")
			(hide yes)
			(effects
				(font
					(size 1.27 1.27)
					(thickness 0.15)
				)
			)
		)
		(property "MPN" "CL10A226MO7JZNC"
			(at 0 0 270)
			(unlocked yes)
			(layer "F.Fab")
			(hide yes)
			(effects
				(font
					(size 1 1)
					(thickness 0.15)
				)
			)
		)
		(property "Manufacturer" "Samsung Electro-Mechanics"
			(at 0 0 270)
			(unlocked yes)
			(layer "F.Fab")
			(hide yes)
			(effects
				(font
					(size 1 1)
					(thickness 0.15)
				)
			)
		)
		(property "License" "Apache-2.0"
			(at 0 0 270)
			(unlocked yes)
			(layer "F.Fab")
			(hide yes)
			(effects
				(font
					(size 1 1)
					(thickness 0.15)
				)
			)
		)
		(property "Author" "Antmicro"
			(at 0 0 270)
			(unlocked yes)
			(layer "F.Fab")
			(hide yes)
			(effects
				(font
					(size 1 1)
					(thickness 0.15)
				)
			)
		)
		(property "Val" "22u"
			(at 0 0 270)
			(unlocked yes)
			(layer "F.Fab")
			(hide yes)
			(effects
				(font
					(size 1 1)
					(thickness 0.15)
				)
			)
		)
		(property "Voltage" "16V"
			(at 0 0 270)
			(unlocked yes)
			(layer "F.Fab")
			(hide yes)
			(effects
				(font
					(size 1 1)
					(thickness 0.15)
				)
			)
		)
		(property "Dielectric" ""
			(at 0 0 270)
			(unlocked yes)
			(layer "F.Fab")
			(hide yes)
			(effects
				(font
					(size 1 1)
					(thickness 0.15)
				)
			)
		)
		(sheetname "/X710-AT2 power/")
		(sheetfile "x710-at2-power.kicad_sch")
		(attr smd)
		(fp_line
			(start -0.15 0.55)
			(end 0.15 0.55)
			(stroke
				(width 0.15)
				(type solid)
			)
			(layer "F.SilkS")
		)
		(fp_line
			(start -0.15 -0.55)
			(end 0.15 -0.55)
			(stroke
				(width 0.15)
				(type solid)
			)
			(layer "F.SilkS")
		)
		(fp_rect
			(start -1.25 -0.65)
			(end 1.25 0.65)
			(stroke
				(width 0.05)
				(type solid)
			)
			(fill no)
			(layer "F.CrtYd")
		)
		(fp_rect
			(start -0.8 -0.45)
			(end 0.8 0.45)
			(stroke
				(width 0.15)
				(type solid)
			)
			(fill no)
			(layer "F.Fab")
		)
		(fp_text user "License: Apache-2.0"
			(at -1.682 5.895 270)
			(layer "F.Fab")
			(effects
				(font
					(size 0.7 0.7)
					(thickness 0.15)
				)
				(justify left bottom)
			)
		)
		(fp_text user "Author: Antmicro"
			(at -1.682 4.894 270)
			(layer "F.Fab")
			(effects
				(font
					(size 0.7 0.7)
					(thickness 0.15)
				)
				(justify left bottom)
			)
		)
		(fp_text user "${REFERENCE}"
			(at -1.682 3.895 270)
			(layer "F.Fab")
			(effects
				(font
					(size 0.7 0.7)
					(thickness 0.15)
				)
				(justify left bottom)
			)
		)
		(pad "1" smd roundrect
			(at -0.7 0 270)
			(size 0.8 1.1)
			(layers "F.Cu" "F.Mask" "F.Paste")
			(roundrect_rratio 0.2)
			(net 23 "GND")
			(pintype "passive")
		)
		(pad "2" smd roundrect
			(at 0.7 0 270)
			(size 0.8 1.1)
			(layers "F.Cu" "F.Mask" "F.Paste")
			(roundrect_rratio 0.2)
			(net 6 "DVDD")
			(pintype "passive")
		)
	)
	(footprint "antmicro-footprints:C_0402_1005Metric"
		(layer "F.Cu")
		(at 171.6 74 90)
		(descr "Capacitor SMD 0402")
		(tags "capacitor SMD 0402")
		(property "Reference" "C284"
			(at -1.2 3.6 90)
			(layer "F.SilkS")
			(effects
				(font
					(size 0.7 0.7)
					(thickness 0.15)
				)
				(justify left bottom)
			)
		)
		(property "Value" "C_10p_25V_0402"
			(at -1.022927 2.155213 90)
			(layer "F.Fab")
			(effects
				(font
					(size 0.7 0.7)
					(thickness 0.15)
				)
				(justify left bottom)
			)
		)
		(property "Datasheet" "https://spicat.kyocera-avx.com/product/mlcc/chartview/04023A100FAT2A/"
			(at 0 0 90)
			(layer "F.Fab")
			(hide yes)
			(effects
				(font
					(size 1.27 1.27)
					(thickness 0.15)
				)
			)
		)
		(property "Description" "Multilayer Ceramic Capacitors MLCC - SMD/SMT 25V 10pF C0G 0402 1%"
			(at 0 0 90)
			(layer "F.Fab")
			(hide yes)
			(effects
				(font
					(size 1.27 1.27)
					(thickness 0.15)
				)
			)
		)
		(property "MPN" "04023A100FAT2A"
			(at 0 0 90)
			(unlocked yes)
			(layer "F.Fab")
			(hide yes)
			(effects
				(font
					(size 1 1)
					(thickness 0.15)
				)
			)
		)
		(property "Manufacturer" "KYOCERA AVX"
			(at 0 0 90)
			(unlocked yes)
			(layer "F.Fab")
			(hide yes)
			(effects
				(font
					(size 1 1)
					(thickness 0.15)
				)
			)
		)
		(property "License" "Apache-2.0"
			(at 0 0 90)
			(unlocked yes)
			(layer "F.Fab")
			(hide yes)
			(effects
				(font
					(size 1 1)
					(thickness 0.15)
				)
			)
		)
		(property "Author" "Antmicro"
			(at 0 0 90)
			(unlocked yes)
			(layer "F.Fab")
			(hide yes)
			(effects
				(font
					(size 1 1)
					(thickness 0.15)
				)
			)
		)
		(property "Val" "10p"
			(at 0 0 90)
			(unlocked yes)
			(layer "F.Fab")
			(hide yes)
			(effects
				(font
					(size 1 1)
					(thickness 0.15)
				)
			)
		)
		(property "Voltage" "25V"
			(at 0 0 90)
			(unlocked yes)
			(layer "F.Fab")
			(hide yes)
			(effects
				(font
					(size 1 1)
					(thickness 0.15)
				)
			)
		)
		(property "Dielectric" "C0G"
			(at 0 0 90)
			(unlocked yes)
			(layer "F.Fab")
			(hide yes)
			(effects
				(font
					(size 1 1)
					(thickness 0.15)
				)
			)
		)
		(sheetname "/X710-AT2 10GbE/")
		(sheetfile "x710-at2-10gbe.kicad_sch")
		(attr smd)
		(fp_rect
			(start -0.925 -0.47)
			(end 0.925 0.47)
			(stroke
				(width 0.05)
				(type default)
			)
			(fill no)
			(layer "F.CrtYd")
		)
		(fp_line
			(start 0.504 -0.25)
			(end 0.504 0.248)
			(stroke
				(width 0.15)
				(type solid)
			)
			(layer "F.Fab")
		)
		(fp_line
			(start -0.494 -0.25)
			(end 0.504 -0.25)
			(stroke
				(width 0.15)
				(type solid)
			)
			(layer "F.Fab")
		)
		(fp_line
			(start 0.504 0.248)
			(end -0.494 0.248)
			(stroke
				(width 0.15)
				(type solid)
			)
			(layer "F.Fab")
		)
		(fp_line
			(start -0.494 0.248)
			(end -0.494 -0.25)
			(stroke
				(width 0.15)
				(type solid)
			)
			(layer "F.Fab")
		)
		(fp_text user "License: Apache-2.0"
			(at -0.939 5.799 90)
			(layer "F.Fab")
			(effects
				(font
					(size 0.7 0.7)
					(thickness 0.15)
				)
				(justify left bottom)
			)
		)
		(fp_text user "Author: Antmicro"
			(at -0.939 3.399 90)
			(layer "F.Fab")
			(effects
				(font
					(size 0.7 0.7)
					(thickness 0.15)
				)
				(justify left bottom)
			)
		)
		(fp_text user "${REFERENCE}"
			(at -0.939 4.599 90)
			(layer "F.Fab")
			(effects
				(font
					(size 0.7 0.7)
					(thickness 0.15)
				)
				(justify left bottom)
			)
		)
		(pad "1" smd roundrect
			(at -0.48 0 90)
			(size 0.59 0.64)
			(layers "F.Cu" "F.Mask" "F.Paste")
			(roundrect_rratio 0.25)
			(net 23 "GND")
			(pintype "passive")
		)
		(pad "2" smd roundrect
			(at 0.48 0 90)
			(size 0.59 0.64)
			(layers "F.Cu" "F.Mask" "F.Paste")
			(roundrect_rratio 0.25)
			(net 122 "/X710-AT2 10GbE/MDIO0_I2C0.MDIO")
			(pintype "passive")
		)
	)
	(footprint "antmicro-footprints:C_0402_1005Metric"
		(layer "F.Cu")
		(at 139.5 111.85)
		(descr "Capacitor SMD 0402")
		(tags "capacitor SMD 0402")
		(property "Reference" "C115"
			(at 16 16.799998 0)
			(layer "F.SilkS")
			(effects
				(font
					(size 0.7 0.7)
					(thickness 0.15)
				)
			)
		)
		(property "Value" "C_100n_0402"
			(at -1.022927 2.155213 0)
			(layer "F.Fab")
			(effects
				(font
					(size 0.7 0.7)
					(thickness 0.15)
				)
				(justify left bottom)
			)
		)
		(property "Datasheet" "https://www.murata.com/products/productdetail?partno=GRM155R61H104KE14%23"
			(at 0 0 0)
			(layer "F.Fab")
			(hide yes)
			(effects
				(font
					(size 1.27 1.27)
					(thickness 0.15)
				)
			)
		)
		(property "Description" "SMD Multilayer Ceramic Capacitor, 0.1 µF, 50 V, 0402 [1005 Metric], ± 10%, X5R, GRM Series"
			(at 0 0 0)
			(layer "F.Fab")
			(hide yes)
			(effects
				(font
					(size 1.27 1.27)
					(thickness 0.15)
				)
			)
		)
		(property "MPN" "GRM155R61H104KE14D"
			(at 0 0 0)
			(unlocked yes)
			(layer "F.Fab")
			(hide yes)
			(effects
				(font
					(size 1 1)
					(thickness 0.15)
				)
			)
		)
		(property "Manufacturer" "Murata"
			(at 0 0 0)
			(unlocked yes)
			(layer "F.Fab")
			(hide yes)
			(effects
				(font
					(size 1 1)
					(thickness 0.15)
				)
			)
		)
		(property "License" "Apache-2.0"
			(at 0 0 0)
			(unlocked yes)
			(layer "F.Fab")
			(hide yes)
			(effects
				(font
					(size 1 1)
					(thickness 0.15)
				)
			)
		)
		(property "Author" "Antmicro"
			(at 0 0 0)
			(unlocked yes)
			(layer "F.Fab")
			(hide yes)
			(effects
				(font
					(size 1 1)
					(thickness 0.15)
				)
			)
		)
		(property "Val" "100n"
			(at 0 0 0)
			(unlocked yes)
			(layer "F.Fab")
			(hide yes)
			(effects
				(font
					(size 1 1)
					(thickness 0.15)
				)
			)
		)
		(property "Voltage" "50V"
			(at 0 0 0)
			(unlocked yes)
			(layer "F.Fab")
			(hide yes)
			(effects
				(font
					(size 1 1)
					(thickness 0.15)
				)
			)
		)
		(property "Dielectric" "X5R"
			(at 0 0 0)
			(unlocked yes)
			(layer "F.Fab")
			(hide yes)
			(effects
				(font
					(size 1 1)
					(thickness 0.15)
				)
			)
		)
		(sheetname "/X710 DCDC converters/")
		(sheetfile "DCDC_converters_X710.kicad_sch")
		(attr smd)
		(fp_rect
			(start -0.925 -0.47)
			(end 0.925 0.47)
			(stroke
				(width 0.05)
				(type default)
			)
			(fill no)
			(layer "F.CrtYd")
		)
		(fp_line
			(start -0.494 -0.25)
			(end 0.504 -0.25)
			(stroke
				(width 0.15)
				(type solid)
			)
			(layer "F.Fab")
		)
		(fp_line
			(start -0.494 0.248)
			(end -0.494 -0.25)
			(stroke
				(width 0.15)
				(type solid)
			)
			(layer "F.Fab")
		)
		(fp_line
			(start 0.504 -0.25)
			(end 0.504 0.248)
			(stroke
				(width 0.15)
				(type solid)
			)
			(layer "F.Fab")
		)
		(fp_line
			(start 0.504 0.248)
			(end -0.494 0.248)
			(stroke
				(width 0.15)
				(type solid)
			)
			(layer "F.Fab")
		)
		(fp_text user "Author: Antmicro"
			(at -0.939 3.399 0)
			(layer "F.Fab")
			(effects
				(font
					(size 0.7 0.7)
					(thickness 0.15)
				)
				(justify left bottom)
			)
		)
		(fp_text user "License: Apache-2.0"
			(at -0.939 5.799 0)
			(layer "F.Fab")
			(effects
				(font
					(size 0.7 0.7)
					(thickness 0.15)
				)
				(justify left bottom)
			)
		)
		(fp_text user "${REFERENCE}"
			(at -0.939 4.599 0)
			(layer "F.Fab")
			(effects
				(font
					(size 0.7 0.7)
					(thickness 0.15)
				)
				(justify left bottom)
			)
		)
		(pad "1" smd roundrect
			(at -0.48 0)
			(size 0.59 0.64)
			(layers "F.Cu" "F.Mask" "F.Paste")
			(roundrect_rratio 0.25)
			(net 23 "GND")
			(pintype "passive")
		)
		(pad "2" smd roundrect
			(at 0.48 0)
			(size 0.59 0.64)
			(layers "F.Cu" "F.Mask" "F.Paste")
			(roundrect_rratio 0.25)
			(net 40 "+5V")
			(pintype "passive")
		)
	)
	(footprint "antmicro-footprints:C_0402_1005Metric"
		(layer "F.Cu")
		(at 119.65 106.25 180)
		(descr "Capacitor SMD 0402")
		(tags "capacitor SMD 0402")
		(property "Reference" "C10"
			(at -6.55 -6.75 180)
			(layer "F.SilkS")
			(effects
				(font
					(size 0.7 0.7)
					(thickness 0.15)
				)
			)
		)
		(property "Value" "C_100n_0402"
			(at -1.022927 2.155213 180)
			(layer "F.Fab")
			(effects
				(font
					(size 0.7 0.7)
					(thickness 0.15)
				)
				(justify left bottom)
			)
		)
		(property "Datasheet" "https://www.murata.com/products/productdetail?partno=GRM155R61H104KE14%23"
			(at 0 0 180)
			(layer "F.Fab")
			(hide yes)
			(effects
				(font
					(size 1.27 1.27)
					(thickness 0.15)
				)
			)
		)
		(property "Description" "SMD Multilayer Ceramic Capacitor, 0.1 µF, 50 V, 0402 [1005 Metric], ± 10%, X5R, GRM Series"
			(at 0 0 180)
			(layer "F.Fab")
			(hide yes)
			(effects
				(font
					(size 1.27 1.27)
					(thickness 0.15)
				)
			)
		)
		(property "MPN" "GRM155R61H104KE14D"
			(at 0 0 180)
			(unlocked yes)
			(layer "F.Fab")
			(hide yes)
			(effects
				(font
					(size 1 1)
					(thickness 0.15)
				)
			)
		)
		(property "Manufacturer" "Murata"
			(at 0 0 180)
			(unlocked yes)
			(layer "F.Fab")
			(hide yes)
			(effects
				(font
					(size 1 1)
					(thickness 0.15)
				)
			)
		)
		(property "License" "Apache-2.0"
			(at 0 0 180)
			(unlocked yes)
			(layer "F.Fab")
			(hide yes)
			(effects
				(font
					(size 1 1)
					(thickness 0.15)
				)
			)
		)
		(property "Val" "100n"
			(at 0 0 180)
			(unlocked yes)
			(layer "F.Fab")
			(hide yes)
			(effects
				(font
					(size 1 1)
					(thickness 0.15)
				)
			)
		)
		(property "Voltage" "50V"
			(at 0 0 180)
			(unlocked yes)
			(layer "F.Fab")
			(hide yes)
			(effects
				(font
					(size 1 1)
					(thickness 0.15)
				)
			)
		)
		(property "Dielectric" "X5R"
			(at 0 0 180)
			(unlocked yes)
			(layer "F.Fab")
			(hide yes)
			(effects
				(font
					(size 1 1)
					(thickness 0.15)
				)
			)
		)
		(property "Author" "Antmicro"
			(at 0 0 180)
			(unlocked yes)
			(layer "F.Fab")
			(hide yes)
			(effects
				(font
					(size 1 1)
					(thickness 0.15)
				)
			)
		)
		(sheetname "/PD and TB DC-DC/")
		(sheetfile "PD_and_TB_DC_DC.kicad_sch")
		(attr smd)
		(fp_rect
			(start -0.925 -0.47)
			(end 0.925 0.47)
			(stroke
				(width 0.05)
				(type default)
			)
			(fill no)
			(layer "F.CrtYd")
		)
		(fp_line
			(start 0.504 0.248)
			(end -0.494 0.248)
			(stroke
				(width 0.15)
				(type solid)
			)
			(layer "F.Fab")
		)
		(fp_line
			(start 0.504 -0.25)
			(end 0.504 0.248)
			(stroke
				(width 0.15)
				(type solid)
			)
			(layer "F.Fab")
		)
		(fp_line
			(start -0.494 0.248)
			(end -0.494 -0.25)
			(stroke
				(width 0.15)
				(type solid)
			)
			(layer "F.Fab")
		)
		(fp_line
			(start -0.494 -0.25)
			(end 0.504 -0.25)
			(stroke
				(width 0.15)
				(type solid)
			)
			(layer "F.Fab")
		)
		(fp_text user "License: Apache-2.0"
			(at -0.939 5.799 180)
			(layer "F.Fab")
			(effects
				(font
					(size 0.7 0.7)
					(thickness 0.15)
				)
				(justify left bottom)
			)
		)
		(fp_text user "${REFERENCE}"
			(at -0.939 4.599 180)
			(layer "F.Fab")
			(effects
				(font
					(size 0.7 0.7)
					(thickness 0.15)
				)
				(justify left bottom)
			)
		)
		(fp_text user "Author: Antmicro"
			(at -0.939 3.399 180)
			(layer "F.Fab")
			(effects
				(font
					(size 0.7 0.7)
					(thickness 0.15)
				)
				(justify left bottom)
			)
		)
		(pad "1" smd roundrect
			(at -0.48 0 180)
			(size 0.59 0.64)
			(layers "F.Cu" "F.Mask" "F.Paste")
			(roundrect_rratio 0.25)
			(net 23 "GND")
			(pintype "passive")
		)
		(pad "2" smd roundrect
			(at 0.48 0 180)
			(size 0.59 0.64)
			(layers "F.Cu" "F.Mask" "F.Paste")
			(roundrect_rratio 0.25)
			(net 161 "Net-(U2-VIN)")
			(pintype "passive")
		)
	)
	(footprint "antmicro-footprints:R_0402_1005Metric"
		(layer "F.Cu")
		(at 136.149999 112.150001)
		(descr "Resistor SMD 0402")
		(tags "resistor SMD 0402")
		(property "Reference" "R101"
			(at 16.549997 17.25 0)
			(layer "F.SilkS")
			(effects
				(font
					(size 0.7 0.7)
					(thickness 0.15)
				)
			)
		)
		(property "Value" "R_30k_0402"
			(at -1.011843 1.772047 0)
			(layer "F.Fab")
			(effects
				(font
					(size 0.7 0.7)
					(thickness 0.15)
				)
				(justify left bottom)
			)
		)
		(property "Datasheet" "https://www.bourns.com/docs/product-datasheets/cr.pdf"
			(at 0 0 0)
			(layer "F.Fab")
			(hide yes)
			(effects
				(font
					(size 1.27 1.27)
					(thickness 0.15)
				)
			)
		)
		(property "Description" "SMD Chip Resistor, 30 kohm, ± 1%, 63 mW, 0402 [1005 Metric], Thick Film, General Purpose"
			(at 0 0 0)
			(layer "F.Fab")
			(hide yes)
			(effects
				(font
					(size 1.27 1.27)
					(thickness 0.15)
				)
			)
		)
		(property "MPN" "CR0402-FX-3002GLF"
			(at 0 0 0)
			(unlocked yes)
			(layer "F.Fab")
			(hide yes)
			(effects
				(font
					(size 1 1)
					(thickness 0.15)
				)
			)
		)
		(property "Manufacturer" "Bourns"
			(at 0 0 0)
			(unlocked yes)
			(layer "F.Fab")
			(hide yes)
			(effects
				(font
					(size 1 1)
					(thickness 0.15)
				)
			)
		)
		(property "License" "Apache-2.0"
			(at 0 0 0)
			(unlocked yes)
			(layer "F.Fab")
			(hide yes)
			(effects
				(font
					(size 1 1)
					(thickness 0.15)
				)
			)
		)
		(property "Author" "Antmicro"
			(at 0 0 0)
			(unlocked yes)
			(layer "F.Fab")
			(hide yes)
			(effects
				(font
					(size 1 1)
					(thickness 0.15)
				)
			)
		)
		(property "Val" "30k"
			(at 0 0 0)
			(unlocked yes)
			(layer "F.Fab")
			(hide yes)
			(effects
				(font
					(size 1 1)
					(thickness 0.15)
				)
			)
		)
		(property "Tolerance" "1%"
			(at 0 0 0)
			(unlocked yes)
			(layer "F.Fab")
			(hide yes)
			(effects
				(font
					(size 1 1)
					(thickness 0.15)
				)
			)
		)
		(sheetname "/X710 DCDC converters/")
		(sheetfile "DCDC_converters_X710.kicad_sch")
		(attr smd)
		(fp_rect
			(start -0.925 -0.47)
			(end 0.925 0.47)
			(stroke
				(width 0.05)
				(type default)
			)
			(fill no)
			(layer "F.CrtYd")
		)
		(fp_rect
			(start -0.5 -0.25)
			(end 0.5 0.25)
			(stroke
				(width 0.15)
				(type solid)
			)
			(fill no)
			(layer "F.Fab")
		)
		(fp_text user "Author: Antmicro"
			(at -0.95 4.169 0)
			(layer "F.Fab")
			(effects
				(font
					(size 0.7 0.7)
					(thickness 0.15)
				)
				(justify left bottom)
			)
		)
		(fp_text user "License: Apache-2.0"
			(at -0.95 5.169 0)
			(layer "F.Fab")
			(effects
				(font
					(size 0.7 0.7)
					(thickness 0.15)
				)
				(justify left bottom)
			)
		)
		(fp_text user "${REFERENCE}"
			(at -0.95 3.168 0)
			(layer "F.Fab")
			(effects
				(font
					(size 0.7 0.7)
					(thickness 0.15)
				)
				(justify left bottom)
			)
		)
		(pad "1" smd roundrect
			(at -0.48 0)
			(size 0.59 0.64)
			(layers "F.Cu" "F.Mask" "F.Paste")
			(roundrect_rratio 0.25)
			(net 23 "GND")
			(pintype "passive")
		)
		(pad "2" smd roundrect
			(at 0.48 0)
			(size 0.59 0.64)
			(layers "F.Cu" "F.Mask" "F.Paste")
			(roundrect_rratio 0.25)
			(net 336 "/X710 DCDC converters/VCCD_FB")
			(pintype "passive")
		)
	)
	(footprint "antmicro-footprints:R_0402_1005Metric"
		(layer "F.Cu")
		(at 117 69.9 180)
		(descr "Resistor SMD 0402")
		(tags "resistor SMD 0402")
		(property "Reference" "R218"
			(at -3.6 10.5 180)
			(layer "F.SilkS")
			(effects
				(font
					(size 0.7 0.7)
					(thickness 0.15)
				)
				(justify left bottom)
			)
		)
		(property "Value" "R_10k_0402"
			(at -1.011843 1.772047 180)
			(layer "F.Fab")
			(effects
				(font
					(size 0.7 0.7)
					(thickness 0.15)
				)
				(justify left bottom)
			)
		)
		(property "Datasheet" "https://www.bourns.com/docs/product-datasheets/cr.pdf"
			(at 0 0 180)
			(layer "F.Fab")
			(hide yes)
			(effects
				(font
					(size 1.27 1.27)
					(thickness 0.15)
				)
			)
		)
		(property "Description" "SMD Chip Resistor, 10 kohm, ± 1%, 62.5 mW, 0402 [1005 Metric], Thick Film, General Purpose"
			(at 0 0 180)
			(layer "F.Fab")
			(hide yes)
			(effects
				(font
					(size 1.27 1.27)
					(thickness 0.15)
				)
			)
		)
		(property "MPN" "CR0402-FX-1002GLF"
			(at 0 0 180)
			(unlocked yes)
			(layer "F.Fab")
			(hide yes)
			(effects
				(font
					(size 1 1)
					(thickness 0.15)
				)
			)
		)
		(property "Manufacturer" "Bourns"
			(at 0 0 180)
			(unlocked yes)
			(layer "F.Fab")
			(hide yes)
			(effects
				(font
					(size 1 1)
					(thickness 0.15)
				)
			)
		)
		(property "License" "Apache-2.0"
			(at 0 0 180)
			(unlocked yes)
			(layer "F.Fab")
			(hide yes)
			(effects
				(font
					(size 1 1)
					(thickness 0.15)
				)
			)
		)
		(property "Author" "Antmicro"
			(at 0 0 180)
			(unlocked yes)
			(layer "F.Fab")
			(hide yes)
			(effects
				(font
					(size 1 1)
					(thickness 0.15)
				)
			)
		)
		(property "Val" "10k"
			(at 0 0 180)
			(unlocked yes)
			(layer "F.Fab")
			(hide yes)
			(effects
				(font
					(size 1 1)
					(thickness 0.15)
				)
			)
		)
		(property "Tolerance" "1%"
			(at 0 0 180)
			(unlocked yes)
			(layer "F.Fab")
			(hide yes)
			(effects
				(font
					(size 1 1)
					(thickness 0.15)
				)
			)
		)
		(sheetname "/Fan controller/")
		(sheetfile "fan-controller.kicad_sch")
		(attr smd)
		(fp_rect
			(start -0.925 -0.47)
			(end 0.925 0.47)
			(stroke
				(width 0.05)
				(type default)
			)
			(fill no)
			(layer "F.CrtYd")
		)
		(fp_rect
			(start -0.5 -0.25)
			(end 0.5 0.25)
			(stroke
				(width 0.15)
				(type solid)
			)
			(fill no)
			(layer "F.Fab")
		)
		(fp_text user "${REFERENCE}"
			(at -0.95 3.168 180)
			(layer "F.Fab")
			(effects
				(font
					(size 0.7 0.7)
					(thickness 0.15)
				)
				(justify left bottom)
			)
		)
		(fp_text user "License: Apache-2.0"
			(at -0.95 5.169 180)
			(layer "F.Fab")
			(effects
				(font
					(size 0.7 0.7)
					(thickness 0.15)
				)
				(justify left bottom)
			)
		)
		(fp_text user "Author: Antmicro"
			(at -0.95 4.169 180)
			(layer "F.Fab")
			(effects
				(font
					(size 0.7 0.7)
					(thickness 0.15)
				)
				(justify left bottom)
			)
		)
		(pad "1" smd roundrect
			(at -0.48 0 180)
			(size 0.59 0.64)
			(layers "F.Cu" "F.Mask" "F.Paste")
			(roundrect_rratio 0.25)
			(net 157 "/Fan controller/DMIN")
			(pintype "passive")
		)
		(pad "2" smd roundrect
			(at 0.48 0 180)
			(size 0.59 0.64)
			(layers "F.Cu" "F.Mask" "F.Paste")
			(roundrect_rratio 0.25)
			(net 40 "+5V")
			(pintype "passive")
		)
	)
	(footprint "antmicro-footprints:VQFN-HR-9_2x1.5mm"
		(layer "F.Cu")
		(at 139.049999 110.149999)
		(property "Reference" "U10"
			(at 16 17.049998 0)
			(layer "F.SilkS")
			(effects
				(font
					(size 0.7 0.7)
					(thickness 0.15)
				)
			)
		)
		(property "Value" "TPS566231P"
			(at -1.65 2.15 0)
			(layer "F.Fab")
			(effects
				(font
					(size 0.7 0.7)
					(thickness 0.15)
				)
				(justify left bottom)
			)
		)
		(property "Datasheet" "https://www.ti.com/lit/ds/symlink/tps566231.pdf"
			(at 0 -0.045 0)
			(layer "F.Fab")
			(effects
				(font
					(size 0.7 0.7)
					(thickness 0.15)
				)
				(justify left bottom)
			)
		)
		(property "Description" "Switching Voltage Regulators 3-V to 18-V, 6-A synchronous buck converter"
			(at -1.45 3.65 0)
			(layer "F.Fab")
			(effects
				(font
					(size 0.7 0.7)
					(thickness 0.15)
				)
				(justify left bottom)
			)
		)
		(property "Manufacturer" "Texas Instruments"
			(at 0 0 0)
			(unlocked yes)
			(layer "F.Fab")
			(hide yes)
			(effects
				(font
					(size 1 1)
					(thickness 0.15)
				)
			)
		)
		(property "MPN" "TPS566231PRQFR"
			(at 0 0 0)
			(unlocked yes)
			(layer "F.Fab")
			(hide yes)
			(effects
				(font
					(size 1 1)
					(thickness 0.15)
				)
			)
		)
		(property "Author" "Antmicro"
			(at 0 0 0)
			(unlocked yes)
			(layer "F.Fab")
			(hide yes)
			(effects
				(font
					(size 1 1)
					(thickness 0.15)
				)
			)
		)
		(property "License" "Apache-2.0"
			(at 0 0 0)
			(unlocked yes)
			(layer "F.Fab")
			(hide yes)
			(effects
				(font
					(size 1 1)
					(thickness 0.15)
				)
			)
		)
		(sheetname "/X710 DCDC converters/")
		(sheetfile "DCDC_converters_X710.kicad_sch")
		(attr smd)
		(fp_line
			(start -1 -0.945)
			(end -0.695 -0.945)
			(stroke
				(width 0.15)
				(type solid)
			)
			(layer "F.SilkS")
		)
		(fp_line
			(start -1 0.945)
			(end -0.695 0.945)
			(stroke
				(width 0.15)
				(type solid)
			)
			(layer "F.SilkS")
		)
		(fp_line
			(start 1 -0.945)
			(end 0.695 -0.945)
			(stroke
				(width 0.15)
				(type solid)
			)
			(layer "F.SilkS")
		)
		(fp_line
			(start 1 0.945)
			(end 0.2 0.945)
			(stroke
				(width 0.15)
				(type solid)
			)
			(layer "F.SilkS")
		)
		(fp_circle
			(center -1.18 -0.77)
			(end -1.13 -0.77)
			(stroke
				(width 0.15)
				(type solid)
			)
			(fill yes)
			(layer "F.SilkS")
		)
		(fp_rect
			(start -1.3 -1.05)
			(end 1.3 1.05)
			(stroke
				(width 0.05)
				(type solid)
			)
			(fill no)
			(layer "F.CrtYd")
		)
		(fp_rect
			(start -1 -0.75)
			(end 1 0.75)
			(stroke
				(width 0.15)
				(type solid)
			)
			(fill no)
			(layer "F.Fab")
		)
		(fp_text user "${REFERENCE}"
			(at -1.65 3.35 0)
			(layer "F.Fab")
			(effects
				(font
					(size 0.7 0.7)
					(thickness 0.15)
				)
				(justify left bottom)
			)
		)
		(fp_text user "Author: Antmicro"
			(at -1.65 4.55 0)
			(layer "F.Fab")
			(effects
				(font
					(size 0.7 0.7)
					(thickness 0.15)
				)
				(justify left bottom)
			)
		)
		(fp_text user "License: Apache-2.0"
			(at -1.65 5.75 0)
			(layer "F.Fab")
			(effects
				(font
					(size 0.7 0.7)
					(thickness 0.15)
				)
				(justify left bottom)
			)
		)
		(pad "1" smd roundrect
			(at -0.925 -0.5)
			(size 0.55 0.25)
			(layers "F.Cu" "F.Mask" "F.Paste")
			(roundrect_rratio 0.125)
			(net 83 "/X710 DCDC converters/VCCD_VCC")
			(pinfunction "V_{CC}")
			(pintype "passive")
		)
		(pad "2" smd roundrect
			(at -0.925 0)
			(size 0.55 0.25)
			(layers "F.Cu" "F.Mask" "F.Paste")
			(roundrect_rratio 0.125)
			(net 336 "/X710 DCDC converters/VCCD_FB")
			(pinfunction "FB")
			(pintype "input")
		)
		(pad "3" smd roundrect
			(at -0.925 0.5)
			(size 0.55 0.25)
			(layers "F.Cu" "F.Mask" "F.Paste")
			(roundrect_rratio 0.125)
			(net 382 "/X710 DCDC converters/VCCD_EN")
			(pinfunction "EN")
			(pintype "input")
		)
		(pad "4" smd roundrect
			(at -0.25 0.45)
			(size 0.25 1)
			(layers "F.Cu" "F.Mask" "F.Paste")
			(roundrect_rratio 0.125)
			(net 23 "GND")
			(pinfunction "PGND")
			(pintype "power_in")
		)
		(pad "5" smd roundrect
			(at 0.925 0.5)
			(size 0.55 0.25)
			(layers "F.Cu" "F.Mask" "F.Paste")
			(roundrect_rratio 0.125)
			(net 40 "+5V")
			(pinfunction "V_{IN}")
			(pintype "power_in")
		)
		(pad "6" smd roundrect
			(at 0.925 0)
			(size 0.55 0.25)
			(layers "F.Cu" "F.Mask" "F.Paste")
			(roundrect_rratio 0.125)
			(net 40 "+5V")
			(pinfunction "V_{IN}")
			(pintype "passive")
		)
		(pad "7" smd roundrect
			(at 0.925 -0.5)
			(size 0.55 0.25)
			(layers "F.Cu" "F.Mask" "F.Paste")
			(roundrect_rratio 0.125)
			(net 119 "/X710 DCDC converters/VCCD_BST")
			(pinfunction "BST")
			(pintype "passive")
		)
		(pad "8" smd roundrect
			(at 0.25 -0.3)
			(size 0.25 1.3)
			(layers "F.Cu" "F.Mask" "F.Paste")
			(roundrect_rratio 0.125)
			(net 153 "/X710 DCDC converters/VCCD_SW")
			(pinfunction "SW")
			(pintype "power_out")
		)
		(pad "9" smd roundrect
			(at -0.25 -0.675)
			(size 0.25 0.55)
			(layers "F.Cu" "F.Mask" "F.Paste")
			(roundrect_rratio 0.125)
			(net 379 "/X710 DCDC converters/VCCD_PG")
			(pinfunction "PG")
			(pintype "passive")
		)
	)
	(footprint "antmicro-footprints:C_0603_1608Metric"
		(layer "F.Cu")
		(at 150.305 68.574999 -90)
		(descr "Capacitor SMD 0603")
		(tags "capacitor 0603")
		(property "Reference" "C220"
			(at -12.274999 -20.045 270)
			(layer "F.SilkS")
			(effects
				(font
					(size 0.7 0.7)
					(thickness 0.15)
				)
			)
		)
		(property "Value" "C_10u_10V_X7R_0603"
			(at -1.42757 1.770288 270)
			(layer "F.Fab")
			(effects
				(font
					(size 0.7 0.7)
					(thickness 0.15)
				)
				(justify left bottom)
			)
		)
		(property "Datasheet" "https://www.murata.com/products/productdetail?partno=GRM188Z71A106KA73%23"
			(at 0 0 270)
			(layer "F.Fab")
			(hide yes)
			(effects
				(font
					(size 1.27 1.27)
					(thickness 0.15)
				)
			)
		)
		(property "Description" "SMD Multilayer Ceramic Capacitor,  10µF, 10V, 0603, ±10%, X7R"
			(at 0 0 270)
			(layer "F.Fab")
			(hide yes)
			(effects
				(font
					(size 1.27 1.27)
					(thickness 0.15)
				)
			)
		)
		(property "MPN" "GRM188Z71A106KA73D"
			(at 0 0 270)
			(unlocked yes)
			(layer "F.Fab")
			(hide yes)
			(effects
				(font
					(size 1 1)
					(thickness 0.15)
				)
			)
		)
		(property "Val" "10u"
			(at 0 0 270)
			(unlocked yes)
			(layer "F.Fab")
			(hide yes)
			(effects
				(font
					(size 1 1)
					(thickness 0.15)
				)
			)
		)
		(property "Voltage" "10V"
			(at 0 0 270)
			(unlocked yes)
			(layer "F.Fab")
			(hide yes)
			(effects
				(font
					(size 1 1)
					(thickness 0.15)
				)
			)
		)
		(property "Dielectric" "X7R"
			(at 0 0 270)
			(unlocked yes)
			(layer "F.Fab")
			(hide yes)
			(effects
				(font
					(size 1 1)
					(thickness 0.15)
				)
			)
		)
		(property "Manufacturer" "Murata"
			(at 0 0 270)
			(unlocked yes)
			(layer "F.Fab")
			(hide yes)
			(effects
				(font
					(size 1 1)
					(thickness 0.15)
				)
			)
		)
		(property "License" "Apache-2.0"
			(at 0 0 270)
			(unlocked yes)
			(layer "F.Fab")
			(hide yes)
			(effects
				(font
					(size 1 1)
					(thickness 0.15)
				)
			)
		)
		(property "Author" "Antmicro"
			(at 0 0 270)
			(unlocked yes)
			(layer "F.Fab")
			(hide yes)
			(effects
				(font
					(size 1 1)
					(thickness 0.15)
				)
			)
		)
		(sheetname "/X710-AT2 power/")
		(sheetfile "x710-at2-power.kicad_sch")
		(attr smd)
		(fp_line
			(start -0.15 0.4)
			(end 0.15 0.4)
			(stroke
				(width 0.15)
				(type solid)
			)
			(layer "F.SilkS")
		)
		(fp_line
			(start -0.15 -0.4)
			(end 0.15 -0.4)
			(stroke
				(width 0.15)
				(type solid)
			)
			(layer "F.SilkS")
		)
		(fp_rect
			(start -1.25 -0.65)
			(end 1.25 0.65)
			(stroke
				(width 0.05)
				(type solid)
			)
			(fill no)
			(layer "F.CrtYd")
		)
		(fp_rect
			(start -0.8 -0.4)
			(end 0.8 0.4)
			(stroke
				(width 0.15)
				(type solid)
			)
			(fill no)
			(layer "F.Fab")
		)
		(fp_text user "Author: Antmicro"
			(at -1.682 4.894 270)
			(layer "F.Fab")
			(effects
				(font
					(size 0.7 0.7)
					(thickness 0.15)
				)
				(justify left bottom)
			)
		)
		(fp_text user "${REFERENCE}"
			(at -1.682 3.895 270)
			(layer "F.Fab")
			(effects
				(font
					(size 0.7 0.7)
					(thickness 0.15)
				)
				(justify left bottom)
			)
		)
		(fp_text user "License: Apache-2.0"
			(at -1.682 5.895 270)
			(layer "F.Fab")
			(effects
				(font
					(size 0.7 0.7)
					(thickness 0.15)
				)
				(justify left bottom)
			)
		)
		(pad "1" smd roundrect
			(at -0.7 0 270)
			(size 0.8 1)
			(layers "F.Cu" "F.Mask" "F.Paste")
			(roundrect_rratio 0.2)
			(net 23 "GND")
			(pintype "passive")
		)
		(pad "2" smd roundrect
			(at 0.7 0 270)
			(size 0.8 1)
			(layers "F.Cu" "F.Mask" "F.Paste")
			(roundrect_rratio 0.2)
			(net 7 "+3V3")
			(pintype "passive")
		)
	)
	(footprint "antmicro-footprints:C_0805_2012Metric"
		(layer "F.Cu")
		(at 165.304999 95.174998 180)
		(descr "Capacitor SMD 0805")
		(tags "capacitor SMD 0805")
		(property "Reference" "C171"
			(at -7.695 0 180)
			(layer "F.SilkS")
			(effects
				(font
					(size 0.7 0.7)
					(thickness 0.15)
				)
			)
		)
		(property "Value" "C_100u_0805"
			(at -2.055717 1.963152 180)
			(layer "F.Fab")
			(effects
				(font
					(size 0.7 0.7)
					(thickness 0.15)
				)
				(justify left bottom)
			)
		)
		(property "Datasheet" "https://www.murata.com/products/productdetail?partno=GRM21BR60J107ME15%23"
			(at 0 0 180)
			(layer "F.Fab")
			(hide yes)
			(effects
				(font
					(size 1.27 1.27)
					(thickness 0.15)
				)
			)
		)
		(property "Description" "SMD Multilayer Ceramic Capacitor, 100 µF, 6.3 V, 0805 [2012 Metric], ± 20%, X5R, GRM Series"
			(at 0 0 180)
			(layer "F.Fab")
			(hide yes)
			(effects
				(font
					(size 1.27 1.27)
					(thickness 0.15)
				)
			)
		)
		(property "MPN" "GRM21BR60J107ME15L"
			(at 0 0 180)
			(unlocked yes)
			(layer "F.Fab")
			(hide yes)
			(effects
				(font
					(size 1 1)
					(thickness 0.15)
				)
			)
		)
		(property "Manufacturer" "Murata"
			(at 0 0 180)
			(unlocked yes)
			(layer "F.Fab")
			(hide yes)
			(effects
				(font
					(size 1 1)
					(thickness 0.15)
				)
			)
		)
		(property "License" "Apache-2.0"
			(at 0 0 180)
			(unlocked yes)
			(layer "F.Fab")
			(hide yes)
			(effects
				(font
					(size 1 1)
					(thickness 0.15)
				)
			)
		)
		(property "Author" "Antmicro"
			(at 0 0 180)
			(unlocked yes)
			(layer "F.Fab")
			(hide yes)
			(effects
				(font
					(size 1 1)
					(thickness 0.15)
				)
			)
		)
		(property "Val" "100u"
			(at 0 0 180)
			(unlocked yes)
			(layer "F.Fab")
			(hide yes)
			(effects
				(font
					(size 1 1)
					(thickness 0.15)
				)
			)
		)
		(property "Voltage" ""
			(at 0 0 180)
			(unlocked yes)
			(layer "F.Fab")
			(hide yes)
			(effects
				(font
					(size 1 1)
					(thickness 0.15)
				)
			)
		)
		(property "Dielectric" ""
			(at 0 0 180)
			(unlocked yes)
			(layer "F.Fab")
			(hide yes)
			(effects
				(font
					(size 1 1)
					(thickness 0.15)
				)
			)
		)
		(property "Public" "False"
			(at 0 0 180)
			(unlocked yes)
			(layer "F.Fab")
			(hide yes)
			(effects
				(font
					(size 1 1)
					(thickness 0.15)
				)
			)
		)
		(sheetname "/X710-AT2 power/")
		(sheetfile "x710-at2-power.kicad_sch")
		(attr smd)
		(fp_line
			(start -0.3 0.7)
			(end 0.3 0.7)
			(stroke
				(width 0.15)
				(type solid)
			)
			(layer "F.SilkS")
		)
		(fp_line
			(start -0.3 -0.7)
			(end 0.3 -0.7)
			(stroke
				(width 0.15)
				(type solid)
			)
			(layer "F.SilkS")
		)
		(fp_rect
			(start 1.95 -0.9)
			(end -1.95 0.9)
			(stroke
				(width 0.05)
				(type default)
			)
			(fill no)
			(layer "F.CrtYd")
		)
		(fp_rect
			(start -0.95 -0.675)
			(end 0.95 0.675)
			(stroke
				(width 0.15)
				(type solid)
			)
			(fill no)
			(layer "F.Fab")
		)
		(fp_text user "License: Apache-2.0"
			(at -1.9 4.947 180)
			(layer "F.Fab")
			(effects
				(font
					(size 0.7 0.7)
					(thickness 0.15)
				)
				(justify left bottom)
			)
		)
		(fp_text user "Author: Antmicro"
			(at -1.9 5.947 180)
			(layer "F.Fab")
			(effects
				(font
					(size 0.7 0.7)
					(thickness 0.15)
				)
				(justify left bottom)
			)
		)
		(fp_text user "${REFERENCE}"
			(at -1.9 3.947 180)
			(layer "F.Fab")
			(effects
				(font
					(size 0.7 0.7)
					(thickness 0.15)
				)
				(justify left bottom)
			)
		)
		(pad "1" smd roundrect
			(at -1.1 0 180)
			(size 1.2 1.3)
			(layers "F.Cu" "F.Mask" "F.Paste")
			(roundrect_rratio 0.25)
			(net 23 "GND")
			(pintype "passive")
		)
		(pad "2" smd roundrect
			(at 1.1 0 180)
			(size 1.2 1.3)
			(layers "F.Cu" "F.Mask" "F.Paste")
			(roundrect_rratio 0.25)
			(net 14 "P1_AVDDL")
			(pintype "passive")
		)
	)
	(footprint "antmicro-footprints:R_0402_1005Metric"
		(layer "F.Cu")
		(at 164 77.4)
		(descr "Resistor SMD 0402")
		(tags "resistor SMD 0402")
		(property "Reference" "R207"
			(at -1 6.4 0)
			(layer "F.SilkS")
			(effects
				(font
					(size 0.7 0.7)
					(thickness 0.15)
				)
				(justify left bottom)
			)
		)
		(property "Value" "R_1k_0402"
			(at -1.011843 1.772047 0)
			(layer "F.Fab")
			(effects
				(font
					(size 0.7 0.7)
					(thickness 0.15)
				)
				(justify left bottom)
			)
		)
		(property "Datasheet" "https://www.bourns.com/docs/product-datasheets/cr.pdf"
			(at 0 0 0)
			(layer "F.Fab")
			(hide yes)
			(effects
				(font
					(size 1.27 1.27)
					(thickness 0.15)
				)
			)
		)
		(property "Description" "SMD Chip Resistor, 1 kohm, ± 1%, 63 mW, 0402 [1005 Metric], Thick Film, General Purpose"
			(at 0 0 0)
			(layer "F.Fab")
			(hide yes)
			(effects
				(font
					(size 1.27 1.27)
					(thickness 0.15)
				)
			)
		)
		(property "MPN" "CR0402-FX-1001GLF"
			(at 0 0 0)
			(unlocked yes)
			(layer "F.Fab")
			(hide yes)
			(effects
				(font
					(size 1 1)
					(thickness 0.15)
				)
			)
		)
		(property "Manufacturer" "Bourns"
			(at 0 0 0)
			(unlocked yes)
			(layer "F.Fab")
			(hide yes)
			(effects
				(font
					(size 1 1)
					(thickness 0.15)
				)
			)
		)
		(property "License" "Apache-2.0"
			(at 0 0 0)
			(unlocked yes)
			(layer "F.Fab")
			(hide yes)
			(effects
				(font
					(size 1 1)
					(thickness 0.15)
				)
			)
		)
		(property "Author" "Antmicro"
			(at 0 0 0)
			(unlocked yes)
			(layer "F.Fab")
			(hide yes)
			(effects
				(font
					(size 1 1)
					(thickness 0.15)
				)
			)
		)
		(property "Val" "1k"
			(at 0 0 0)
			(unlocked yes)
			(layer "F.Fab")
			(hide yes)
			(effects
				(font
					(size 1 1)
					(thickness 0.15)
				)
			)
		)
		(property "Tolerance" "1%"
			(at 0 0 0)
			(unlocked yes)
			(layer "F.Fab")
			(hide yes)
			(effects
				(font
					(size 1 1)
					(thickness 0.15)
				)
			)
		)
		(sheetname "/X710-AT2 10GbE/")
		(sheetfile "x710-at2-10gbe.kicad_sch")
		(attr smd dnp)
		(fp_rect
			(start -0.925 -0.47)
			(end 0.925 0.47)
			(stroke
				(width 0.05)
				(type default)
			)
			(fill no)
			(layer "F.CrtYd")
		)
		(fp_rect
			(start -0.5 -0.25)
			(end 0.5 0.25)
			(stroke
				(width 0.15)
				(type solid)
			)
			(fill no)
			(layer "F.Fab")
		)
		(fp_text user "License: Apache-2.0"
			(at -0.95 5.169 0)
			(layer "F.Fab")
			(effects
				(font
					(size 0.7 0.7)
					(thickness 0.15)
				)
				(justify left bottom)
			)
		)
		(fp_text user "Author: Antmicro"
			(at -0.95 4.169 0)
			(layer "F.Fab")
			(effects
				(font
					(size 0.7 0.7)
					(thickness 0.15)
				)
				(justify left bottom)
			)
		)
		(fp_text user "${REFERENCE}"
			(at -0.95 3.168 0)
			(layer "F.Fab")
			(effects
				(font
					(size 0.7 0.7)
					(thickness 0.15)
				)
				(justify left bottom)
			)
		)
		(pad "1" smd roundrect
			(at -0.48 0)
			(size 0.59 0.64)
			(layers "F.Cu" "F.Mask" "F.Paste")
			(roundrect_rratio 0.25)
			(net 131 "/X710-AT2 10GbE/TPIN_5")
			(pintype "passive")
		)
		(pad "2" smd roundrect
			(at 0.48 0)
			(size 0.59 0.64)
			(layers "F.Cu" "F.Mask" "F.Paste")
			(roundrect_rratio 0.25)
			(net 18 "+1V88")
			(pintype "passive")
		)
	)
	(footprint "antmicro-footprints:C_0402_1005Metric"
		(layer "F.Cu")
		(at 172.6 74 90)
		(descr "Capacitor SMD 0402")
		(tags "capacitor SMD 0402")
		(property "Reference" "C285"
			(at -1.2 3.6 90)
			(layer "F.SilkS")
			(effects
				(font
					(size 0.7 0.7)
					(thickness 0.15)
				)
				(justify left bottom)
			)
		)
		(property "Value" "C_10p_25V_0402"
			(at -1.022927 2.155213 90)
			(layer "F.Fab")
			(effects
				(font
					(size 0.7 0.7)
					(thickness 0.15)
				)
				(justify left bottom)
			)
		)
		(property "Datasheet" "https://spicat.kyocera-avx.com/product/mlcc/chartview/04023A100FAT2A/"
			(at 0 0 90)
			(layer "F.Fab")
			(hide yes)
			(effects
				(font
					(size 1.27 1.27)
					(thickness 0.15)
				)
			)
		)
		(property "Description" "Multilayer Ceramic Capacitors MLCC - SMD/SMT 25V 10pF C0G 0402 1%"
			(at 0 0 90)
			(layer "F.Fab")
			(hide yes)
			(effects
				(font
					(size 1.27 1.27)
					(thickness 0.15)
				)
			)
		)
		(property "MPN" "04023A100FAT2A"
			(at 0 0 90)
			(unlocked yes)
			(layer "F.Fab")
			(hide yes)
			(effects
				(font
					(size 1 1)
					(thickness 0.15)
				)
			)
		)
		(property "Manufacturer" "KYOCERA AVX"
			(at 0 0 90)
			(unlocked yes)
			(layer "F.Fab")
			(hide yes)
			(effects
				(font
					(size 1 1)
					(thickness 0.15)
				)
			)
		)
		(property "License" "Apache-2.0"
			(at 0 0 90)
			(unlocked yes)
			(layer "F.Fab")
			(hide yes)
			(effects
				(font
					(size 1 1)
					(thickness 0.15)
				)
			)
		)
		(property "Author" "Antmicro"
			(at 0 0 90)
			(unlocked yes)
			(layer "F.Fab")
			(hide yes)
			(effects
				(font
					(size 1 1)
					(thickness 0.15)
				)
			)
		)
		(property "Val" "10p"
			(at 0 0 90)
			(unlocked yes)
			(layer "F.Fab")
			(hide yes)
			(effects
				(font
					(size 1 1)
					(thickness 0.15)
				)
			)
		)
		(property "Voltage" "25V"
			(at 0 0 90)
			(unlocked yes)
			(layer "F.Fab")
			(hide yes)
			(effects
				(font
					(size 1 1)
					(thickness 0.15)
				)
			)
		)
		(property "Dielectric" "C0G"
			(at 0 0 90)
			(unlocked yes)
			(layer "F.Fab")
			(hide yes)
			(effects
				(font
					(size 1 1)
					(thickness 0.15)
				)
			)
		)
		(sheetname "/X710-AT2 10GbE/")
		(sheetfile "x710-at2-10gbe.kicad_sch")
		(attr smd)
		(fp_rect
			(start -0.925 -0.47)
			(end 0.925 0.47)
			(stroke
				(width 0.05)
				(type default)
			)
			(fill no)
			(layer "F.CrtYd")
		)
		(fp_line
			(start 0.504 -0.25)
			(end 0.504 0.248)
			(stroke
				(width 0.15)
				(type solid)
			)
			(layer "F.Fab")
		)
		(fp_line
			(start -0.494 -0.25)
			(end 0.504 -0.25)
			(stroke
				(width 0.15)
				(type solid)
			)
			(layer "F.Fab")
		)
		(fp_line
			(start 0.504 0.248)
			(end -0.494 0.248)
			(stroke
				(width 0.15)
				(type solid)
			)
			(layer "F.Fab")
		)
		(fp_line
			(start -0.494 0.248)
			(end -0.494 -0.25)
			(stroke
				(width 0.15)
				(type solid)
			)
			(layer "F.Fab")
		)
		(fp_text user "Author: Antmicro"
			(at -0.939 3.399 90)
			(layer "F.Fab")
			(effects
				(font
					(size 0.7 0.7)
					(thickness 0.15)
				)
				(justify left bottom)
			)
		)
		(fp_text user "${REFERENCE}"
			(at -0.939 4.599 90)
			(layer "F.Fab")
			(effects
				(font
					(size 0.7 0.7)
					(thickness 0.15)
				)
				(justify left bottom)
			)
		)
		(fp_text user "License: Apache-2.0"
			(at -0.939 5.799 90)
			(layer "F.Fab")
			(effects
				(font
					(size 0.7 0.7)
					(thickness 0.15)
				)
				(justify left bottom)
			)
		)
		(pad "1" smd roundrect
			(at -0.48 0 90)
			(size 0.59 0.64)
			(layers "F.Cu" "F.Mask" "F.Paste")
			(roundrect_rratio 0.25)
			(net 23 "GND")
			(pintype "passive")
		)
		(pad "2" smd roundrect
			(at 0.48 0 90)
			(size 0.59 0.64)
			(layers "F.Cu" "F.Mask" "F.Paste")
			(roundrect_rratio 0.25)
			(net 125 "/X710-AT2 10GbE/MDIO0_I2C0.MDC")
			(pintype "passive")
		)
	)
	(footprint "antmicro-footprints:FB_0603_1608Metric"
		(layer "F.Cu")
		(at 146.355 97.375 90)
		(property "Reference" "FB4"
			(at -19.625001 23.445 90)
			(layer "F.SilkS")
			(effects
				(font
					(size 0.7 0.7)
					(thickness 0.15)
				)
			)
		)
		(property "Value" "FB_470Z_1A_Murata-BLM18PG_0603"
			(at 0 1.5 90)
			(layer "F.Fab")
			(effects
				(font
					(size 0.7 0.7)
					(thickness 0.15)
				)
				(justify left bottom)
			)
		)
		(property "Datasheet" "https://www.murata.com/en-us/products/productdata/8796738650142/ENFA0003.pdf"
			(at 0 0 90)
			(layer "F.Fab")
			(hide yes)
			(effects
				(font
					(size 1.27 1.27)
					(thickness 0.15)
				)
			)
		)
		(property "Description" "Ferrite Bead, 0603 [1608 Metric], 470 ohm, 1 A, BLM18P, 0.2 ohm, ± 25%, DC power line"
			(at 0 0 90)
			(layer "F.Fab")
			(hide yes)
			(effects
				(font
					(size 1.27 1.27)
					(thickness 0.15)
				)
			)
		)
		(property "Val" "470Z/1A"
			(at 0 0 90)
			(unlocked yes)
			(layer "F.Fab")
			(hide yes)
			(effects
				(font
					(size 1 1)
					(thickness 0.15)
				)
			)
		)
		(property "MPN" "BLM18PG471SN1D"
			(at 0 0 90)
			(unlocked yes)
			(layer "F.Fab")
			(hide yes)
			(effects
				(font
					(size 1 1)
					(thickness 0.15)
				)
			)
		)
		(property "Manufacturer" "Murata"
			(at 0 0 90)
			(unlocked yes)
			(layer "F.Fab")
			(hide yes)
			(effects
				(font
					(size 1 1)
					(thickness 0.15)
				)
			)
		)
		(property "Current" ""
			(at 0 0 90)
			(unlocked yes)
			(layer "F.Fab")
			(hide yes)
			(effects
				(font
					(size 1 1)
					(thickness 0.15)
				)
			)
		)
		(property "Author" "Antmicro"
			(at 0 0 90)
			(unlocked yes)
			(layer "F.Fab")
			(hide yes)
			(effects
				(font
					(size 1 1)
					(thickness 0.15)
				)
			)
		)
		(property "License" "Apache-2.0"
			(at 0 0 90)
			(unlocked yes)
			(layer "F.Fab")
			(hide yes)
			(effects
				(font
					(size 1 1)
					(thickness 0.15)
				)
			)
		)
		(sheetname "/X710-AT2 power/")
		(sheetfile "x710-at2-power.kicad_sch")
		(attr smd)
		(fp_line
			(start -0.15 -0.4)
			(end 0.15 -0.4)
			(stroke
				(width 0.15)
				(type solid)
			)
			(layer "F.SilkS")
		)
		(fp_line
			(start -0.15 0.4)
			(end 0.15 0.4)
			(stroke
				(width 0.15)
				(type solid)
			)
			(layer "F.SilkS")
		)
		(fp_rect
			(start -1.25 -0.65)
			(end 1.25 0.65)
			(stroke
				(width 0.05)
				(type solid)
			)
			(fill no)
			(layer "F.CrtYd")
		)
		(fp_line
			(start 0.8 -0.408)
			(end -0.803 -0.408)
			(stroke
				(width 0.15)
				(type solid)
			)
			(layer "F.Fab")
		)
		(fp_line
			(start 0.8 -0.408)
			(end 0.8 0.406)
			(stroke
				(width 0.15)
				(type solid)
			)
			(layer "F.Fab")
		)
		(fp_line
			(start 0.8 0.406)
			(end -0.803 0.406)
			(stroke
				(width 0.15)
				(type solid)
			)
			(layer "F.Fab")
		)
		(fp_line
			(start -0.803 0.406)
			(end -0.803 -0.408)
			(stroke
				(width 0.15)
				(type solid)
			)
			(layer "F.Fab")
		)
		(fp_text user "License: Apache-2.0"
			(at -1.653 5.9 90)
			(layer "F.Fab")
			(effects
				(font
					(size 0.7 0.7)
					(thickness 0.15)
				)
				(justify left bottom)
			)
		)
		(fp_text user "${REFERENCE}"
			(at -1.653 4.6 90)
			(layer "F.Fab")
			(effects
				(font
					(size 0.7 0.7)
					(thickness 0.15)
				)
				(justify left bottom)
			)
		)
		(fp_text user "Author: Antmicro"
			(at -1.653 3.162 90)
			(layer "F.Fab")
			(effects
				(font
					(size 0.7 0.7)
					(thickness 0.15)
				)
				(justify left bottom)
			)
		)
		(pad "1" smd roundrect
			(at -0.7 0 90)
			(size 0.8 1)
			(layers "F.Cu" "F.Mask" "F.Paste")
			(roundrect_rratio 0.2)
			(net 18 "+1V88")
			(pintype "passive")
		)
		(pad "2" smd roundrect
			(at 0.7 0 90)
			(size 0.8 1)
			(layers "F.Cu" "F.Mask" "F.Paste")
			(roundrect_rratio 0.2)
			(net 20 "XGB_AVDDH")
			(pintype "passive")
		)
	)
	(footprint "antmicro-footprints:C_0402_1005Metric"
		(layer "F.Cu")
		(at 117.8 119 180)
		(descr "Capacitor SMD 0402")
		(tags "capacitor SMD 0402")
		(property "Reference" "C48"
			(at -0.8 -0.2 180)
			(layer "F.SilkS")
			(effects
				(font
					(size 0.7 0.7)
					(thickness 0.15)
				)
				(justify left bottom)
			)
		)
		(property "Value" "C_220n_0402"
			(at -1.022927 2.155213 180)
			(layer "F.Fab")
			(effects
				(font
					(size 0.7 0.7)
					(thickness 0.15)
				)
				(justify left bottom)
			)
		)
		(property "Datasheet" "https://www.yageo.com/en/Chart/Download/pdf/CC0402KRX5R6BB224"
			(at 0 0 180)
			(layer "F.Fab")
			(hide yes)
			(effects
				(font
					(size 1.27 1.27)
					(thickness 0.15)
				)
			)
		)
		(property "Description" "SMD Multilayer Ceramic Capacitor, 0.22 µF, 10 V, 0402 [1005 Metric], ± 10%, X5R, CC Series"
			(at 0 0 180)
			(layer "F.Fab")
			(hide yes)
			(effects
				(font
					(size 1.27 1.27)
					(thickness 0.15)
				)
			)
		)
		(property "MPN" "CC0402KRX5R6BB224"
			(at 0 0 180)
			(unlocked yes)
			(layer "F.Fab")
			(hide yes)
			(effects
				(font
					(size 1 1)
					(thickness 0.15)
				)
			)
		)
		(property "Manufacturer" "YAGEO"
			(at 0 0 180)
			(unlocked yes)
			(layer "F.Fab")
			(hide yes)
			(effects
				(font
					(size 1 1)
					(thickness 0.15)
				)
			)
		)
		(property "License" "Apache-2.0"
			(at 0 0 180)
			(unlocked yes)
			(layer "F.Fab")
			(hide yes)
			(effects
				(font
					(size 1 1)
					(thickness 0.15)
				)
			)
		)
		(property "Val" "220n"
			(at 0 0 180)
			(unlocked yes)
			(layer "F.Fab")
			(hide yes)
			(effects
				(font
					(size 1 1)
					(thickness 0.15)
				)
			)
		)
		(property "Voltage" ""
			(at 0 0 180)
			(unlocked yes)
			(layer "F.Fab")
			(hide yes)
			(effects
				(font
					(size 1 1)
					(thickness 0.15)
				)
			)
		)
		(property "Dielectric" ""
			(at 0 0 180)
			(unlocked yes)
			(layer "F.Fab")
			(hide yes)
			(effects
				(font
					(size 1 1)
					(thickness 0.15)
				)
			)
		)
		(property "Author" "Antmicro"
			(at 0 0 180)
			(unlocked yes)
			(layer "F.Fab")
			(hide yes)
			(effects
				(font
					(size 1 1)
					(thickness 0.15)
				)
			)
		)
		(sheetname "/TB Controller/")
		(sheetfile "tb.kicad_sch")
		(attr smd)
		(fp_rect
			(start -0.925 -0.47)
			(end 0.925 0.47)
			(stroke
				(width 0.05)
				(type default)
			)
			(fill no)
			(layer "F.CrtYd")
		)
		(fp_line
			(start 0.504 0.248)
			(end -0.494 0.248)
			(stroke
				(width 0.15)
				(type solid)
			)
			(layer "F.Fab")
		)
		(fp_line
			(start 0.504 -0.25)
			(end 0.504 0.248)
			(stroke
				(width 0.15)
				(type solid)
			)
			(layer "F.Fab")
		)
		(fp_line
			(start -0.494 0.248)
			(end -0.494 -0.25)
			(stroke
				(width 0.15)
				(type solid)
			)
			(layer "F.Fab")
		)
		(fp_line
			(start -0.494 -0.25)
			(end 0.504 -0.25)
			(stroke
				(width 0.15)
				(type solid)
			)
			(layer "F.Fab")
		)
		(fp_text user "Author: Antmicro"
			(at -0.939 3.399 180)
			(layer "F.Fab")
			(effects
				(font
					(size 0.7 0.7)
					(thickness 0.15)
				)
				(justify left bottom)
			)
		)
		(fp_text user "${REFERENCE}"
			(at -0.939 4.599 180)
			(layer "F.Fab")
			(effects
				(font
					(size 0.7 0.7)
					(thickness 0.15)
				)
				(justify left bottom)
			)
		)
		(fp_text user "License: Apache-2.0"
			(at -0.939 5.799 180)
			(layer "F.Fab")
			(effects
				(font
					(size 0.7 0.7)
					(thickness 0.15)
				)
				(justify left bottom)
			)
		)
		(pad "1" smd roundrect
			(at -0.48 0 180)
			(size 0.59 0.64)
			(layers "F.Cu" "F.Mask" "F.Paste")
			(roundrect_rratio 0.25)
			(net 315 "/TB Controller/TB_PCIE_TX0_N")
			(pintype "passive")
		)
		(pad "2" smd roundrect
			(at 0.48 0 180)
			(size 0.59 0.64)
			(layers "F.Cu" "F.Mask" "F.Paste")
			(roundrect_rratio 0.25)
			(net 322 "/TB Controller/PCIex4.RX0-")
			(pintype "passive")
		)
	)
	(footprint "antmicro-footprints:Conn_Molex_Nano-Fit_1x2_105313-2202_Horizontal"
		(layer "F.Cu")
		(at 131.146 56.804561 90)
		(descr "Molex Nano-Fit Power Connectors, 2 Pins per row")
		(tags "connector Molex Nano-Fit NanoFit top entry 2.50mm horizontal")
		(property "Reference" "J5"
			(at -0.395439 4.454 90)
			(layer "F.SilkS")
			(effects
				(font
					(size 0.7 0.7)
					(thickness 0.15)
				)
				(justify left bottom)
			)
		)
		(property "Value" "Molex_Nano-Fit_1x2_105313-2202_Horizontal"
			(at 0 5.8 90)
			(layer "F.Fab")
			(effects
				(font
					(size 0.7 0.7)
					(thickness 0.15)
				)
				(justify left bottom)
			)
		)
		(property "Datasheet" "https://tools.molex.com/pdm_docs/sd/1053132202_sd.pdf"
			(at 0 0 90)
			(layer "F.Fab")
			(hide yes)
			(effects
				(font
					(size 1.27 1.27)
					(thickness 0.15)
				)
			)
		)
		(property "Description" "Pin Header, Power, 2.5 mm, 1 Rows, 2 Contacts, Through Hole Horizontal, Nano-Fit"
			(at 0 0 90)
			(layer "F.Fab")
			(hide yes)
			(effects
				(font
					(size 1.27 1.27)
					(thickness 0.15)
				)
			)
		)
		(property "MPN" "105313-2202"
			(at 0 0 90)
			(unlocked yes)
			(layer "F.Fab")
			(hide yes)
			(effects
				(font
					(size 1 1)
					(thickness 0.15)
				)
			)
		)
		(property "Manufacturer" "Molex"
			(at 0 0 90)
			(unlocked yes)
			(layer "F.Fab")
			(hide yes)
			(effects
				(font
					(size 1 1)
					(thickness 0.15)
				)
			)
		)
		(property "Author" "Antmicro"
			(at 0 0 90)
			(unlocked yes)
			(layer "F.Fab")
			(hide yes)
			(effects
				(font
					(size 1 1)
					(thickness 0.15)
				)
			)
		)
		(property "License" "Apache-2.0"
			(at 0 0 90)
			(unlocked yes)
			(layer "F.Fab")
			(hide yes)
			(effects
				(font
					(size 1 1)
					(thickness 0.15)
				)
			)
		)
		(sheetname "/Power input/")
		(sheetfile "power_input.kicad_sch")
		(attr through_hole)
		(fp_rect
			(start 10.4 -1.7)
			(end 1.898 4.2)
			(stroke
				(width 0.15)
				(type solid)
			)
			(fill no)
			(layer "F.SilkS")
		)
		(fp_rect
			(start 1.4 -0.299)
			(end 1.899 0.299)
			(stroke
				(width 0.15)
				(type solid)
			)
			(fill no)
			(layer "F.SilkS")
		)
		(fp_rect
			(start 1.4 2.2)
			(end 1.899 2.798)
			(stroke
				(width 0.15)
				(type solid)
			)
			(fill no)
			(layer "F.SilkS")
		)
		(fp_circle
			(center 0 -1.25)
			(end 0.05 -1.25)
			(stroke
				(width 0.15)
				(type solid)
			)
			(fill yes)
			(layer "F.SilkS")
		)
		(fp_rect
			(start -1.197 -2.116)
			(end 12.042 4.624)
			(stroke
				(width 0.05)
				(type solid)
			)
			(fill no)
			(layer "F.CrtYd")
		)
		(fp_line
			(start -0.35 -1.71)
			(end -0.595 -1.465)
			(stroke
				(width 0.15)
				(type solid)
			)
			(layer "F.Fab")
		)
		(fp_rect
			(start -0.597 -1.716)
			(end 11.842 4.224)
			(stroke
				(width 0.15)
				(type solid)
			)
			(fill no)
			(layer "F.Fab")
		)
		(fp_text user "${REFERENCE}"
			(at -3.1 7.4 90)
			(layer "F.Fab")
			(effects
				(font
					(size 0.7 0.7)
					(thickness 0.15)
				)
				(justify left bottom)
			)
		)
		(fp_text user "License: Apache-2.0"
			(at -3.1 8.6 90)
			(layer "F.Fab")
			(effects
				(font
					(size 0.7 0.7)
					(thickness 0.15)
				)
				(justify left bottom)
			)
		)
		(fp_text user "Author: Antmicro"
			(at -3.1 9.8 90)
			(layer "F.Fab")
			(effects
				(font
					(size 0.7 0.7)
					(thickness 0.15)
				)
				(justify left bottom)
			)
		)
		(pad "" np_thru_hole circle
			(at 7.179 0 90)
			(size 1.7 1.7)
			(drill 1.7)
			(layers "*.Cu" "*.Mask")
		)
		(pad "" np_thru_hole circle
			(at 7.179 2.499 90)
			(size 1.7 1.7)
			(drill 1.7)
			(layers "*.Cu" "*.Mask")
		)
		(pad "1" thru_hole custom
			(at 0 0 90)
			(size 1.417157 1.417157)
			(drill 1.2)
			(layers "*.Cu" "*.Mask")
			(remove_unused_layers no)
			(net 412 "Net-(D15-C)")
			(pintype "input")
			(thermal_bridge_angle 90)
			(options
				(clearance outline)
				(anchor circle)
			)
			(primitives
				(gr_poly
					(pts
						(xy -0.85 -0.6) (xy 0.85 -0.6) (xy 0.85 0.6) (xy -0.45 0.6) (xy -0.85 0.2)
					)
					(width 0.5)
					(fill yes)
				)
			)
		)
		(pad "2" thru_hole oval
			(at 0 2.499 90)
			(size 2.2 1.7)
			(drill 1.2)
			(layers "*.Cu" "*.Mask")
			(remove_unused_layers no)
			(net 23 "GND")
			(pintype "input")
		)
	)
	(footprint "antmicro-footprints:RJ45_JTH-0024NL"
		(layer "F.Cu")
		(at 157.15 135.865 180)
		(property "Reference" "J3"
			(at 7.65 4.365 0)
			(unlocked yes)
			(layer "F.SilkS")
			(effects
				(font
					(size 0.7 0.7)
					(thickness 0.15)
				)
				(justify left bottom)
			)
		)
		(property "Value" "Bus_RJ45_JTH-0024NL"
			(at 5.06 1 180)
			(unlocked yes)
			(layer "F.Fab")
			(effects
				(font
					(size 0.7 0.7)
					(thickness 0.15)
				)
				(justify left bottom)
			)
		)
		(property "Datasheet" "https://www.mouser.com/datasheet/2/447/JTH_0024NL-3072047.pdf"
			(at 0 0 180)
			(layer "F.Fab")
			(hide yes)
			(effects
				(font
					(size 1.27 1.27)
					(thickness 0.15)
				)
			)
		)
		(property "Description" "Modular Connectors / Ethernet Connectors 1X1 TAB DOWN W/LED'S ETHERNET (NON PoE)"
			(at 0 0 180)
			(layer "F.Fab")
			(hide yes)
			(effects
				(font
					(size 1.27 1.27)
					(thickness 0.15)
				)
			)
		)
		(property "MPN" "JTH-0024NL"
			(at 0 0 180)
			(unlocked yes)
			(layer "F.Fab")
			(hide yes)
			(effects
				(font
					(size 1 1)
					(thickness 0.15)
				)
			)
		)
		(property "Manufacturer" "Pulse Electronics"
			(at 0 0 180)
			(unlocked yes)
			(layer "F.Fab")
			(hide yes)
			(effects
				(font
					(size 1 1)
					(thickness 0.15)
				)
			)
		)
		(property "Author" "Antmicro"
			(at 0 0 180)
			(unlocked yes)
			(layer "F.Fab")
			(hide yes)
			(effects
				(font
					(size 1 1)
					(thickness 0.15)
				)
			)
		)
		(property "License" "Apache-2.0"
			(at 0 0 180)
			(unlocked yes)
			(layer "F.Fab")
			(hide yes)
			(effects
				(font
					(size 1 1)
					(thickness 0.15)
				)
			)
		)
		(property ki_fp_filters "CONN18_5-2337992-8_TEC")
		(sheetname "/2xRJ45/")
		(sheetfile "2xrj45.kicad_sch")
		(attr through_hole)
		(fp_line
			(start 14 4)
			(end 14 -5.25)
			(stroke
				(width 0.1)
				(type default)
			)
			(layer "F.SilkS")
		)
		(fp_line
			(start -3.75 4)
			(end 14 4)
			(stroke
				(width 0.1)
				(type default)
			)
			(layer "F.SilkS")
		)
		(fp_line
			(start -3.75 -5.25)
			(end -3.75 4)
			(stroke
				(width 0.1)
				(type default)
			)
			(layer "F.SilkS")
		)
		(fp_rect
			(start -5.4 -20.72)
			(end 15.58 4.45)
			(stroke
				(width 0.05)
				(type solid)
			)
			(fill no)
			(layer "F.CrtYd")
		)
		(fp_text user "License: Apache-2.0"
			(at -5.75 7.65 180)
			(layer "F.Fab")
			(effects
				(font
					(size 0.7 0.7)
					(thickness 0.15)
				)
				(justify left bottom)
			)
		)
		(fp_text user "${REFERENCE}"
			(at -5.75 6.45 180)
			(unlocked yes)
			(layer "F.Fab")
			(effects
				(font
					(size 0.7 0.7)
					(thickness 0.15)
				)
				(justify left bottom)
			)
		)
		(fp_text user "Author: Antmicro"
			(at -5.75 8.85 180)
			(layer "F.Fab")
			(effects
				(font
					(size 0.7 0.7)
					(thickness 0.15)
				)
				(justify left bottom)
			)
		)
		(pad "" np_thru_hole circle
			(at 0.245 -6.6 180)
			(size 3.2 3.2)
			(drill 3.2)
			(layers "*.Cu" "*.Mask")
		)
		(pad "" np_thru_hole circle
			(at 9.895 -6.6 180)
			(size 3.2 3.2)
			(drill 3.2)
			(layers "*.Cu" "*.Mask")
		)
		(pad "1" thru_hole circle
			(at 0 0 180)
			(size 1.39 1.39)
			(drill 0.89)
			(layers "*.Cu" "*.Mask")
			(remove_unused_layers no)
			(net 133 "/2xRJ45/P0_CT")
			(pinfunction "CT3")
			(pintype "bidirectional")
		)
		(pad "2" thru_hole circle
			(at 2.03 0 180)
			(size 1.39 1.39)
			(drill 0.89)
			(layers "*.Cu" "*.Mask")
			(remove_unused_layers no)
			(net 38 "/2xRJ45/Ethernet_P0.D3-")
			(pinfunction "T2-")
			(pintype "bidirectional")
		)
		(pad "3" thru_hole circle
			(at 4.06 0 180)
			(size 1.39 1.39)
			(drill 0.89)
			(layers "*.Cu" "*.Mask")
			(remove_unused_layers no)
			(net 44 "/2xRJ45/Ethernet_P0.D3+")
			(pinfunction "T2+")
			(pintype "bidirectional")
		)
		(pad "4" thru_hole circle
			(at 6.09 0 180)
			(size 1.39 1.39)
			(drill 0.89)
			(layers "*.Cu" "*.Mask")
			(remove_unused_layers no)
			(net 39 "/2xRJ45/Ethernet_P0.D2+")
			(pinfunction "T3+")
			(pintype "bidirectional")
		)
		(pad "5" thru_hole circle
			(at 8.12 0 180)
			(size 1.39 1.39)
			(drill 0.89)
			(layers "*.Cu" "*.Mask")
			(remove_unused_layers no)
			(net 36 "/2xRJ45/Ethernet_P0.D2-")
			(pinfunction "T3-")
			(pintype "bidirectional")
		)
		(pad "6" thru_hole circle
			(at 10.15 0 180)
			(size 1.39 1.39)
			(drill 0.89)
			(layers "*.Cu" "*.Mask")
			(remove_unused_layers no)
			(net 133 "/2xRJ45/P0_CT")
			(pinfunction "CT2")
			(pintype "bidirectional")
		)
		(pad "7" thru_hole circle
			(at -1.02 2.54 180)
			(size 1.39 1.39)
			(drill 0.89)
			(layers "*.Cu" "*.Mask")
			(remove_unused_layers no)
			(net 133 "/2xRJ45/P0_CT")
			(pinfunction "CT4")
			(pintype "bidirectional")
		)
		(pad "8" thru_hole circle
			(at 1.01 2.54 180)
			(size 1.39 1.39)
			(drill 0.89)
			(layers "*.Cu" "*.Mask")
			(remove_unused_layers no)
			(net 41 "/2xRJ45/Ethernet_P0.D4+")
			(pinfunction "T1+")
			(pintype "bidirectional")
		)
		(pad "9" thru_hole circle
			(at 3.04 2.54 180)
			(size 1.39 1.39)
			(drill 0.89)
			(layers "*.Cu" "*.Mask")
			(remove_unused_layers no)
			(net 43 "/2xRJ45/Ethernet_P0.D4-")
			(pinfunction "T1-")
			(pintype "bidirectional")
		)
		(pad "10" thru_hole circle
			(at 7.11 2.54 180)
			(size 1.39 1.39)
			(drill 0.89)
			(layers "*.Cu" "*.Mask")
			(remove_unused_layers no)
			(net 37 "/2xRJ45/Ethernet_P0.D1-")
			(pinfunction "T4-")
			(pintype "bidirectional")
		)
		(pad "11" thru_hole circle
			(at 9.14 2.54 180)
			(size 1.39 1.39)
			(drill 0.89)
			(layers "*.Cu" "*.Mask")
			(remove_unused_layers no)
			(net 42 "/2xRJ45/Ethernet_P0.D1+")
			(pinfunction "T4+")
			(pintype "bidirectional")
		)
		(pad "12" thru_hole circle
			(at 11.17 2.54 180)
			(size 1.39 1.39)
			(drill 0.89)
			(layers "*.Cu" "*.Mask")
			(remove_unused_layers no)
			(net 133 "/2xRJ45/P0_CT")
			(pinfunction "CT1")
			(pintype "bidirectional")
		)
		(pad "13" thru_hole circle
			(at 12.59 -12.95 180)
			(size 1.77 1.77)
			(drill 1.27)
			(layers "*.Cu" "*.Mask")
			(remove_unused_layers no)
			(net 410 "Net-(J3-LED_GRN-)")
			(pinfunction "LED_GRN-")
			(pintype "passive")
		)
		(pad "14" thru_hole circle
			(at 12.59 -15.49 180)
			(size 1.77 1.77)
			(drill 1.27)
			(layers "*.Cu" "*.Mask")
			(remove_unused_layers no)
			(net 7 "+3V3")
			(pinfunction "LED_GRN+")
			(pintype "passive")
		)
		(pad "15" thru_hole circle
			(at -2.45 -10.41 180)
			(size 1.77 1.77)
			(drill 1.27)
			(layers "*.Cu" "*.Mask")
			(remove_unused_layers no)
			(net 406 "Net-(J3-LED_YG_Y-)")
			(pinfunction "LED_YG_Y-")
			(pintype "passive")
		)
		(pad "16" thru_hole circle
			(at -2.45 -12.95 180)
			(size 1.77 1.77)
			(drill 1.27)
			(layers "*.Cu" "*.Mask")
			(remove_unused_layers no)
			(net 7 "+3V3")
			(pinfunction "LED_COM+")
			(pintype "passive")
		)
		(pad "17" thru_hole circle
			(at -2.45 -15.49 180)
			(size 1.77 1.77)
			(drill 1.27)
			(layers "*.Cu" "*.Mask")
			(remove_unused_layers no)
			(net 408 "Net-(J3-LED_YG_G-)")
			(pinfunction "LED_YG_G-")
			(pintype "passive")
		)
		(pad "SH" thru_hole circle
			(at -3.72 -6.6 180)
			(size 2.07 2.07)
			(drill 1.57)
			(layers "*.Cu" "*.Mask")
			(remove_unused_layers no)
			(net 23 "GND")
			(pinfunction "SHIELD")
			(pintype "passive")
		)
		(pad "SH" thru_hole circle
			(at 13.86 -6.6 180)
			(size 2.07 2.07)
			(drill 1.57)
			(layers "*.Cu" "*.Mask")
			(remove_unused_layers no)
			(net 23 "GND")
			(pinfunction "SHIELD")
			(pintype "passive")
		)
	)
	(footprint "antmicro-footprints:C_0402_1005Metric"
		(layer "F.Cu")
		(at 151.550002 109.150002)
		(descr "Capacitor SMD 0402")
		(tags "capacitor SMD 0402")
		(property "Reference" "C121"
			(at 14.149998 17.25 0)
			(layer "F.SilkS")
			(effects
				(font
					(size 0.7 0.7)
					(thickness 0.15)
				)
			)
		)
		(property "Value" "C_1u_25V_0402"
			(at -1.022927 2.155213 0)
			(layer "F.Fab")
			(effects
				(font
					(size 0.7 0.7)
					(thickness 0.15)
				)
				(justify left bottom)
			)
		)
		(property "Datasheet" "https://www.murata.com/products/productdetail?partno=GRM155R61E105KE11%23"
			(at 0 0 0)
			(layer "F.Fab")
			(hide yes)
			(effects
				(font
					(size 1.27 1.27)
					(thickness 0.15)
				)
			)
		)
		(property "Description" "SMD Multilayer Ceramic Capacitor, 1 µF, 25 V, 0402 [1005 Metric], ± 10%, X5R, GRM Series"
			(at 0 0 0)
			(layer "F.Fab")
			(hide yes)
			(effects
				(font
					(size 1.27 1.27)
					(thickness 0.15)
				)
			)
		)
		(property "MPN" "GRM155R61E105KE11J"
			(at 0 0 0)
			(unlocked yes)
			(layer "F.Fab")
			(hide yes)
			(effects
				(font
					(size 1 1)
					(thickness 0.15)
				)
			)
		)
		(property "Manufacturer" "Murata"
			(at 0 0 0)
			(unlocked yes)
			(layer "F.Fab")
			(hide yes)
			(effects
				(font
					(size 1 1)
					(thickness 0.15)
				)
			)
		)
		(property "License" "Apache-2.0"
			(at 0 0 0)
			(unlocked yes)
			(layer "F.Fab")
			(hide yes)
			(effects
				(font
					(size 1 1)
					(thickness 0.15)
				)
			)
		)
		(property "Author" "Antmicro"
			(at 0 0 0)
			(unlocked yes)
			(layer "F.Fab")
			(hide yes)
			(effects
				(font
					(size 1 1)
					(thickness 0.15)
				)
			)
		)
		(property "Val" "1u"
			(at 0 0 0)
			(unlocked yes)
			(layer "F.Fab")
			(hide yes)
			(effects
				(font
					(size 1 1)
					(thickness 0.15)
				)
			)
		)
		(property "Voltage" "25V"
			(at 0 0 0)
			(unlocked yes)
			(layer "F.Fab")
			(hide yes)
			(effects
				(font
					(size 1 1)
					(thickness 0.15)
				)
			)
		)
		(property "Dielectric" "X5R"
			(at 0 0 0)
			(unlocked yes)
			(layer "F.Fab")
			(hide yes)
			(effects
				(font
					(size 1 1)
					(thickness 0.15)
				)
			)
		)
		(sheetname "/X710 DCDC converters/")
		(sheetfile "DCDC_converters_X710.kicad_sch")
		(attr smd)
		(fp_rect
			(start -0.925 -0.47)
			(end 0.925 0.47)
			(stroke
				(width 0.05)
				(type default)
			)
			(fill no)
			(layer "F.CrtYd")
		)
		(fp_line
			(start -0.494 -0.25)
			(end 0.504 -0.25)
			(stroke
				(width 0.15)
				(type solid)
			)
			(layer "F.Fab")
		)
		(fp_line
			(start -0.494 0.248)
			(end -0.494 -0.25)
			(stroke
				(width 0.15)
				(type solid)
			)
			(layer "F.Fab")
		)
		(fp_line
			(start 0.504 -0.25)
			(end 0.504 0.248)
			(stroke
				(width 0.15)
				(type solid)
			)
			(layer "F.Fab")
		)
		(fp_line
			(start 0.504 0.248)
			(end -0.494 0.248)
			(stroke
				(width 0.15)
				(type solid)
			)
			(layer "F.Fab")
		)
		(fp_text user "Author: Antmicro"
			(at -0.939 3.399 0)
			(layer "F.Fab")
			(effects
				(font
					(size 0.7 0.7)
					(thickness 0.15)
				)
				(justify left bottom)
			)
		)
		(fp_text user "License: Apache-2.0"
			(at -0.939 5.799 0)
			(layer "F.Fab")
			(effects
				(font
					(size 0.7 0.7)
					(thickness 0.15)
				)
				(justify left bottom)
			)
		)
		(fp_text user "${REFERENCE}"
			(at -0.939 4.599 0)
			(layer "F.Fab")
			(effects
				(font
					(size 0.7 0.7)
					(thickness 0.15)
				)
				(justify left bottom)
			)
		)
		(pad "1" smd roundrect
			(at -0.48 0)
			(size 0.59 0.64)
			(layers "F.Cu" "F.Mask" "F.Paste")
			(roundrect_rratio 0.25)
			(net 23 "GND")
			(pintype "passive")
		)
		(pad "2" smd roundrect
			(at 0.48 0)
			(size 0.59 0.64)
			(layers "F.Cu" "F.Mask" "F.Paste")
			(roundrect_rratio 0.25)
			(net 108 "/X710 DCDC converters/1V88_VCC")
			(pintype "passive")
		)
	)
	(footprint "antmicro-footprints:R_0402_1005Metric"
		(layer "F.Cu")
		(at 125.02 86.5)
		(descr "Resistor SMD 0402")
		(tags "resistor SMD 0402")
		(property "Reference" "R120"
			(at -2.42 -0.509 0)
			(layer "F.SilkS")
			(effects
				(font
					(size 0.7 0.7)
					(thickness 0.15)
				)
				(justify left bottom)
			)
		)
		(property "Value" "R_8k2_0402"
			(at -1.011843 1.772047 0)
			(layer "F.Fab")
			(effects
				(font
					(size 0.7 0.7)
					(thickness 0.15)
				)
				(justify left bottom)
			)
		)
		(property "Datasheet" "https://www.bourns.com/docs/product-datasheets/cr.pdf"
			(at 0 0 0)
			(layer "F.Fab")
			(hide yes)
			(effects
				(font
					(size 1.27 1.27)
					(thickness 0.15)
				)
			)
		)
		(property "Description" "SMD Chip Resistor"
			(at 0 0 0)
			(layer "F.Fab")
			(hide yes)
			(effects
				(font
					(size 1.27 1.27)
					(thickness 0.15)
				)
			)
		)
		(property "MPN" "CR0402-FX-8201GLF"
			(at 0 0 0)
			(unlocked yes)
			(layer "F.Fab")
			(hide yes)
			(effects
				(font
					(size 1 1)
					(thickness 0.15)
				)
			)
		)
		(property "Manufacturer" "Bourns"
			(at 0 0 0)
			(unlocked yes)
			(layer "F.Fab")
			(hide yes)
			(effects
				(font
					(size 1 1)
					(thickness 0.15)
				)
			)
		)
		(property "License" "Apache-2.0"
			(at 0 0 0)
			(unlocked yes)
			(layer "F.Fab")
			(hide yes)
			(effects
				(font
					(size 1 1)
					(thickness 0.15)
				)
			)
		)
		(property "Author" "Antmicro"
			(at 0 0 0)
			(unlocked yes)
			(layer "F.Fab")
			(hide yes)
			(effects
				(font
					(size 1 1)
					(thickness 0.15)
				)
			)
		)
		(property "Val" "8k2"
			(at 0 0 0)
			(unlocked yes)
			(layer "F.Fab")
			(hide yes)
			(effects
				(font
					(size 1 1)
					(thickness 0.15)
				)
			)
		)
		(property "Tolerance" "1%"
			(at 0 0 0)
			(unlocked yes)
			(layer "F.Fab")
			(hide yes)
			(effects
				(font
					(size 1 1)
					(thickness 0.15)
				)
			)
		)
		(sheetname "/X710-AT2 PCIe/")
		(sheetfile "x710-at2-pcie.kicad_sch")
		(attr smd)
		(fp_rect
			(start -0.925 -0.47)
			(end 0.925 0.47)
			(stroke
				(width 0.05)
				(type default)
			)
			(fill no)
			(layer "F.CrtYd")
		)
		(fp_rect
			(start -0.5 -0.25)
			(end 0.5 0.25)
			(stroke
				(width 0.15)
				(type solid)
			)
			(fill no)
			(layer "F.Fab")
		)
		(fp_text user "License: Apache-2.0"
			(at -0.95 5.169 0)
			(layer "F.Fab")
			(effects
				(font
					(size 0.7 0.7)
					(thickness 0.15)
				)
				(justify left bottom)
			)
		)
		(fp_text user "Author: Antmicro"
			(at -0.95 4.169 0)
			(layer "F.Fab")
			(effects
				(font
					(size 0.7 0.7)
					(thickness 0.15)
				)
				(justify left bottom)
			)
		)
		(fp_text user "${REFERENCE}"
			(at -0.95 3.168 0)
			(layer "F.Fab")
			(effects
				(font
					(size 0.7 0.7)
					(thickness 0.15)
				)
				(justify left bottom)
			)
		)
		(pad "1" smd roundrect
			(at -0.48 0)
			(size 0.59 0.64)
			(layers "F.Cu" "F.Mask" "F.Paste")
			(roundrect_rratio 0.25)
			(net 23 "GND")
			(pintype "passive")
		)
		(pad "2" smd roundrect
			(at 0.48 0)
			(size 0.59 0.64)
			(layers "F.Cu" "F.Mask" "F.Paste")
			(roundrect_rratio 0.25)
			(net 15 "/X710-AT2 PCIe/PCIe_JTAG.~{JRST}")
			(pintype "passive")
		)
	)
	(footprint "antmicro-footprints:R_0402_1005Metric"
		(layer "F.Cu")
		(at 116.4 108.1)
		(descr "Resistor SMD 0402")
		(tags "resistor SMD 0402")
		(property "Reference" "R7"
			(at 0 -8.1 0)
			(layer "F.SilkS")
			(effects
				(font
					(size 0.7 0.7)
					(thickness 0.15)
				)
			)
		)
		(property "Value" "R_10k_0402"
			(at -1.011843 1.772047 0)
			(layer "F.Fab")
			(effects
				(font
					(size 0.7 0.7)
					(thickness 0.15)
				)
				(justify left bottom)
			)
		)
		(property "Datasheet" "https://www.bourns.com/docs/product-datasheets/cr.pdf"
			(at 0 0 0)
			(layer "F.Fab")
			(hide yes)
			(effects
				(font
					(size 1.27 1.27)
					(thickness 0.15)
				)
			)
		)
		(property "Description" "SMD Chip Resistor, 10 kohm, ± 1%, 62.5 mW, 0402 [1005 Metric], Thick Film, General Purpose"
			(at 0 0 0)
			(layer "F.Fab")
			(hide yes)
			(effects
				(font
					(size 1.27 1.27)
					(thickness 0.15)
				)
			)
		)
		(property "MPN" "CR0402-FX-1002GLF"
			(at 0 0 0)
			(unlocked yes)
			(layer "F.Fab")
			(hide yes)
			(effects
				(font
					(size 1 1)
					(thickness 0.15)
				)
			)
		)
		(property "Manufacturer" "Bourns"
			(at 0 0 0)
			(unlocked yes)
			(layer "F.Fab")
			(hide yes)
			(effects
				(font
					(size 1 1)
					(thickness 0.15)
				)
			)
		)
		(property "License" "Apache-2.0"
			(at 0 0 0)
			(unlocked yes)
			(layer "F.Fab")
			(hide yes)
			(effects
				(font
					(size 1 1)
					(thickness 0.15)
				)
			)
		)
		(property "Val" "10k"
			(at 0 0 0)
			(unlocked yes)
			(layer "F.Fab")
			(hide yes)
			(effects
				(font
					(size 1 1)
					(thickness 0.15)
				)
			)
		)
		(property "Tolerance" "1%"
			(at 0 0 0)
			(unlocked yes)
			(layer "F.Fab")
			(hide yes)
			(effects
				(font
					(size 1 1)
					(thickness 0.15)
				)
			)
		)
		(property "Author" "Antmicro"
			(at 0 0 0)
			(unlocked yes)
			(layer "F.Fab")
			(hide yes)
			(effects
				(font
					(size 1 1)
					(thickness 0.15)
				)
			)
		)
		(sheetname "/PD and TB DC-DC/")
		(sheetfile "PD_and_TB_DC_DC.kicad_sch")
		(attr smd)
		(fp_rect
			(start -0.925 -0.47)
			(end 0.925 0.47)
			(stroke
				(width 0.05)
				(type default)
			)
			(fill no)
			(layer "F.CrtYd")
		)
		(fp_rect
			(start -0.5 -0.25)
			(end 0.5 0.25)
			(stroke
				(width 0.15)
				(type solid)
			)
			(fill no)
			(layer "F.Fab")
		)
		(fp_text user "Author: Antmicro"
			(at -0.95 4.169 0)
			(layer "F.Fab")
			(effects
				(font
					(size 0.7 0.7)
					(thickness 0.15)
				)
				(justify left bottom)
			)
		)
		(fp_text user "${REFERENCE}"
			(at -0.95 3.168 0)
			(layer "F.Fab")
			(effects
				(font
					(size 0.7 0.7)
					(thickness 0.15)
				)
				(justify left bottom)
			)
		)
		(fp_text user "License: Apache-2.0"
			(at -0.95 5.169 0)
			(layer "F.Fab")
			(effects
				(font
					(size 0.7 0.7)
					(thickness 0.15)
				)
				(justify left bottom)
			)
		)
		(pad "1" smd roundrect
			(at -0.48 0)
			(size 0.59 0.64)
			(layers "F.Cu" "F.Mask" "F.Paste")
			(roundrect_rratio 0.25)
			(net 23 "GND")
			(pintype "passive")
		)
		(pad "2" smd roundrect
			(at 0.48 0)
			(size 0.59 0.64)
			(layers "F.Cu" "F.Mask" "F.Paste")
			(roundrect_rratio 0.25)
			(net 413 "Net-(D3-C)")
			(pintype "passive")
		)
	)
	(footprint "antmicro-footprints:R_0402_1005Metric"
		(layer "F.Cu")
		(at 139 68.5)
		(descr "Resistor SMD 0402")
		(tags "resistor SMD 0402")
		(property "Reference" "R114"
			(at 1 0.450001 0)
			(layer "F.SilkS")
			(effects
				(font
					(size 0.7 0.7)
					(thickness 0.15)
				)
				(justify left bottom)
			)
		)
		(property "Value" "R_0R_0402"
			(at -1.011843 1.772047 0)
			(layer "F.Fab")
			(effects
				(font
					(size 0.7 0.7)
					(thickness 0.15)
				)
				(justify left bottom)
			)
		)
		(property "Datasheet" "https://industrial.panasonic.com/cdbs/www-data/pdf/RDA0000/AOA0000C301.pdf"
			(at 0 0 0)
			(layer "F.Fab")
			(hide yes)
			(effects
				(font
					(size 1.27 1.27)
					(thickness 0.15)
				)
			)
		)
		(property "Description" "SMD Chip Resistor, Jumper, 0 ohm, 100 mW, 0402 [1005 Metric], Thick Film, General Purpose"
			(at 0 0 0)
			(layer "F.Fab")
			(hide yes)
			(effects
				(font
					(size 1.27 1.27)
					(thickness 0.15)
				)
			)
		)
		(property "MPN" "ERJ2GE0R00X"
			(at 0 0 0)
			(unlocked yes)
			(layer "F.Fab")
			(hide yes)
			(effects
				(font
					(size 1 1)
					(thickness 0.15)
				)
			)
		)
		(property "Manufacturer" "Panasonic"
			(at 0 0 0)
			(unlocked yes)
			(layer "F.Fab")
			(hide yes)
			(effects
				(font
					(size 1 1)
					(thickness 0.15)
				)
			)
		)
		(property "License" "Apache-2.0"
			(at 0 0 0)
			(unlocked yes)
			(layer "F.Fab")
			(hide yes)
			(effects
				(font
					(size 1 1)
					(thickness 0.15)
				)
			)
		)
		(property "Author" "Antmicro"
			(at 0 0 0)
			(unlocked yes)
			(layer "F.Fab")
			(hide yes)
			(effects
				(font
					(size 1 1)
					(thickness 0.15)
				)
			)
		)
		(property "Val" "0R"
			(at 0 0 0)
			(unlocked yes)
			(layer "F.Fab")
			(hide yes)
			(effects
				(font
					(size 1 1)
					(thickness 0.15)
				)
			)
		)
		(property "Tolerance" "~"
			(at 0 0 0)
			(unlocked yes)
			(layer "F.Fab")
			(hide yes)
			(effects
				(font
					(size 1 1)
					(thickness 0.15)
				)
			)
		)
		(property "Current" "1A"
			(at 0 0 0)
			(unlocked yes)
			(layer "F.Fab")
			(hide yes)
			(effects
				(font
					(size 1 1)
					(thickness 0.15)
				)
			)
		)
		(sheetname "/X710-AT2 PCIe/")
		(sheetfile "x710-at2-pcie.kicad_sch")
		(attr smd)
		(fp_rect
			(start -0.925 -0.47)
			(end 0.925 0.47)
			(stroke
				(width 0.05)
				(type default)
			)
			(fill no)
			(layer "F.CrtYd")
		)
		(fp_rect
			(start -0.5 -0.25)
			(end 0.5 0.25)
			(stroke
				(width 0.15)
				(type solid)
			)
			(fill no)
			(layer "F.Fab")
		)
		(fp_text user "License: Apache-2.0"
			(at -0.95 5.169 0)
			(layer "F.Fab")
			(effects
				(font
					(size 0.7 0.7)
					(thickness 0.15)
				)
				(justify left bottom)
			)
		)
		(fp_text user "Author: Antmicro"
			(at -0.95 4.169 0)
			(layer "F.Fab")
			(effects
				(font
					(size 0.7 0.7)
					(thickness 0.15)
				)
				(justify left bottom)
			)
		)
		(fp_text user "${REFERENCE}"
			(at -0.95 3.168 0)
			(layer "F.Fab")
			(effects
				(font
					(size 0.7 0.7)
					(thickness 0.15)
				)
				(justify left bottom)
			)
		)
		(pad "1" smd roundrect
			(at -0.48 0)
			(size 0.59 0.64)
			(layers "F.Cu" "F.Mask" "F.Paste")
			(roundrect_rratio 0.25)
			(net 394 "/TB Controller/REFCLK.-")
			(pintype "passive")
		)
		(pad "2" smd roundrect
			(at 0.48 0)
			(size 0.59 0.64)
			(layers "F.Cu" "F.Mask" "F.Paste")
			(roundrect_rratio 0.25)
			(net 160 "/X710-AT2 PCIe/CLK-")
			(pintype "passive")
		)
	)
	(footprint "antmicro-footprints:SOT-23-6"
		(layer "F.Cu")
		(at 142.25 61.25 90)
		(property "Reference" "U21"
			(at -0.55 -2.05 90)
			(layer "F.SilkS")
			(effects
				(font
					(size 0.7 0.7)
					(thickness 0.15)
				)
				(justify left bottom)
			)
		)
		(property "Value" "LTC4412IS6"
			(at -1.75 2.693 90)
			(layer "F.Fab")
			(effects
				(font
					(size 0.7 0.7)
					(thickness 0.15)
				)
				(justify left bottom)
			)
		)
		(property "Datasheet" "https://www.analog.com/media/en/technical-documentation/data-sheets/4412fb.pdf"
			(at 0 -0.057 90)
			(layer "F.Fab")
			(hide yes)
			(effects
				(font
					(size 1.27 1.27)
					(thickness 0.15)
				)
			)
		)
		(property "Description" "Ideal diode controller"
			(at 0 -0.057 90)
			(layer "F.Fab")
			(hide yes)
			(effects
				(font
					(size 1.27 1.27)
					(thickness 0.15)
				)
			)
		)
		(property "MPN" "LTC4412IS6#TRMPBF"
			(at 0 0 90)
			(unlocked yes)
			(layer "F.Fab")
			(hide yes)
			(effects
				(font
					(size 1 1)
					(thickness 0.15)
				)
			)
		)
		(property "Manufacturer" "Analog Devices"
			(at 0 0 90)
			(unlocked yes)
			(layer "F.Fab")
			(hide yes)
			(effects
				(font
					(size 1 1)
					(thickness 0.15)
				)
			)
		)
		(property "Author" "Antmicro"
			(at 0 0 90)
			(unlocked yes)
			(layer "F.Fab")
			(hide yes)
			(effects
				(font
					(size 1 1)
					(thickness 0.15)
				)
			)
		)
		(property "License" "Apache-2.0"
			(at 0 0 90)
			(unlocked yes)
			(layer "F.Fab")
			(hide yes)
			(effects
				(font
					(size 1 1)
					(thickness 0.15)
				)
			)
		)
		(sheetname "/Power input/")
		(sheetfile "power_input.kicad_sch")
		(attr smd)
		(fp_line
			(start 1.45 -0.757)
			(end 1.45 -0.457)
			(stroke
				(width 0.12)
				(type solid)
			)
			(layer "F.SilkS")
		)
		(fp_line
			(start 1.3 -0.757)
			(end 1.45 -0.757)
			(stroke
				(width 0.12)
				(type solid)
			)
			(layer "F.SilkS")
		)
		(fp_line
			(start -1.3 -0.757)
			(end -1.45 -0.757)
			(stroke
				(width 0.12)
				(type solid)
			)
			(layer "F.SilkS")
		)
		(fp_line
			(start -1.45 -0.757)
			(end -1.45 -0.457)
			(stroke
				(width 0.12)
				(type solid)
			)
			(layer "F.SilkS")
		)
		(fp_line
			(start 1.45 0.643)
			(end 1.45 0.343)
			(stroke
				(width 0.12)
				(type solid)
			)
			(layer "F.SilkS")
		)
		(fp_line
			(start 1.3 0.643)
			(end 1.45 0.643)
			(stroke
				(width 0.12)
				(type solid)
			)
			(layer "F.SilkS")
		)
		(fp_line
			(start -1.45 0.643)
			(end -1.45 0.343)
			(stroke
				(width 0.12)
				(type solid)
			)
			(layer "F.SilkS")
		)
		(fp_rect
			(start -1.55 -1.85)
			(end 1.55 1.75)
			(stroke
				(width 0.05)
				(type solid)
			)
			(fill no)
			(layer "F.CrtYd")
		)
		(fp_line
			(start 1.5 -0.757)
			(end 1.5 0.643)
			(stroke
				(width 0.1)
				(type solid)
			)
			(layer "F.Fab")
		)
		(fp_line
			(start -1.5 -0.757)
			(end 1.5 -0.757)
			(stroke
				(width 0.1)
				(type solid)
			)
			(layer "F.Fab")
		)
		(fp_line
			(start 1.5 0.643)
			(end -1.5 0.643)
			(stroke
				(width 0.1)
				(type solid)
			)
			(layer "F.Fab")
		)
		(fp_line
			(start -1.5 0.643)
			(end -1.5 -0.757)
			(stroke
				(width 0.1)
				(type solid)
			)
			(layer "F.Fab")
		)
		(fp_text user "."
			(at -1.4 1.143 270)
			(layer "F.SilkS")
			(effects
				(font
					(size 1 1)
					(thickness 0.15)
				)
			)
		)
		(fp_text user "${REFERENCE}"
			(at -1.75 4 90)
			(layer "F.Fab")
			(effects
				(font
					(size 0.7 0.7)
					(thickness 0.15)
				)
				(justify left bottom)
			)
		)
		(fp_text user "License: Apache-2.0"
			(at -1.75 6.5 90)
			(layer "F.Fab")
			(effects
				(font
					(size 0.7 0.7)
					(thickness 0.15)
				)
				(justify left bottom)
			)
		)
		(fp_text user "Author: Antmicro"
			(at -1.829 5.25 90)
			(layer "F.Fab")
			(effects
				(font
					(size 0.7 0.7)
					(thickness 0.15)
				)
				(justify left bottom)
			)
		)
		(pad "1" smd roundrect
			(at -0.954 1.1 90)
			(size 0.55 1)
			(layers "F.Cu" "F.Mask" "F.Paste")
			(roundrect_rratio 0.15)
			(net 13 "/Power input/5V_JACK")
			(pinfunction "IN")
			(pintype "power_in")
		)
		(pad "2" smd roundrect
			(at -0.003 1.1 90)
			(size 0.55 1)
			(layers "F.Cu" "F.Mask" "F.Paste")
			(roundrect_rratio 0.15)
			(net 23 "GND")
			(pinfunction "GND")
			(pintype "power_in")
		)
		(pad "3" smd roundrect
			(at 0.947 1.1 90)
			(size 0.55 1)
			(layers "F.Cu" "F.Mask" "F.Paste")
			(roundrect_rratio 0.15)
			(net 23 "GND")
			(pinfunction "CTL")
			(pintype "input")
		)
		(pad "4" smd roundrect
			(at 0.947 -1.214 90)
			(size 0.55 1)
			(layers "F.Cu" "F.Mask" "F.Paste")
			(roundrect_rratio 0.15)
			(net 593 "unconnected-(U21-STAT-Pad4)")
			(pinfunction "STAT")
			(pintype "output+no_connect")
		)
		(pad "5" smd roundrect
			(at -0.003 -1.214 90)
			(size 0.55 1)
			(layers "F.Cu" "F.Mask" "F.Paste")
			(roundrect_rratio 0.15)
			(net 432 "Net-(Q7-G)")
			(pinfunction "GATE")
			(pintype "output")
		)
		(pad "6" smd roundrect
			(at -0.954 -1.214 90)
			(size 0.55 1)
			(layers "F.Cu" "F.Mask" "F.Paste")
			(roundrect_rratio 0.15)
			(net 40 "+5V")
			(pinfunction "SENSE")
			(pintype "input")
		)
	)
	(footprint "antmicro-footprints:C_2220_5650Metric"
		(layer "F.Cu")
		(at 149 51 90)
		(descr "Capacitor SMD 2220")
		(tags "capacitor SMD 2220")
		(property "Reference" "C313"
			(at 3.6 -3 180)
			(layer "F.SilkS")
			(effects
				(font
					(size 0.7 0.7)
					(thickness 0.15)
				)
				(justify left bottom)
			)
		)
		(property "Value" "C_22u_100V_2220"
			(at 0 3.9 90)
			(layer "F.Fab")
			(effects
				(font
					(size 0.7 0.7)
					(thickness 0.15)
				)
				(justify left bottom)
			)
		)
		(property "Datasheet" "https://product.tdk.com/en/search/capacitor/ceramic/mlcc/info?part_no=C5750X7S2A226M280KB"
			(at 0 0 90)
			(layer "F.Fab")
			(hide yes)
			(effects
				(font
					(size 1.27 1.27)
					(thickness 0.15)
				)
			)
		)
		(property "Description" "SMT Multilayer Ceramic Capacitor, 22 µF, 100 V, 2220 [5750 Metric], ± 20%, X7S, C"
			(at 0 0 90)
			(layer "F.Fab")
			(hide yes)
			(effects
				(font
					(size 1.27 1.27)
					(thickness 0.15)
				)
			)
		)
		(property "MPN" "C5750X7S2A226M280KB"
			(at 0 0 90)
			(unlocked yes)
			(layer "F.Fab")
			(hide yes)
			(effects
				(font
					(size 1 1)
					(thickness 0.15)
				)
			)
		)
		(property "Manufacturer" "TDK"
			(at 0 0 90)
			(unlocked yes)
			(layer "F.Fab")
			(hide yes)
			(effects
				(font
					(size 1 1)
					(thickness 0.15)
				)
			)
		)
		(property "License" "Apache-2.0"
			(at 0 0 90)
			(unlocked yes)
			(layer "F.Fab")
			(hide yes)
			(effects
				(font
					(size 1 1)
					(thickness 0.15)
				)
			)
		)
		(property "Author" "Antmicro"
			(at 0 0 90)
			(unlocked yes)
			(layer "F.Fab")
			(hide yes)
			(effects
				(font
					(size 1 1)
					(thickness 0.15)
				)
			)
		)
		(property "Val" "22u"
			(at 0 0 90)
			(unlocked yes)
			(layer "F.Fab")
			(hide yes)
			(effects
				(font
					(size 1 1)
					(thickness 0.15)
				)
			)
		)
		(property "Voltage" "100V"
			(at 0 0 90)
			(unlocked yes)
			(layer "F.Fab")
			(hide yes)
			(effects
				(font
					(size 1 1)
					(thickness 0.15)
				)
			)
		)
		(property "Dielectric" "X7S"
			(at 0 0 90)
			(unlocked yes)
			(layer "F.Fab")
			(hide yes)
			(effects
				(font
					(size 1 1)
					(thickness 0.15)
				)
			)
		)
		(property "Public" "False"
			(at 0 0 90)
			(unlocked yes)
			(layer "F.Fab")
			(hide yes)
			(effects
				(font
					(size 1 1)
					(thickness 0.15)
				)
			)
		)
		(sheetname "/Power input/")
		(sheetfile "power_input.kicad_sch")
		(attr smd)
		(fp_line
			(start -1.415 -2.61)
			(end 1.415 -2.61)
			(stroke
				(width 0.15)
				(type solid)
			)
			(layer "F.SilkS")
		)
		(fp_line
			(start -1.415 2.61)
			(end 1.415 2.61)
			(stroke
				(width 0.15)
				(type solid)
			)
			(layer "F.SilkS")
		)
		(fp_rect
			(start -3.7 -2.95)
			(end 3.7 2.95)
			(stroke
				(width 0.05)
				(type solid)
			)
			(fill no)
			(layer "F.CrtYd")
		)
		(fp_rect
			(start -2.85 -2.5)
			(end 2.85 2.5)
			(stroke
				(width 0.15)
				(type solid)
			)
			(fill no)
			(layer "F.Fab")
		)
		(fp_text user "License: Apache-2.0"
			(at -3.7 6.9 90)
			(layer "F.Fab")
			(effects
				(font
					(size 0.7 0.7)
					(thickness 0.15)
				)
				(justify left bottom)
			)
		)
		(fp_text user "${REFERENCE}"
			(at -3.7 5.9 90)
			(layer "F.Fab")
			(effects
				(font
					(size 0.7 0.7)
					(thickness 0.15)
				)
				(justify left bottom)
			)
		)
		(fp_text user "Author: Antmicro"
			(at -3.7 7.9 90)
			(layer "F.Fab")
			(effects
				(font
					(size 0.7 0.7)
					(thickness 0.15)
				)
				(justify left bottom)
			)
		)
		(pad "1" smd roundrect
			(at -2.55 0 90)
			(size 1.8 5.4)
			(layers "F.Cu" "F.Mask" "F.Paste")
			(roundrect_rratio 0.138889)
			(net 23 "GND")
			(pintype "passive")
		)
		(pad "2" smd roundrect
			(at 2.55 0 90)
			(size 1.8 5.4)
			(layers "F.Cu" "F.Mask" "F.Paste")
			(roundrect_rratio 0.138889)
			(net 412 "Net-(D15-C)")
			(pintype "passive")
		)
	)
	(footprint "antmicro-footprints:R_0402_1005Metric"
		(layer "F.Cu")
		(at 117 70.9)
		(descr "Resistor SMD 0402")
		(tags "resistor SMD 0402")
		(property "Reference" "R222"
			(at 3.6 -10.5 0)
			(layer "F.SilkS")
			(effects
				(font
					(size 0.7 0.7)
					(thickness 0.15)
				)
				(justify left bottom)
			)
		)
		(property "Value" "R_10k_0402"
			(at -1.011843 1.772047 0)
			(layer "F.Fab")
			(effects
				(font
					(size 0.7 0.7)
					(thickness 0.15)
				)
				(justify left bottom)
			)
		)
		(property "Datasheet" "https://www.bourns.com/docs/product-datasheets/cr.pdf"
			(at 0 0 0)
			(layer "F.Fab")
			(hide yes)
			(effects
				(font
					(size 1.27 1.27)
					(thickness 0.15)
				)
			)
		)
		(property "Description" "SMD Chip Resistor, 10 kohm, ± 1%, 62.5 mW, 0402 [1005 Metric], Thick Film, General Purpose"
			(at 0 0 0)
			(layer "F.Fab")
			(hide yes)
			(effects
				(font
					(size 1.27 1.27)
					(thickness 0.15)
				)
			)
		)
		(property "MPN" "CR0402-FX-1002GLF"
			(at 0 0 0)
			(unlocked yes)
			(layer "F.Fab")
			(hide yes)
			(effects
				(font
					(size 1 1)
					(thickness 0.15)
				)
			)
		)
		(property "Manufacturer" "Bourns"
			(at 0 0 0)
			(unlocked yes)
			(layer "F.Fab")
			(hide yes)
			(effects
				(font
					(size 1 1)
					(thickness 0.15)
				)
			)
		)
		(property "License" "Apache-2.0"
			(at 0 0 0)
			(unlocked yes)
			(layer "F.Fab")
			(hide yes)
			(effects
				(font
					(size 1 1)
					(thickness 0.15)
				)
			)
		)
		(property "Author" "Antmicro"
			(at 0 0 0)
			(unlocked yes)
			(layer "F.Fab")
			(hide yes)
			(effects
				(font
					(size 1 1)
					(thickness 0.15)
				)
			)
		)
		(property "Val" "10k"
			(at 0 0 0)
			(unlocked yes)
			(layer "F.Fab")
			(hide yes)
			(effects
				(font
					(size 1 1)
					(thickness 0.15)
				)
			)
		)
		(property "Tolerance" "1%"
			(at 0 0 0)
			(unlocked yes)
			(layer "F.Fab")
			(hide yes)
			(effects
				(font
					(size 1 1)
					(thickness 0.15)
				)
			)
		)
		(sheetname "/Fan controller/")
		(sheetfile "fan-controller.kicad_sch")
		(attr smd)
		(fp_rect
			(start -0.925 -0.47)
			(end 0.925 0.47)
			(stroke
				(width 0.05)
				(type default)
			)
			(fill no)
			(layer "F.CrtYd")
		)
		(fp_rect
			(start -0.5 -0.25)
			(end 0.5 0.25)
			(stroke
				(width 0.15)
				(type solid)
			)
			(fill no)
			(layer "F.Fab")
		)
		(fp_text user "Author: Antmicro"
			(at -0.95 4.169 0)
			(layer "F.Fab")
			(effects
				(font
					(size 0.7 0.7)
					(thickness 0.15)
				)
				(justify left bottom)
			)
		)
		(fp_text user "${REFERENCE}"
			(at -0.95 3.168 0)
			(layer "F.Fab")
			(effects
				(font
					(size 0.7 0.7)
					(thickness 0.15)
				)
				(justify left bottom)
			)
		)
		(fp_text user "License: Apache-2.0"
			(at -0.95 5.169 0)
			(layer "F.Fab")
			(effects
				(font
					(size 0.7 0.7)
					(thickness 0.15)
				)
				(justify left bottom)
			)
		)
		(pad "1" smd roundrect
			(at -0.48 0)
			(size 0.59 0.64)
			(layers "F.Cu" "F.Mask" "F.Paste")
			(roundrect_rratio 0.25)
			(net 23 "GND")
			(pintype "passive")
		)
		(pad "2" smd roundrect
			(at 0.48 0)
			(size 0.59 0.64)
			(layers "F.Cu" "F.Mask" "F.Paste")
			(roundrect_rratio 0.25)
			(net 158 "/Fan controller/SLOPE")
			(pintype "passive")
		)
	)
	(footprint "antmicro-footprints:C_0402_1005Metric"
		(layer "F.Cu")
		(at 138 72.25)
		(descr "Capacitor SMD 0402")
		(tags "capacitor SMD 0402")
		(property "Reference" "C270"
			(at -3.8 0.45 0)
			(layer "F.SilkS")
			(effects
				(font
					(size 0.7 0.7)
					(thickness 0.15)
				)
				(justify left bottom)
			)
		)
		(property "Value" "C_220n_16V_0402"
			(at -1.022927 2.155213 0)
			(layer "F.Fab")
			(effects
				(font
					(size 0.7 0.7)
					(thickness 0.15)
				)
				(justify left bottom)
			)
		)
		(property "Datasheet" "https://www.murata.com/products/productdetail?partno=GRM155R71C224KA12%23"
			(at 0 0 0)
			(layer "F.Fab")
			(hide yes)
			(effects
				(font
					(size 1.27 1.27)
					(thickness 0.15)
				)
			)
		)
		(property "Description" "SMD Multilayer Ceramic Capacitor, 0.22 µF, 16 V, 0402 [1005 Metric], ± 10%, X7R, GRM Series"
			(at 0 0 0)
			(layer "F.Fab")
			(hide yes)
			(effects
				(font
					(size 1.27 1.27)
					(thickness 0.15)
				)
			)
		)
		(property "MPN" "GRM155R71C224KA12D"
			(at 0 0 0)
			(unlocked yes)
			(layer "F.Fab")
			(hide yes)
			(effects
				(font
					(size 1 1)
					(thickness 0.15)
				)
			)
		)
		(property "Manufacturer" "Murata"
			(at 0 0 0)
			(unlocked yes)
			(layer "F.Fab")
			(hide yes)
			(effects
				(font
					(size 1 1)
					(thickness 0.15)
				)
			)
		)
		(property "License" "Apache-2.0"
			(at 0 0 0)
			(unlocked yes)
			(layer "F.Fab")
			(hide yes)
			(effects
				(font
					(size 1 1)
					(thickness 0.15)
				)
			)
		)
		(property "Author" "Antmicro"
			(at 0 0 0)
			(unlocked yes)
			(layer "F.Fab")
			(hide yes)
			(effects
				(font
					(size 1 1)
					(thickness 0.15)
				)
			)
		)
		(property "Val" "220n"
			(at 0 0 0)
			(unlocked yes)
			(layer "F.Fab")
			(hide yes)
			(effects
				(font
					(size 1 1)
					(thickness 0.15)
				)
			)
		)
		(property "Voltage" "16V"
			(at 0 0 0)
			(unlocked yes)
			(layer "F.Fab")
			(hide yes)
			(effects
				(font
					(size 1 1)
					(thickness 0.15)
				)
			)
		)
		(property "Dielectric" "X7R"
			(at 0 0 0)
			(unlocked yes)
			(layer "F.Fab")
			(hide yes)
			(effects
				(font
					(size 1 1)
					(thickness 0.15)
				)
			)
		)
		(sheetname "/X710-AT2 PCIe/")
		(sheetfile "x710-at2-pcie.kicad_sch")
		(attr smd)
		(fp_rect
			(start -0.925 -0.47)
			(end 0.925 0.47)
			(stroke
				(width 0.05)
				(type default)
			)
			(fill no)
			(layer "F.CrtYd")
		)
		(fp_line
			(start -0.494 -0.25)
			(end 0.504 -0.25)
			(stroke
				(width 0.15)
				(type solid)
			)
			(layer "F.Fab")
		)
		(fp_line
			(start -0.494 0.248)
			(end -0.494 -0.25)
			(stroke
				(width 0.15)
				(type solid)
			)
			(layer "F.Fab")
		)
		(fp_line
			(start 0.504 -0.25)
			(end 0.504 0.248)
			(stroke
				(width 0.15)
				(type solid)
			)
			(layer "F.Fab")
		)
		(fp_line
			(start 0.504 0.248)
			(end -0.494 0.248)
			(stroke
				(width 0.15)
				(type solid)
			)
			(layer "F.Fab")
		)
		(fp_text user "Author: Antmicro"
			(at -0.939 3.399 0)
			(layer "F.Fab")
			(effects
				(font
					(size 0.7 0.7)
					(thickness 0.15)
				)
				(justify left bottom)
			)
		)
		(fp_text user "${REFERENCE}"
			(at -0.939 4.599 0)
			(layer "F.Fab")
			(effects
				(font
					(size 0.7 0.7)
					(thickness 0.15)
				)
				(justify left bottom)
			)
		)
		(fp_text user "License: Apache-2.0"
			(at -0.939 5.799 0)
			(layer "F.Fab")
			(effects
				(font
					(size 0.7 0.7)
					(thickness 0.15)
				)
				(justify left bottom)
			)
		)
		(pad "1" smd roundrect
			(at -0.48 0)
			(size 0.59 0.64)
			(layers "F.Cu" "F.Mask" "F.Paste")
			(roundrect_rratio 0.25)
			(net 596 "/TB Controller/PCIex4.TX0+")
			(pintype "passive")
		)
		(pad "2" smd roundrect
			(at 0.48 0)
			(size 0.59 0.64)
			(layers "F.Cu" "F.Mask" "F.Paste")
			(roundrect_rratio 0.25)
			(net 27 "/X710-AT2 PCIe/PCIe_{x4}_AC.TX0+")
			(pintype "passive")
		)
	)
	(footprint "antmicro-footprints:C_0402_1005Metric"
		(layer "F.Cu")
		(at 126.4 94.9)
		(descr "Capacitor SMD 0402")
		(tags "capacitor SMD 0402")
		(property "Reference" "C41"
			(at -0.9 -0.6 0)
			(layer "F.SilkS")
			(effects
				(font
					(size 0.7 0.7)
					(thickness 0.15)
				)
				(justify left bottom)
			)
		)
		(property "Value" "C_100n_0402"
			(at -1.022927 2.155213 0)
			(layer "F.Fab")
			(effects
				(font
					(size 0.7 0.7)
					(thickness 0.15)
				)
				(justify left bottom)
			)
		)
		(property "Datasheet" "https://www.murata.com/products/productdetail?partno=GRM155R61H104KE14%23"
			(at 0 0 0)
			(layer "F.Fab")
			(hide yes)
			(effects
				(font
					(size 1.27 1.27)
					(thickness 0.15)
				)
			)
		)
		(property "Description" "SMD Multilayer Ceramic Capacitor, 0.1 µF, 50 V, 0402 [1005 Metric], ± 10%, X5R, GRM Series"
			(at 0 0 0)
			(layer "F.Fab")
			(hide yes)
			(effects
				(font
					(size 1.27 1.27)
					(thickness 0.15)
				)
			)
		)
		(property "MPN" "GRM155R61H104KE14D"
			(at 0 0 0)
			(unlocked yes)
			(layer "F.Fab")
			(hide yes)
			(effects
				(font
					(size 1 1)
					(thickness 0.15)
				)
			)
		)
		(property "Manufacturer" "Murata"
			(at 0 0 0)
			(unlocked yes)
			(layer "F.Fab")
			(hide yes)
			(effects
				(font
					(size 1 1)
					(thickness 0.15)
				)
			)
		)
		(property "License" "Apache-2.0"
			(at 0 0 0)
			(unlocked yes)
			(layer "F.Fab")
			(hide yes)
			(effects
				(font
					(size 1 1)
					(thickness 0.15)
				)
			)
		)
		(property "Val" "100n"
			(at 0 0 0)
			(unlocked yes)
			(layer "F.Fab")
			(hide yes)
			(effects
				(font
					(size 1 1)
					(thickness 0.15)
				)
			)
		)
		(property "Voltage" "50V"
			(at 0 0 0)
			(unlocked yes)
			(layer "F.Fab")
			(hide yes)
			(effects
				(font
					(size 1 1)
					(thickness 0.15)
				)
			)
		)
		(property "Dielectric" "X5R"
			(at 0 0 0)
			(unlocked yes)
			(layer "F.Fab")
			(hide yes)
			(effects
				(font
					(size 1 1)
					(thickness 0.15)
				)
			)
		)
		(property "Author" "Antmicro"
			(at 0 0 0)
			(unlocked yes)
			(layer "F.Fab")
			(hide yes)
			(effects
				(font
					(size 1 1)
					(thickness 0.15)
				)
			)
		)
		(sheetname "/TB Controller/")
		(sheetfile "tb.kicad_sch")
		(attr smd)
		(fp_rect
			(start -0.925 -0.47)
			(end 0.925 0.47)
			(stroke
				(width 0.05)
				(type default)
			)
			(fill no)
			(layer "F.CrtYd")
		)
		(fp_line
			(start -0.494 -0.25)
			(end 0.504 -0.25)
			(stroke
				(width 0.15)
				(type solid)
			)
			(layer "F.Fab")
		)
		(fp_line
			(start -0.494 0.248)
			(end -0.494 -0.25)
			(stroke
				(width 0.15)
				(type solid)
			)
			(layer "F.Fab")
		)
		(fp_line
			(start 0.504 -0.25)
			(end 0.504 0.248)
			(stroke
				(width 0.15)
				(type solid)
			)
			(layer "F.Fab")
		)
		(fp_line
			(start 0.504 0.248)
			(end -0.494 0.248)
			(stroke
				(width 0.15)
				(type solid)
			)
			(layer "F.Fab")
		)
		(fp_text user "Author: Antmicro"
			(at -0.939 3.399 0)
			(layer "F.Fab")
			(effects
				(font
					(size 0.7 0.7)
					(thickness 0.15)
				)
				(justify left bottom)
			)
		)
		(fp_text user "${REFERENCE}"
			(at -0.939 4.599 0)
			(layer "F.Fab")
			(effects
				(font
					(size 0.7 0.7)
					(thickness 0.15)
				)
				(justify left bottom)
			)
		)
		(fp_text user "License: Apache-2.0"
			(at -0.939 5.799 0)
			(layer "F.Fab")
			(effects
				(font
					(size 0.7 0.7)
					(thickness 0.15)
				)
				(justify left bottom)
			)
		)
		(pad "1" smd roundrect
			(at -0.48 0)
			(size 0.59 0.64)
			(layers "F.Cu" "F.Mask" "F.Paste")
			(roundrect_rratio 0.25)
			(net 23 "GND")
			(pintype "passive")
		)
		(pad "2" smd roundrect
			(at 0.48 0)
			(size 0.59 0.64)
			(layers "F.Cu" "F.Mask" "F.Paste")
			(roundrect_rratio 0.25)
			(net 57 "+3V3_TB")
			(pintype "passive")
		)
	)
	(footprint "antmicro-footprints:SW_DS04-254-1-01BK-SMT"
		(layer "F.Cu")
		(at 118 59.5 -90)
		(property "Reference" "SW1"
			(at -2.25 -3 270)
			(layer "F.SilkS")
			(effects
				(font
					(size 0.7 0.7)
					(thickness 0.15)
				)
				(justify left bottom)
			)
		)
		(property "Value" "SW_DS04-254-1-01BK-SMT"
			(at 0 3 270)
			(layer "F.Fab")
			(effects
				(font
					(size 0.7 0.7)
					(thickness 0.15)
				)
				(justify left bottom)
			)
		)
		(property "Datasheet" "https://www.mouser.com/datasheet/2/670/ds04_254_smt-1777718.pdf"
			(at 0 0 270)
			(layer "F.Fab")
			(hide yes)
			(effects
				(font
					(size 1.27 1.27)
					(thickness 0.15)
				)
			)
		)
		(property "Description" "Slide switch"
			(at 0 0 270)
			(layer "F.Fab")
			(hide yes)
			(effects
				(font
					(size 1.27 1.27)
					(thickness 0.15)
				)
			)
		)
		(property "MPN" "DS04-254-1-01BK-SMT"
			(at 0 0 270)
			(unlocked yes)
			(layer "F.Fab")
			(hide yes)
			(effects
				(font
					(size 1 1)
					(thickness 0.15)
				)
			)
		)
		(property "Manufacturer" "CUI Inc"
			(at 0 0 270)
			(unlocked yes)
			(layer "F.Fab")
			(hide yes)
			(effects
				(font
					(size 1 1)
					(thickness 0.15)
				)
			)
		)
		(property "Author" "Antmicro"
			(at 0 0 270)
			(unlocked yes)
			(layer "F.Fab")
			(hide yes)
			(effects
				(font
					(size 1 1)
					(thickness 0.15)
				)
			)
		)
		(property "License" "Apache-2.0"
			(at 0 0 270)
			(unlocked yes)
			(layer "F.Fab")
			(hide yes)
			(effects
				(font
					(size 1 1)
					(thickness 0.15)
				)
			)
		)
		(property ki_fp_filters "SW?DIP?x1*")
		(sheetname "/X710-AT2 RSVD/")
		(sheetfile "x710-at2-rsvd.kicad_sch")
		(attr smd dnp)
		(fp_rect
			(start -3.3 -2)
			(end 3.3 2)
			(stroke
				(width 0.15)
				(type solid)
			)
			(fill no)
			(layer "F.SilkS")
		)
		(fp_rect
			(start -5.25 -2.025)
			(end 5.25 2.025)
			(stroke
				(width 0.05)
				(type solid)
			)
			(fill no)
			(layer "F.CrtYd")
		)
		(fp_rect
			(start -3.1 -1.8)
			(end 3.1 1.8)
			(stroke
				(width 0.15)
				(type solid)
			)
			(fill no)
			(layer "F.Fab")
		)
		(fp_text user "Author: Antmicro"
			(at -5.25 5.6 270)
			(layer "F.Fab")
			(effects
				(font
					(size 0.7 0.7)
					(thickness 0.15)
				)
				(justify left bottom)
			)
		)
		(fp_text user "License: Apache-2.0"
			(at -5.25 6.799 270)
			(layer "F.Fab")
			(effects
				(font
					(size 0.7 0.7)
					(thickness 0.15)
				)
				(justify left bottom)
			)
		)
		(fp_text user "${REFERENCE}"
			(at -5.25 4.4 270)
			(layer "F.Fab")
			(effects
				(font
					(size 0.7 0.7)
					(thickness 0.15)
				)
				(justify left bottom)
			)
		)
		(pad "1" smd rect
			(at -4.472 0.038 270)
			(size 1.5 1.1)
			(layers "F.Cu" "F.Mask" "F.Paste")
			(net 86 "/X710-AT2 RSVD/DEBUG_EN")
			(pintype "passive")
		)
		(pad "2" smd rect
			(at 4.428 0.038 90)
			(size 1.5 1.1)
			(layers "F.Cu" "F.Mask" "F.Paste")
			(net 7 "+3V3")
			(pintype "passive")
		)
	)
	(footprint "antmicro-footprints:C_0402_1005Metric"
		(layer "F.Cu")
		(at 118 140.2)
		(descr "Capacitor SMD 0402")
		(tags "capacitor SMD 0402")
		(property "Reference" "C5"
			(at 1 0.4 0)
			(layer "F.SilkS")
			(effects
				(font
					(size 0.7 0.7)
					(thickness 0.15)
				)
				(justify left bottom)
			)
		)
		(property "Value" "C_4u7_25V_0402"
			(at -1.022927 2.155213 0)
			(layer "F.Fab")
			(effects
				(font
					(size 0.7 0.7)
					(thickness 0.15)
				)
				(justify left bottom)
			)
		)
		(property "Datasheet" "https://www.murata.com/products/productdetail?partno=GRM155C61E475ME15%23"
			(at 0 0 0)
			(layer "F.Fab")
			(hide yes)
			(effects
				(font
					(size 1.27 1.27)
					(thickness 0.15)
				)
			)
		)
		(property "Description" "SMD Multilayer Ceramic Capacitor"
			(at 0 0 0)
			(layer "F.Fab")
			(hide yes)
			(effects
				(font
					(size 1.27 1.27)
					(thickness 0.15)
				)
			)
		)
		(property "MPN" "GRM155C61E475ME15J"
			(at 0 0 0)
			(unlocked yes)
			(layer "F.Fab")
			(hide yes)
			(effects
				(font
					(size 1 1)
					(thickness 0.15)
				)
			)
		)
		(property "Manufacturer" "Murata"
			(at 0 0 0)
			(unlocked yes)
			(layer "F.Fab")
			(hide yes)
			(effects
				(font
					(size 1 1)
					(thickness 0.15)
				)
			)
		)
		(property "License" "Apache-2.0"
			(at 0 0 0)
			(unlocked yes)
			(layer "F.Fab")
			(hide yes)
			(effects
				(font
					(size 1 1)
					(thickness 0.15)
				)
			)
		)
		(property "Author" "Antmicro"
			(at 0 0 0)
			(unlocked yes)
			(layer "F.Fab")
			(hide yes)
			(effects
				(font
					(size 1 1)
					(thickness 0.15)
				)
			)
		)
		(property "Val" "4u7"
			(at 0 0 0)
			(unlocked yes)
			(layer "F.Fab")
			(hide yes)
			(effects
				(font
					(size 1 1)
					(thickness 0.15)
				)
			)
		)
		(property "Voltage" "25V"
			(at 0 0 0)
			(unlocked yes)
			(layer "F.Fab")
			(hide yes)
			(effects
				(font
					(size 1 1)
					(thickness 0.15)
				)
			)
		)
		(property "Dielectric" "X5S"
			(at 0 0 0)
			(unlocked yes)
			(layer "F.Fab")
			(hide yes)
			(effects
				(font
					(size 1 1)
					(thickness 0.15)
				)
			)
		)
		(sheetname "/USB-C connector/")
		(sheetfile "USB-C_connector.kicad_sch")
		(attr smd)
		(fp_rect
			(start -0.925 -0.47)
			(end 0.925 0.47)
			(stroke
				(width 0.05)
				(type default)
			)
			(fill no)
			(layer "F.CrtYd")
		)
		(fp_line
			(start -0.494 -0.25)
			(end 0.504 -0.25)
			(stroke
				(width 0.15)
				(type solid)
			)
			(layer "F.Fab")
		)
		(fp_line
			(start -0.494 0.248)
			(end -0.494 -0.25)
			(stroke
				(width 0.15)
				(type solid)
			)
			(layer "F.Fab")
		)
		(fp_line
			(start 0.504 -0.25)
			(end 0.504 0.248)
			(stroke
				(width 0.15)
				(type solid)
			)
			(layer "F.Fab")
		)
		(fp_line
			(start 0.504 0.248)
			(end -0.494 0.248)
			(stroke
				(width 0.15)
				(type solid)
			)
			(layer "F.Fab")
		)
		(fp_text user "${REFERENCE}"
			(at -0.939 4.599 0)
			(layer "F.Fab")
			(effects
				(font
					(size 0.7 0.7)
					(thickness 0.15)
				)
				(justify left bottom)
			)
		)
		(fp_text user "License: Apache-2.0"
			(at -0.939 5.799 0)
			(layer "F.Fab")
			(effects
				(font
					(size 0.7 0.7)
					(thickness 0.15)
				)
				(justify left bottom)
			)
		)
		(fp_text user "Author: Antmicro"
			(at -0.939 3.399 0)
			(layer "F.Fab")
			(effects
				(font
					(size 0.7 0.7)
					(thickness 0.15)
				)
				(justify left bottom)
			)
		)
		(pad "1" smd roundrect
			(at -0.48 0)
			(size 0.59 0.64)
			(layers "F.Cu" "F.Mask" "F.Paste")
			(roundrect_rratio 0.25)
			(net 23 "GND")
			(pintype "passive")
		)
		(pad "2" smd roundrect
			(at 0.48 0)
			(size 0.59 0.64)
			(layers "F.Cu" "F.Mask" "F.Paste")
			(roundrect_rratio 0.25)
			(net 53 "+5V_USB")
			(pintype "passive")
		)
	)
	(footprint "antmicro-footprints:SOT-753"
		(layer "F.Cu")
		(at 137.355 85.174999)
		(property "Reference" "U15"
			(at -0.555 -1.974999 0)
			(layer "F.SilkS")
			(effects
				(font
					(size 0.7 0.7)
					(thickness 0.15)
				)
				(justify left bottom)
			)
		)
		(property "Value" "74LVC1G07_SOT-753"
			(at 0 2.9 0)
			(layer "F.Fab")
			(effects
				(font
					(size 0.7 0.7)
					(thickness 0.15)
				)
				(justify left bottom)
			)
		)
		(property "Datasheet" "https://www.mouser.com/datasheet/2/916/74LVC1G07-1529858.pdf"
			(at 0 0 0)
			(layer "F.Fab")
			(hide yes)
			(effects
				(font
					(size 1.27 1.27)
					(thickness 0.15)
				)
			)
		)
		(property "Description" "Buffer, 74LVC1G07, 1.65 V to 5.5 V, SC-74A-5"
			(at 0 0 0)
			(layer "F.Fab")
			(hide yes)
			(effects
				(font
					(size 1.27 1.27)
					(thickness 0.15)
				)
			)
		)
		(property "MPN" "74LVC1G07GV,125"
			(at 0 0 0)
			(unlocked yes)
			(layer "F.Fab")
			(hide yes)
			(effects
				(font
					(size 1 1)
					(thickness 0.15)
				)
			)
		)
		(property "Manufacturer" "Nexperia"
			(at 0 0 0)
			(unlocked yes)
			(layer "F.Fab")
			(hide yes)
			(effects
				(font
					(size 1 1)
					(thickness 0.15)
				)
			)
		)
		(property "Author" "Antmicro"
			(at 0 0 0)
			(unlocked yes)
			(layer "F.Fab")
			(hide yes)
			(effects
				(font
					(size 1 1)
					(thickness 0.15)
				)
			)
		)
		(property "License" "Apache-2.0"
			(at 0 0 0)
			(unlocked yes)
			(layer "F.Fab")
			(hide yes)
			(effects
				(font
					(size 1 1)
					(thickness 0.15)
				)
			)
		)
		(sheetname "/X710-AT2 Misc/")
		(sheetfile "x710-at2-mics.kicad_sch")
		(attr smd)
		(fp_line
			(start -1.651 -1)
			(end -1.651 -0.701)
			(stroke
				(width 0.15)
				(type solid)
			)
			(layer "F.SilkS")
		)
		(fp_line
			(start -1.648 1)
			(end -1.648 0.677)
			(stroke
				(width 0.15)
				(type solid)
			)
			(layer "F.SilkS")
		)
		(fp_line
			(start -1.5 -1)
			(end -1.651 -1)
			(stroke
				(width 0.15)
				(type solid)
			)
			(layer "F.SilkS")
		)
		(fp_line
			(start -1.5 1)
			(end -1.648 1)
			(stroke
				(width 0.15)
				(type solid)
			)
			(layer "F.SilkS")
		)
		(fp_line
			(start 1.5 -1)
			(end 1.648 -1)
			(stroke
				(width 0.15)
				(type solid)
			)
			(layer "F.SilkS")
		)
		(fp_line
			(start 1.5 0.998)
			(end 1.648 0.998)
			(stroke
				(width 0.15)
				(type solid)
			)
			(layer "F.SilkS")
		)
		(fp_line
			(start 1.648 -1)
			(end 1.648 -0.677)
			(stroke
				(width 0.15)
				(type solid)
			)
			(layer "F.SilkS")
		)
		(fp_line
			(start 1.648 0.998)
			(end 1.648 0.699)
			(stroke
				(width 0.15)
				(type solid)
			)
			(layer "F.SilkS")
		)
		(fp_circle
			(center -1.5 1.35)
			(end -1.46 1.4)
			(stroke
				(width 0.15)
				(type solid)
			)
			(fill yes)
			(layer "F.SilkS")
		)
		(fp_rect
			(start -1.7 -1.901)
			(end 1.699 1.898)
			(stroke
				(width 0.05)
				(type solid)
			)
			(fill no)
			(layer "F.CrtYd")
		)
		(fp_line
			(start -1.526 -0.875)
			(end 1.523 -0.875)
			(stroke
				(width 0.15)
				(type solid)
			)
			(layer "F.Fab")
		)
		(fp_line
			(start -1.526 0.623)
			(end -1.526 -0.875)
			(stroke
				(width 0.15)
				(type solid)
			)
			(layer "F.Fab")
		)
		(fp_line
			(start -1.526 0.623)
			(end -1.351 0.873)
			(stroke
				(width 0.15)
				(type solid)
			)
			(layer "F.Fab")
		)
		(fp_line
			(start -1.351 0.873)
			(end 1.523 0.873)
			(stroke
				(width 0.15)
				(type solid)
			)
			(layer "F.Fab")
		)
		(fp_line
			(start 1.523 -0.875)
			(end 1.523 0.873)
			(stroke
				(width 0.15)
				(type solid)
			)
			(layer "F.Fab")
		)
		(fp_text user "Author: Antmicro"
			(at -1.651 7.225 0)
			(layer "F.Fab")
			(effects
				(font
					(size 0.7 0.7)
					(thickness 0.15)
				)
				(justify left bottom)
			)
		)
		(fp_text user "License: Apache-2.0"
			(at -1.651 8.425 0)
			(layer "F.Fab")
			(effects
				(font
					(size 0.7 0.7)
					(thickness 0.15)
				)
				(justify left bottom)
			)
		)
		(fp_text user "${REFERENCE}"
			(at -1.651 6.025 0)
			(layer "F.Fab")
			(effects
				(font
					(size 0.7 0.7)
					(thickness 0.15)
				)
				(justify left bottom)
			)
		)
		(pad "1" smd roundrect
			(at -0.951 1.35)
			(size 0.6 1.05)
			(layers "F.Cu" "F.Mask" "F.Paste")
			(roundrect_rratio 0.25)
			(net 588 "unconnected-(U15-NC-Pad1)")
			(pinfunction "NC")
			(pintype "no_connect")
		)
		(pad "2" smd roundrect
			(at 0 1.35)
			(size 0.6 1.05)
			(layers "F.Cu" "F.Mask" "F.Paste")
			(roundrect_rratio 0.25)
			(net 437 "Net-(U15-A)")
			(pinfunction "A")
			(pintype "input")
		)
		(pad "3" smd roundrect
			(at 0.949 1.35)
			(size 0.6 1.05)
			(layers "F.Cu" "F.Mask" "F.Paste")
			(roundrect_rratio 0.25)
			(net 23 "GND")
			(pinfunction "GND")
			(pintype "power_in")
		)
		(pad "4" smd roundrect
			(at 0.949 -1.351)
			(size 0.6 1.05)
			(layers "F.Cu" "F.Mask" "F.Paste")
			(roundrect_rratio 0.25)
			(net 74 "/X710-AT2 Misc/LAN_PWR_GOOD")
			(pinfunction "Y")
			(pintype "output")
		)
		(pad "5" smd roundrect
			(at -0.951 -1.351)
			(size 0.6 1.05)
			(layers "F.Cu" "F.Mask" "F.Paste")
			(roundrect_rratio 0.25)
			(net 7 "+3V3")
			(pinfunction "VCC")
			(pintype "power_in")
		)
	)
	(footprint "antmicro-footprints:R_0402_1005Metric"
		(layer "F.Cu")
		(at 130.4 145.5)
		(descr "Resistor SMD 0402")
		(tags "resistor SMD 0402")
		(property "Reference" "R237"
			(at 1 0.5 0)
			(layer "F.SilkS")
			(effects
				(font
					(size 0.7 0.7)
					(thickness 0.15)
				)
				(justify left bottom)
			)
		)
		(property "Value" "R_470R_0402"
			(at -1.011843 1.772047 0)
			(layer "F.Fab")
			(effects
				(font
					(size 0.7 0.7)
					(thickness 0.15)
				)
				(justify left bottom)
			)
		)
		(property "Datasheet" "https://www.bourns.com/docs/product-datasheets/cr.pdf"
			(at 0 0 0)
			(layer "F.Fab")
			(hide yes)
			(effects
				(font
					(size 1.27 1.27)
					(thickness 0.15)
				)
			)
		)
		(property "Description" "SMD Chip Resistor, 470 ohm, ± 1%, 62.5 mW, 0402 [1005 Metric], Thick Film, General Purpose"
			(at 0 0 0)
			(layer "F.Fab")
			(hide yes)
			(effects
				(font
					(size 1.27 1.27)
					(thickness 0.15)
				)
			)
		)
		(property "MPN" "CR0402-FX-4700GLF"
			(at 0 0 0)
			(unlocked yes)
			(layer "F.Fab")
			(hide yes)
			(effects
				(font
					(size 1 1)
					(thickness 0.15)
				)
			)
		)
		(property "Manufacturer" "Bourns"
			(at 0 0 0)
			(unlocked yes)
			(layer "F.Fab")
			(hide yes)
			(effects
				(font
					(size 1 1)
					(thickness 0.15)
				)
			)
		)
		(property "License" "Apache-2.0"
			(at 0 0 0)
			(unlocked yes)
			(layer "F.Fab")
			(hide yes)
			(effects
				(font
					(size 1 1)
					(thickness 0.15)
				)
			)
		)
		(property "Author" "Antmicro"
			(at 0 0 0)
			(unlocked yes)
			(layer "F.Fab")
			(hide yes)
			(effects
				(font
					(size 1 1)
					(thickness 0.15)
				)
			)
		)
		(property "Val" "470R"
			(at 0 0 0)
			(unlocked yes)
			(layer "F.Fab")
			(hide yes)
			(effects
				(font
					(size 1 1)
					(thickness 0.15)
				)
			)
		)
		(property "Tolerance" "1%"
			(at 0 0 0)
			(unlocked yes)
			(layer "F.Fab")
			(hide yes)
			(effects
				(font
					(size 1 1)
					(thickness 0.15)
				)
			)
		)
		(sheetname "/Power input/")
		(sheetfile "power_input.kicad_sch")
		(attr smd)
		(fp_rect
			(start -0.925 -0.47)
			(end 0.925 0.47)
			(stroke
				(width 0.05)
				(type default)
			)
			(fill no)
			(layer "F.CrtYd")
		)
		(fp_rect
			(start -0.5 -0.25)
			(end 0.5 0.25)
			(stroke
				(width 0.15)
				(type solid)
			)
			(fill no)
			(layer "F.Fab")
		)
		(fp_text user "${REFERENCE}"
			(at -0.95 3.168 0)
			(layer "F.Fab")
			(effects
				(font
					(size 0.7 0.7)
					(thickness 0.15)
				)
				(justify left bottom)
			)
		)
		(fp_text user "License: Apache-2.0"
			(at -0.95 5.169 0)
			(layer "F.Fab")
			(effects
				(font
					(size 0.7 0.7)
					(thickness 0.15)
				)
				(justify left bottom)
			)
		)
		(fp_text user "Author: Antmicro"
			(at -0.95 4.169 0)
			(layer "F.Fab")
			(effects
				(font
					(size 0.7 0.7)
					(thickness 0.15)
				)
				(justify left bottom)
			)
		)
		(pad "1" smd roundrect
			(at -0.48 0)
			(size 0.59 0.64)
			(layers "F.Cu" "F.Mask" "F.Paste")
			(roundrect_rratio 0.25)
			(net 421 "Net-(D18-A)")
			(pintype "passive")
		)
		(pad "2" smd roundrect
			(at 0.48 0)
			(size 0.59 0.64)
			(layers "F.Cu" "F.Mask" "F.Paste")
			(roundrect_rratio 0.25)
			(net 40 "+5V")
			(pintype "passive")
		)
	)
	(footprint "antmicro-footprints:C_0402_1005Metric"
		(layer "F.Cu")
		(at 161.4 49.5 -90)
		(descr "Capacitor SMD 0402")
		(tags "capacitor SMD 0402")
		(property "Reference" "C315"
			(at 0.9 -1.8 270)
			(layer "F.SilkS")
			(effects
				(font
					(size 0.7 0.7)
					(thickness 0.15)
				)
				(justify left bottom)
			)
		)
		(property "Value" "C_1u_0402"
			(at -1.022927 2.155213 270)
			(layer "F.Fab")
			(effects
				(font
					(size 0.7 0.7)
					(thickness 0.15)
				)
				(justify left bottom)
			)
		)
		(property "Datasheet" "https://product.tdk.com/en/search/capacitor/ceramic/mlcc/info?part_no=C1005X6S1A105K050BC"
			(at 0 0 270)
			(layer "F.Fab")
			(hide yes)
			(effects
				(font
					(size 1.27 1.27)
					(thickness 0.15)
				)
			)
		)
		(property "Description" "SMD Multilayer Ceramic Capacitor, 1 µF, 10 V, 0402 [1005 Metric], ± 10%, X6S, C"
			(at 0 0 270)
			(layer "F.Fab")
			(hide yes)
			(effects
				(font
					(size 1.27 1.27)
					(thickness 0.15)
				)
			)
		)
		(property "Manufacturer" "TDK"
			(at 0 0 270)
			(unlocked yes)
			(layer "F.Fab")
			(hide yes)
			(effects
				(font
					(size 1 1)
					(thickness 0.15)
				)
			)
		)
		(property "MPN" "C1005X6S1A105K050BC"
			(at 0 0 270)
			(unlocked yes)
			(layer "F.Fab")
			(hide yes)
			(effects
				(font
					(size 1 1)
					(thickness 0.15)
				)
			)
		)
		(property "Val" "1u"
			(at 0 0 270)
			(unlocked yes)
			(layer "F.Fab")
			(hide yes)
			(effects
				(font
					(size 1 1)
					(thickness 0.15)
				)
			)
		)
		(property "License" "Apache-2.0"
			(at 0 0 270)
			(unlocked yes)
			(layer "F.Fab")
			(hide yes)
			(effects
				(font
					(size 1 1)
					(thickness 0.15)
				)
			)
		)
		(property "Author" "Antmicro"
			(at 0 0 270)
			(unlocked yes)
			(layer "F.Fab")
			(hide yes)
			(effects
				(font
					(size 1 1)
					(thickness 0.15)
				)
			)
		)
		(property "Voltage" ""
			(at 0 0 270)
			(unlocked yes)
			(layer "F.Fab")
			(hide yes)
			(effects
				(font
					(size 1 1)
					(thickness 0.15)
				)
			)
		)
		(property "Dielectric" ""
			(at 0 0 270)
			(unlocked yes)
			(layer "F.Fab")
			(hide yes)
			(effects
				(font
					(size 1 1)
					(thickness 0.15)
				)
			)
		)
		(sheetname "/Power input/")
		(sheetfile "power_input.kicad_sch")
		(attr smd)
		(fp_rect
			(start -0.925 -0.47)
			(end 0.925 0.47)
			(stroke
				(width 0.05)
				(type default)
			)
			(fill no)
			(layer "F.CrtYd")
		)
		(fp_line
			(start -0.494 0.248)
			(end -0.494 -0.25)
			(stroke
				(width 0.15)
				(type solid)
			)
			(layer "F.Fab")
		)
		(fp_line
			(start 0.504 0.248)
			(end -0.494 0.248)
			(stroke
				(width 0.15)
				(type solid)
			)
			(layer "F.Fab")
		)
		(fp_line
			(start -0.494 -0.25)
			(end 0.504 -0.25)
			(stroke
				(width 0.15)
				(type solid)
			)
			(layer "F.Fab")
		)
		(fp_line
			(start 0.504 -0.25)
			(end 0.504 0.248)
			(stroke
				(width 0.15)
				(type solid)
			)
			(layer "F.Fab")
		)
		(fp_text user "${REFERENCE}"
			(at -0.939 4.599 270)
			(layer "F.Fab")
			(effects
				(font
					(size 0.7 0.7)
					(thickness 0.15)
				)
				(justify left bottom)
			)
		)
		(fp_text user "License: Apache-2.0"
			(at -0.939 5.799 270)
			(layer "F.Fab")
			(effects
				(font
					(size 0.7 0.7)
					(thickness 0.15)
				)
				(justify left bottom)
			)
		)
		(fp_text user "Author: Antmicro"
			(at -0.939 3.399 270)
			(layer "F.Fab")
			(effects
				(font
					(size 0.7 0.7)
					(thickness 0.15)
				)
				(justify left bottom)
			)
		)
		(pad "1" smd roundrect
			(at -0.48 0 270)
			(size 0.59 0.64)
			(layers "F.Cu" "F.Mask" "F.Paste")
			(roundrect_rratio 0.25)
			(net 23 "GND")
			(pintype "passive")
		)
		(pad "2" smd roundrect
			(at 0.48 0 270)
			(size 0.59 0.64)
			(layers "F.Cu" "F.Mask" "F.Paste")
			(roundrect_rratio 0.25)
			(net 345 "/Power input/5V_VDD")
			(pintype "passive")
		)
	)
	(footprint "antmicro-footprints:L_Bourns-SRP4021HMT"
		(layer "F.Cu")
		(at 139.45 106.000001 -90)
		(property "Reference" "L5"
			(at 17.549996 -16 270)
			(layer "F.SilkS")
			(effects
				(font
					(size 0.7 0.7)
					(thickness 0.15)
				)
			)
		)
		(property "Value" "L_1u_10A_Bourns-SRP4021HMT"
			(at -2.85 3.4 270)
			(layer "F.Fab")
			(effects
				(font
					(size 0.7 0.7)
					(thickness 0.15)
				)
				(justify left bottom)
			)
		)
		(property "Datasheet" "https://www.mouser.com/datasheet/2/54/Bourns_04_01_2025_SRP4021HMT_Datasheet-3580094.pdf"
			(at 0 0 270)
			(layer "F.Fab")
			(effects
				(font
					(size 0.7 0.7)
					(thickness 0.15)
				)
				(justify left bottom)
			)
		)
		(property "Description" "Power Inductors - SMD Ind,4.1x4.2x1.9mm,1uH+/-20%,10A, Shielded"
			(at 0 0 270)
			(layer "F.Fab")
			(effects
				(font
					(size 0.7 0.7)
					(thickness 0.15)
				)
				(justify left bottom)
			)
		)
		(property "Val" "1u/10A"
			(at 0 0 270)
			(unlocked yes)
			(layer "F.Fab")
			(hide yes)
			(effects
				(font
					(size 1 1)
					(thickness 0.15)
				)
			)
		)
		(property "Manufacturer" "Bourns"
			(at 0 0 270)
			(unlocked yes)
			(layer "F.Fab")
			(hide yes)
			(effects
				(font
					(size 1 1)
					(thickness 0.15)
				)
			)
		)
		(property "MPN" "SRP4021HMT-1R0M"
			(at 0 0 270)
			(unlocked yes)
			(layer "F.Fab")
			(hide yes)
			(effects
				(font
					(size 1 1)
					(thickness 0.15)
				)
			)
		)
		(property "ISat" ""
			(at 0 0 270)
			(unlocked yes)
			(layer "F.Fab")
			(hide yes)
			(effects
				(font
					(size 1 1)
					(thickness 0.15)
				)
			)
		)
		(property "Isat" "8A"
			(at 0 0 270)
			(unlocked yes)
			(layer "F.Fab")
			(hide yes)
			(effects
				(font
					(size 1 1)
					(thickness 0.15)
				)
			)
		)
		(property "IMax" ""
			(at 0 0 270)
			(unlocked yes)
			(layer "F.Fab")
			(hide yes)
			(effects
				(font
					(size 1 1)
					(thickness 0.15)
				)
			)
		)
		(property "Imax" "10A"
			(at 0 0 270)
			(unlocked yes)
			(layer "F.Fab")
			(hide yes)
			(effects
				(font
					(size 1 1)
					(thickness 0.15)
				)
			)
		)
		(property "Size" "4.2x4.1"
			(at 0 0 270)
			(unlocked yes)
			(layer "F.Fab")
			(hide yes)
			(effects
				(font
					(size 1 1)
					(thickness 0.15)
				)
			)
		)
		(property "Author" "Antmicro"
			(at 0 0 270)
			(unlocked yes)
			(layer "F.Fab")
			(hide yes)
			(effects
				(font
					(size 1 1)
					(thickness 0.15)
				)
			)
		)
		(property "License" "Apache-2.0"
			(at 0 0 270)
			(unlocked yes)
			(layer "F.Fab")
			(hide yes)
			(effects
				(font
					(size 1 1)
					(thickness 0.15)
				)
			)
		)
		(sheetname "/X710 DCDC converters/")
		(sheetfile "DCDC_converters_X710.kicad_sch")
		(attr smd)
		(fp_line
			(start -0.8 2.05)
			(end 0.8 2.05)
			(stroke
				(width 0.15)
				(type solid)
			)
			(layer "F.SilkS")
		)
		(fp_line
			(start -0.8 -2.05)
			(end 0.8 -2.05)
			(stroke
				(width 0.15)
				(type solid)
			)
			(layer "F.SilkS")
		)
		(fp_rect
			(start -2.85 -2.3)
			(end 2.85 2.3)
			(stroke
				(width 0.05)
				(type solid)
			)
			(fill no)
			(layer "F.CrtYd")
		)
		(fp_rect
			(start -2 -2.05)
			(end 2 2.05)
			(stroke
				(width 0.15)
				(type solid)
			)
			(fill no)
			(layer "F.Fab")
		)
		(fp_text user "License: Apache-2.0"
			(at -2.85 7 270)
			(layer "F.Fab")
			(effects
				(font
					(size 0.7 0.7)
					(thickness 0.15)
				)
				(justify left bottom)
			)
		)
		(fp_text user "${REFERENCE}"
			(at -2.85 5.8 270)
			(layer "F.Fab")
			(effects
				(font
					(size 0.7 0.7)
					(thickness 0.15)
				)
				(justify left bottom)
			)
		)
		(fp_text user "Author: Antmicro"
			(at -2.85 4.6 270)
			(layer "F.Fab")
			(effects
				(font
					(size 0.7 0.7)
					(thickness 0.15)
				)
				(justify left bottom)
			)
		)
		(pad "1" smd rect
			(at 1.85 0 90)
			(size 1.5 3.5)
			(layers "F.Cu" "F.Mask" "F.Paste")
			(net 153 "/X710 DCDC converters/VCCD_SW")
			(pintype "passive")
		)
		(pad "2" smd rect
			(at -1.85 0 90)
			(size 1.5 3.5)
			(layers "F.Cu" "F.Mask" "F.Paste")
			(net 335 "/X710 DCDC converters/+VCCD_OUT")
			(pintype "passive")
		)
	)
	(footprint "antmicro-footprints:FB_0805_2012Metric"
		(layer "F.Cu")
		(at 122.65 108.9 -90)
		(descr "FERRITE BEAD 0805")
		(tags "FERRITE BEAD 0805")
		(property "Reference" "FB2"
			(at 5.7 -5.35 270)
			(layer "F.SilkS")
			(effects
				(font
					(size 0.7 0.7)
					(thickness 0.15)
				)
			)
		)
		(property "Value" "FB_30Z_8.5A_Murata-BLM21SN_0805"
			(at 0.001 1.801 270)
			(layer "F.Fab")
			(effects
				(font
					(size 0.7 0.7)
					(thickness 0.15)
				)
				(justify left bottom)
			)
		)
		(property "Datasheet" "https://www.murata.com/en-sg/products/productdata/8796738977822/ENFA0005.pdf?1519270210000"
			(at 0 0 270)
			(layer "F.Fab")
			(hide yes)
			(effects
				(font
					(size 1.27 1.27)
					(thickness 0.15)
				)
			)
		)
		(property "Description" "Ferrite Bead, 0805 [2012 Metric], 30 ohm, 8.5 A, BLM21SN, 0.004 ohm, ± 10ohm, DC power line"
			(at 0 0 270)
			(layer "F.Fab")
			(hide yes)
			(effects
				(font
					(size 1.27 1.27)
					(thickness 0.15)
				)
			)
		)
		(property "MPN" "BLM21SN300SZ1D"
			(at 0 0 270)
			(unlocked yes)
			(layer "F.Fab")
			(hide yes)
			(effects
				(font
					(size 1 1)
					(thickness 0.15)
				)
			)
		)
		(property "Manufacturer" "Murata"
			(at 0 0 270)
			(unlocked yes)
			(layer "F.Fab")
			(hide yes)
			(effects
				(font
					(size 1 1)
					(thickness 0.15)
				)
			)
		)
		(property "License" "Apache-2.0"
			(at 0 0 270)
			(unlocked yes)
			(layer "F.Fab")
			(hide yes)
			(effects
				(font
					(size 1 1)
					(thickness 0.15)
				)
			)
		)
		(property "Author" "Antmicro"
			(at 0 0 270)
			(unlocked yes)
			(layer "F.Fab")
			(hide yes)
			(effects
				(font
					(size 1 1)
					(thickness 0.15)
				)
			)
		)
		(property "Val" "30Z/8.5A"
			(at 0 0 270)
			(unlocked yes)
			(layer "F.Fab")
			(hide yes)
			(effects
				(font
					(size 1 1)
					(thickness 0.15)
				)
			)
		)
		(property "Current" ""
			(at 0 0 270)
			(unlocked yes)
			(layer "F.Fab")
			(hide yes)
			(effects
				(font
					(size 1 1)
					(thickness 0.15)
				)
			)
		)
		(sheetname "/PD and TB DC-DC/")
		(sheetfile "PD_and_TB_DC_DC.kicad_sch")
		(attr smd)
		(fp_line
			(start -0.319 0.698)
			(end 0.281 0.698)
			(stroke
				(width 0.15)
				(type solid)
			)
			(layer "F.SilkS")
		)
		(fp_line
			(start -0.299 -0.698)
			(end 0.299 -0.698)
			(stroke
				(width 0.15)
				(type solid)
			)
			(layer "F.SilkS")
		)
		(fp_rect
			(start 1.95 -0.9)
			(end -1.95 0.9)
			(stroke
				(width 0.05)
				(type default)
			)
			(fill no)
			(layer "F.CrtYd")
		)
		(fp_line
			(start -0.948 0.681)
			(end 0.948 0.681)
			(stroke
				(width 0.15)
				(type solid)
			)
			(layer "F.Fab")
		)
		(fp_line
			(start -0.948 -0.676)
			(end -0.948 0.676)
			(stroke
				(width 0.15)
				(type solid)
			)
			(layer "F.Fab")
		)
		(fp_line
			(start 0.948 -0.676)
			(end 0.948 0.676)
			(stroke
				(width 0.15)
				(type solid)
			)
			(layer "F.Fab")
		)
		(fp_line
			(start -0.948 -0.681)
			(end 0.948 -0.681)
			(stroke
				(width 0.15)
				(type solid)
			)
			(layer "F.Fab")
		)
		(fp_text user "License: Apache-2.0"
			(at -1.44 6.201 270)
			(layer "F.Fab")
			(effects
				(font
					(size 0.7 0.7)
					(thickness 0.15)
				)
				(justify left bottom)
			)
		)
		(fp_text user "${REFERENCE}"
			(at -1.44 3.801 270)
			(layer "F.Fab")
			(effects
				(font
					(size 0.7 0.7)
					(thickness 0.15)
				)
				(justify left bottom)
			)
		)
		(fp_text user "Author: Antmicro"
			(at -1.44 5.001 270)
			(layer "F.Fab")
			(effects
				(font
					(size 0.7 0.7)
					(thickness 0.15)
				)
				(justify left bottom)
			)
		)
		(pad "1" smd roundrect
			(at -1.1 0 270)
			(size 1.2 1.3)
			(layers "F.Cu" "F.Mask" "F.Paste")
			(roundrect_rratio 0.25)
			(net 399 "Net-(D4-A)")
			(pintype "passive")
		)
		(pad "2" smd roundrect
			(at 1.1 0 270)
			(size 1.2 1.3)
			(layers "F.Cu" "F.Mask" "F.Paste")
			(roundrect_rratio 0.25)
			(net 57 "+3V3_TB")
			(pintype "passive")
		)
	)
	(footprint "antmicro-footprints:R_0402_1005Metric"
		(layer "F.Cu")
		(at 159.249997 110.149999 180)
		(descr "Resistor SMD 0402")
		(tags "resistor SMD 0402")
		(property "Reference" "R104"
			(at -12.950004 -17.25 180)
			(layer "F.SilkS")
			(effects
				(font
					(size 0.7 0.7)
					(thickness 0.15)
				)
			)
		)
		(property "Value" "R_20k_0402"
			(at -1.011843 1.772047 180)
			(layer "F.Fab")
			(effects
				(font
					(size 0.7 0.7)
					(thickness 0.15)
				)
				(justify left bottom)
			)
		)
		(property "Datasheet" "https://www.bourns.com/docs/product-datasheets/cr.pdf"
			(at 0 0 180)
			(layer "F.Fab")
			(hide yes)
			(effects
				(font
					(size 1.27 1.27)
					(thickness 0.15)
				)
			)
		)
		(property "Description" "SMD Chip Resistor, 20 kohm, ± 1%, 62.5 mW, 0402 [1005 Metric], Thick Film, General Purpose"
			(at 0 0 180)
			(layer "F.Fab")
			(hide yes)
			(effects
				(font
					(size 1.27 1.27)
					(thickness 0.15)
				)
			)
		)
		(property "MPN" "CR0402-FX-2002GLF"
			(at 0 0 180)
			(unlocked yes)
			(layer "F.Fab")
			(hide yes)
			(effects
				(font
					(size 1 1)
					(thickness 0.15)
				)
			)
		)
		(property "Manufacturer" "Bourns"
			(at 0 0 180)
			(unlocked yes)
			(layer "F.Fab")
			(hide yes)
			(effects
				(font
					(size 1 1)
					(thickness 0.15)
				)
			)
		)
		(property "License" "Apache-2.0"
			(at 0 0 180)
			(unlocked yes)
			(layer "F.Fab")
			(hide yes)
			(effects
				(font
					(size 1 1)
					(thickness 0.15)
				)
			)
		)
		(property "Author" "Antmicro"
			(at 0 0 180)
			(unlocked yes)
			(layer "F.Fab")
			(hide yes)
			(effects
				(font
					(size 1 1)
					(thickness 0.15)
				)
			)
		)
		(property "Val" "20k"
			(at 0 0 180)
			(unlocked yes)
			(layer "F.Fab")
			(hide yes)
			(effects
				(font
					(size 1 1)
					(thickness 0.15)
				)
			)
		)
		(property "Tolerance" "1%"
			(at 0 0 180)
			(unlocked yes)
			(layer "F.Fab")
			(hide yes)
			(effects
				(font
					(size 1 1)
					(thickness 0.15)
				)
			)
		)
		(sheetname "/X710 DCDC converters/")
		(sheetfile "DCDC_converters_X710.kicad_sch")
		(attr smd)
		(fp_rect
			(start -0.925 -0.47)
			(end 0.925 0.47)
			(stroke
				(width 0.05)
				(type default)
			)
			(fill no)
			(layer "F.CrtYd")
		)
		(fp_rect
			(start -0.5 -0.25)
			(end 0.5 0.25)
			(stroke
				(width 0.15)
				(type solid)
			)
			(fill no)
			(layer "F.Fab")
		)
		(fp_text user "${REFERENCE}"
			(at -0.95 3.168 180)
			(layer "F.Fab")
			(effects
				(font
					(size 0.7 0.7)
					(thickness 0.15)
				)
				(justify left bottom)
			)
		)
		(fp_text user "Author: Antmicro"
			(at -0.95 4.169 180)
			(layer "F.Fab")
			(effects
				(font
					(size 0.7 0.7)
					(thickness 0.15)
				)
				(justify left bottom)
			)
		)
		(fp_text user "License: Apache-2.0"
			(at -0.95 5.169 180)
			(layer "F.Fab")
			(effects
				(font
					(size 0.7 0.7)
					(thickness 0.15)
				)
				(justify left bottom)
			)
		)
		(pad "1" smd roundrect
			(at -0.48 0 180)
			(size 0.59 0.64)
			(layers "F.Cu" "F.Mask" "F.Paste")
			(roundrect_rratio 0.25)
			(net 340 "/X710 DCDC converters/1V0_FB")
			(pintype "passive")
		)
		(pad "2" smd roundrect
			(at 0.48 0 180)
			(size 0.59 0.64)
			(layers "F.Cu" "F.Mask" "F.Paste")
			(roundrect_rratio 0.25)
			(net 339 "/X710 DCDC converters/+1V0_OUT")
			(pintype "passive")
		)
	)
	(footprint "antmicro-footprints:C_0603_1608Metric_EIA"
		(layer "F.Cu")
		(at 150.500001 105.600001 90)
		(descr "Capacitor SMD 0603, IPC-7351 Density Level A")
		(tags "Capacitor 0603")
		(property "Reference" "C136"
			(at -17.849995 14.449998 90)
			(layer "F.SilkS")
			(effects
				(font
					(size 0.7 0.7)
					(thickness 0.15)
				)
			)
		)
		(property "Value" "C_22u_16V_0603"
			(at -1.42757 1.770288 90)
			(layer "F.Fab")
			(effects
				(font
					(size 0.7 0.7)
					(thickness 0.15)
				)
				(justify left bottom)
			)
		)
		(property "Datasheet" "https://product.samsungsem.com/mlcc/CL10A226MO7JZN.do"
			(at 0 0 90)
			(layer "F.Fab")
			(hide yes)
			(effects
				(font
					(size 1.27 1.27)
					(thickness 0.15)
				)
			)
		)
		(property "Description" "SMD Multilayer Ceramic Capacitor"
			(at 0 0 90)
			(layer "F.Fab")
			(hide yes)
			(effects
				(font
					(size 1.27 1.27)
					(thickness 0.15)
				)
			)
		)
		(property "MPN" "CL10A226MO7JZNC"
			(at 0 0 90)
			(unlocked yes)
			(layer "F.Fab")
			(hide yes)
			(effects
				(font
					(size 1 1)
					(thickness 0.15)
				)
			)
		)
		(property "Manufacturer" "Samsung Electro-Mechanics"
			(at 0 0 90)
			(unlocked yes)
			(layer "F.Fab")
			(hide yes)
			(effects
				(font
					(size 1 1)
					(thickness 0.15)
				)
			)
		)
		(property "License" "Apache-2.0"
			(at 0 0 90)
			(unlocked yes)
			(layer "F.Fab")
			(hide yes)
			(effects
				(font
					(size 1 1)
					(thickness 0.15)
				)
			)
		)
		(property "Author" "Antmicro"
			(at 0 0 90)
			(unlocked yes)
			(layer "F.Fab")
			(hide yes)
			(effects
				(font
					(size 1 1)
					(thickness 0.15)
				)
			)
		)
		(property "Val" "22u"
			(at 0 0 90)
			(unlocked yes)
			(layer "F.Fab")
			(hide yes)
			(effects
				(font
					(size 1 1)
					(thickness 0.15)
				)
			)
		)
		(property "Voltage" "16V"
			(at 0 0 90)
			(unlocked yes)
			(layer "F.Fab")
			(hide yes)
			(effects
				(font
					(size 1 1)
					(thickness 0.15)
				)
			)
		)
		(property "Dielectric" ""
			(at 0 0 90)
			(unlocked yes)
			(layer "F.Fab")
			(hide yes)
			(effects
				(font
					(size 1 1)
					(thickness 0.15)
				)
			)
		)
		(sheetname "/X710 DCDC converters/")
		(sheetfile "DCDC_converters_X710.kicad_sch")
		(attr smd)
		(fp_line
			(start -0.15 -0.55)
			(end 0.15 -0.55)
			(stroke
				(width 0.15)
				(type solid)
			)
			(layer "F.SilkS")
		)
		(fp_line
			(start -0.15 0.55)
			(end 0.15 0.55)
			(stroke
				(width 0.15)
				(type solid)
			)
			(layer "F.SilkS")
		)
		(fp_rect
			(start -1.25 -0.65)
			(end 1.25 0.65)
			(stroke
				(width 0.05)
				(type solid)
			)
			(fill no)
			(layer "F.CrtYd")
		)
		(fp_rect
			(start -0.8 -0.45)
			(end 0.8 0.45)
			(stroke
				(width 0.15)
				(type solid)
			)
			(fill no)
			(layer "F.Fab")
		)
		(fp_text user "Author: Antmicro"
			(at -1.682 4.894 90)
			(layer "F.Fab")
			(effects
				(font
					(size 0.7 0.7)
					(thickness 0.15)
				)
				(justify left bottom)
			)
		)
		(fp_text user "${REFERENCE}"
			(at -1.682 3.895 90)
			(layer "F.Fab")
			(effects
				(font
					(size 0.7 0.7)
					(thickness 0.15)
				)
				(justify left bottom)
			)
		)
		(fp_text user "License: Apache-2.0"
			(at -1.682 5.895 90)
			(layer "F.Fab")
			(effects
				(font
					(size 0.7 0.7)
					(thickness 0.15)
				)
				(justify left bottom)
			)
		)
		(pad "1" smd roundrect
			(at -0.7 0 90)
			(size 0.8 1.1)
			(layers "F.Cu" "F.Mask" "F.Paste")
			(roundrect_rratio 0.2)
			(net 23 "GND")
			(pintype "passive")
		)
		(pad "2" smd roundrect
			(at 0.7 0 90)
			(size 0.8 1.1)
			(layers "F.Cu" "F.Mask" "F.Paste")
			(roundrect_rratio 0.2)
			(net 338 "/X710 DCDC converters/+1V88_OUT")
			(pintype "passive")
		)
	)
	(footprint "antmicro-footprints:Mech_Lightpipe_Mentor_1271.1001"
		(layer "F.Cu")
		(at 130.45 147.813534 180)
		(descr "1x1  Horizontal Light Guide with transparent pipe")
		(tags "Horizontal, THT, MECHANICAL, MODULE")
		(property "Reference" "H4"
			(at 1.7 -3.386466 0)
			(unlocked yes)
			(layer "F.SilkS")
			(effects
				(font
					(size 0.7 0.7)
					(thickness 0.15)
				)
				(justify left bottom)
			)
		)
		(property "Value" "Lightpipe_Mentor_1271.1001"
			(at 0 9 180)
			(unlocked yes)
			(layer "F.Fab")
			(effects
				(font
					(size 0.7 0.7)
					(thickness 0.15)
				)
				(justify left bottom)
			)
		)
		(property "Datasheet" "https://www.mentor.de.com/productpdfs/ll/ll14-20.pdf"
			(at 0 0 180)
			(layer "F.Fab")
			(hide yes)
			(effects
				(font
					(size 1.27 1.27)
					(thickness 0.15)
				)
			)
		)
		(property "Description" "Light Pipe, 14.45 mm, 1 Pipe, Circular, PC Board, Transparent"
			(at 0 0 180)
			(layer "F.Fab")
			(hide yes)
			(effects
				(font
					(size 1.27 1.27)
					(thickness 0.15)
				)
			)
		)
		(property "MPN" "1271.1001"
			(at 0 0 180)
			(unlocked yes)
			(layer "F.Fab")
			(hide yes)
			(effects
				(font
					(size 1 1)
					(thickness 0.15)
				)
			)
		)
		(property "Manufacturer" "Mentor Worldwide"
			(at 0 0 180)
			(unlocked yes)
			(layer "F.Fab")
			(hide yes)
			(effects
				(font
					(size 1 1)
					(thickness 0.15)
				)
			)
		)
		(property "Author" "Antmicro"
			(at 0 0 180)
			(unlocked yes)
			(layer "F.Fab")
			(hide yes)
			(effects
				(font
					(size 1 1)
					(thickness 0.15)
				)
			)
		)
		(property "License" "Apache-2.0"
			(at 0 0 180)
			(unlocked yes)
			(layer "F.Fab")
			(hide yes)
			(effects
				(font
					(size 1 1)
					(thickness 0.15)
				)
			)
		)
		(sheetname "/")
		(sheetfile "thunderbolt-to-10gbe-adapter.kicad_sch")
		(attr through_hole)
		(fp_rect
			(start -1.55 -2.1)
			(end 1.55 1.3)
			(stroke
				(width 0.05)
				(type solid)
			)
			(fill no)
			(layer "F.SilkS")
		)
		(fp_rect
			(start -1.75 -2.3)
			(end 1.75 1.475)
			(stroke
				(width 0.05)
				(type solid)
			)
			(fill no)
			(layer "F.CrtYd")
		)
		(fp_rect
			(start -1.4732 -8.128)
			(end 1.4732 6.2484)
			(stroke
				(width 0.15)
				(type solid)
			)
			(fill no)
			(layer "F.Fab")
		)
		(fp_text user "${REFERENCE}"
			(at -1.8 12.9 180)
			(layer "F.Fab")
			(effects
				(font
					(size 0.7 0.7)
					(thickness 0.15)
				)
				(justify left bottom)
			)
		)
		(fp_text user "Author: Antmicro"
			(at -1.8 10.5 180)
			(layer "F.Fab")
			(effects
				(font
					(size 0.7 0.7)
					(thickness 0.15)
				)
				(justify left bottom)
			)
		)
		(fp_text user "License: Apache-2.0"
			(at -1.8 11.7 180)
			(layer "F.Fab")
			(effects
				(font
					(size 0.7 0.7)
					(thickness 0.15)
				)
				(justify left bottom)
			)
		)
		(pad "" np_thru_hole circle
			(at 0 0 180)
			(size 2.3 2.3)
			(drill 2.3)
			(layers "*.Cu" "*.Mask")
		)
	)
	(footprint "antmicro-footprints:C_0603_1608Metric"
		(layer "F.Cu")
		(at 149.305 95.374999 180)
		(descr "Capacitor SMD 0603")
		(tags "capacitor 0603")
		(property "Reference" "C169"
			(at -23.294999 -19.625001 180)
			(layer "F.SilkS")
			(effects
				(font
					(size 0.7 0.7)
					(thickness 0.15)
				)
			)
		)
		(property "Value" "C_10u_10V_X7R_0603"
			(at -1.42757 1.770288 180)
			(layer "F.Fab")
			(effects
				(font
					(size 0.7 0.7)
					(thickness 0.15)
				)
				(justify left bottom)
			)
		)
		(property "Datasheet" "https://www.murata.com/products/productdetail?partno=GRM188Z71A106KA73%23"
			(at 0 0 180)
			(layer "F.Fab")
			(hide yes)
			(effects
				(font
					(size 1.27 1.27)
					(thickness 0.15)
				)
			)
		)
		(property "Description" "SMD Multilayer Ceramic Capacitor,  10µF, 10V, 0603, ±10%, X7R"
			(at 0 0 180)
			(layer "F.Fab")
			(hide yes)
			(effects
				(font
					(size 1.27 1.27)
					(thickness 0.15)
				)
			)
		)
		(property "MPN" "GRM188Z71A106KA73D"
			(at 0 0 180)
			(unlocked yes)
			(layer "F.Fab")
			(hide yes)
			(effects
				(font
					(size 1 1)
					(thickness 0.15)
				)
			)
		)
		(property "Val" "10u"
			(at 0 0 180)
			(unlocked yes)
			(layer "F.Fab")
			(hide yes)
			(effects
				(font
					(size 1 1)
					(thickness 0.15)
				)
			)
		)
		(property "Voltage" "10V"
			(at 0 0 180)
			(unlocked yes)
			(layer "F.Fab")
			(hide yes)
			(effects
				(font
					(size 1 1)
					(thickness 0.15)
				)
			)
		)
		(property "Dielectric" "X7R"
			(at 0 0 180)
			(unlocked yes)
			(layer "F.Fab")
			(hide yes)
			(effects
				(font
					(size 1 1)
					(thickness 0.15)
				)
			)
		)
		(property "Manufacturer" "Murata"
			(at 0 0 180)
			(unlocked yes)
			(layer "F.Fab")
			(hide yes)
			(effects
				(font
					(size 1 1)
					(thickness 0.15)
				)
			)
		)
		(property "License" "Apache-2.0"
			(at 0 0 180)
			(unlocked yes)
			(layer "F.Fab")
			(hide yes)
			(effects
				(font
					(size 1 1)
					(thickness 0.15)
				)
			)
		)
		(property "Author" "Antmicro"
			(at 0 0 180)
			(unlocked yes)
			(layer "F.Fab")
			(hide yes)
			(effects
				(font
					(size 1 1)
					(thickness 0.15)
				)
			)
		)
		(sheetname "/X710-AT2 power/")
		(sheetfile "x710-at2-power.kicad_sch")
		(attr smd)
		(fp_line
			(start -0.15 0.4)
			(end 0.15 0.4)
			(stroke
				(width 0.15)
				(type solid)
			)
			(layer "F.SilkS")
		)
		(fp_line
			(start -0.15 -0.4)
			(end 0.15 -0.4)
			(stroke
				(width 0.15)
				(type solid)
			)
			(layer "F.SilkS")
		)
		(fp_rect
			(start -1.25 -0.65)
			(end 1.25 0.65)
			(stroke
				(width 0.05)
				(type solid)
			)
			(fill no)
			(layer "F.CrtYd")
		)
		(fp_rect
			(start -0.8 -0.4)
			(end 0.8 0.4)
			(stroke
				(width 0.15)
				(type solid)
			)
			(fill no)
			(layer "F.Fab")
		)
		(fp_text user "${REFERENCE}"
			(at -1.682 3.895 180)
			(layer "F.Fab")
			(effects
				(font
					(size 0.7 0.7)
					(thickness 0.15)
				)
				(justify left bottom)
			)
		)
		(fp_text user "Author: Antmicro"
			(at -1.682 4.894 180)
			(layer "F.Fab")
			(effects
				(font
					(size 0.7 0.7)
					(thickness 0.15)
				)
				(justify left bottom)
			)
		)
		(fp_text user "License: Apache-2.0"
			(at -1.682 5.895 180)
			(layer "F.Fab")
			(effects
				(font
					(size 0.7 0.7)
					(thickness 0.15)
				)
				(justify left bottom)
			)
		)
		(pad "1" smd roundrect
			(at -0.7 0 180)
			(size 0.8 1)
			(layers "F.Cu" "F.Mask" "F.Paste")
			(roundrect_rratio 0.2)
			(net 23 "GND")
			(pintype "passive")
		)
		(pad "2" smd roundrect
			(at 0.7 0 180)
			(size 0.8 1)
			(layers "F.Cu" "F.Mask" "F.Paste")
			(roundrect_rratio 0.2)
			(net 10 "AVDDH")
			(pintype "passive")
		)
	)
	(footprint "antmicro-footprints:R_0402_1005Metric"
		(layer "F.Cu")
		(at 151.550002 108.15 180)
		(descr "Resistor SMD 0402")
		(tags "resistor SMD 0402")
		(property "Reference" "R89"
			(at -14.149998 -17.25 180)
			(layer "F.SilkS")
			(effects
				(font
					(size 0.7 0.7)
					(thickness 0.15)
				)
			)
		)
		(property "Value" "R_100k_0402"
			(at -1.011843 1.772047 180)
			(layer "F.Fab")
			(effects
				(font
					(size 0.7 0.7)
					(thickness 0.15)
				)
				(justify left bottom)
			)
		)
		(property "Datasheet" "https://www.bourns.com/docs/product-datasheets/cr.pdf"
			(at 0 0 180)
			(layer "F.Fab")
			(hide yes)
			(effects
				(font
					(size 1.27 1.27)
					(thickness 0.15)
				)
			)
		)
		(property "Description" "SMD Chip Resistor, 100 kohm, ± 1%, 62.5 mW, 0402 [1005 Metric], Thick Film, General Purpose"
			(at 0 0 180)
			(layer "F.Fab")
			(hide yes)
			(effects
				(font
					(size 1.27 1.27)
					(thickness 0.15)
				)
			)
		)
		(property "MPN" "CR0402-FX-1003GLF"
			(at 0 0 180)
			(unlocked yes)
			(layer "F.Fab")
			(hide yes)
			(effects
				(font
					(size 1 1)
					(thickness 0.15)
				)
			)
		)
		(property "Manufacturer" "Bourns"
			(at 0 0 180)
			(unlocked yes)
			(layer "F.Fab")
			(hide yes)
			(effects
				(font
					(size 1 1)
					(thickness 0.15)
				)
			)
		)
		(property "License" "Apache-2.0"
			(at 0 0 180)
			(unlocked yes)
			(layer "F.Fab")
			(hide yes)
			(effects
				(font
					(size 1 1)
					(thickness 0.15)
				)
			)
		)
		(property "Author" "Antmicro"
			(at 0 0 180)
			(unlocked yes)
			(layer "F.Fab")
			(hide yes)
			(effects
				(font
					(size 1 1)
					(thickness 0.15)
				)
			)
		)
		(property "Val" "100k"
			(at 0 0 180)
			(unlocked yes)
			(layer "F.Fab")
			(hide yes)
			(effects
				(font
					(size 1 1)
					(thickness 0.15)
				)
			)
		)
		(property "Tolerance" "1%"
			(at 0 0 180)
			(unlocked yes)
			(layer "F.Fab")
			(hide yes)
			(effects
				(font
					(size 1 1)
					(thickness 0.15)
				)
			)
		)
		(sheetname "/X710 DCDC converters/")
		(sheetfile "DCDC_converters_X710.kicad_sch")
		(attr smd)
		(fp_rect
			(start -0.925 -0.47)
			(end 0.925 0.47)
			(stroke
				(width 0.05)
				(type default)
			)
			(fill no)
			(layer "F.CrtYd")
		)
		(fp_rect
			(start -0.5 -0.25)
			(end 0.5 0.25)
			(stroke
				(width 0.15)
				(type solid)
			)
			(fill no)
			(layer "F.Fab")
		)
		(fp_text user "License: Apache-2.0"
			(at -0.95 5.169 180)
			(layer "F.Fab")
			(effects
				(font
					(size 0.7 0.7)
					(thickness 0.15)
				)
				(justify left bottom)
			)
		)
		(fp_text user "Author: Antmicro"
			(at -0.95 4.169 180)
			(layer "F.Fab")
			(effects
				(font
					(size 0.7 0.7)
					(thickness 0.15)
				)
				(justify left bottom)
			)
		)
		(fp_text user "${REFERENCE}"
			(at -0.95 3.168 180)
			(layer "F.Fab")
			(effects
				(font
					(size 0.7 0.7)
					(thickness 0.15)
				)
				(justify left bottom)
			)
		)
		(pad "1" smd roundrect
			(at -0.48 0 180)
			(size 0.59 0.64)
			(layers "F.Cu" "F.Mask" "F.Paste")
			(roundrect_rratio 0.25)
			(net 380 "/X710 DCDC converters/1V88_PG")
			(pintype "passive")
		)
		(pad "2" smd roundrect
			(at 0.48 0 180)
			(size 0.59 0.64)
			(layers "F.Cu" "F.Mask" "F.Paste")
			(roundrect_rratio 0.25)
			(net 108 "/X710 DCDC converters/1V88_VCC")
			(pintype "passive")
		)
	)
	(footprint "antmicro-footprints:LED_0603_1608Metric_G"
		(layer "F.Cu")
		(at 183.2 73)
		(descr "LED SMD 0603 Green")
		(tags "LED SMD 0603 Green")
		(property "Reference" "D8"
			(at -1.2 6.75 0)
			(layer "F.SilkS")
			(effects
				(font
					(size 0.7 0.7)
					(thickness 0.15)
				)
				(justify left bottom)
			)
		)
		(property "Value" "LED_G_0603_LG_L29K-G2J1-24-Z"
			(at -0.001 1.599 0)
			(layer "F.Fab")
			(effects
				(font
					(size 0.7 0.7)
					(thickness 0.15)
				)
				(justify left bottom)
			)
		)
		(property "Datasheet" "https://look.ams-osram.com/m/19ee86b3ae0ee95b/original/LG-L29K.pdf"
			(at 0 0 0)
			(layer "F.Fab")
			(hide yes)
			(effects
				(font
					(size 1.27 1.27)
					(thickness 0.15)
				)
			)
		)
		(property "Description" "LED, Green, SMD, 0603, 20 mA, 1.7 V, 570 nm"
			(at 0 0 0)
			(layer "F.Fab")
			(hide yes)
			(effects
				(font
					(size 1.27 1.27)
					(thickness 0.15)
				)
			)
		)
		(property "MPN" "LG L29K-G2J1-24-Z"
			(at 0 0 0)
			(unlocked yes)
			(layer "F.Fab")
			(hide yes)
			(effects
				(font
					(size 1 1)
					(thickness 0.15)
				)
			)
		)
		(property "Manufacturer" "OSRAM"
			(at 0 0 0)
			(unlocked yes)
			(layer "F.Fab")
			(hide yes)
			(effects
				(font
					(size 1 1)
					(thickness 0.15)
				)
			)
		)
		(property "Color" "Green"
			(at 0 0 0)
			(unlocked yes)
			(layer "F.Fab")
			(hide yes)
			(effects
				(font
					(size 1 1)
					(thickness 0.15)
				)
			)
		)
		(property "Author" "Antmicro"
			(at 0 0 0)
			(unlocked yes)
			(layer "F.Fab")
			(hide yes)
			(effects
				(font
					(size 1 1)
					(thickness 0.15)
				)
			)
		)
		(property "License" "Apache-2.0"
			(at 0 0 0)
			(unlocked yes)
			(layer "F.Fab")
			(hide yes)
			(effects
				(font
					(size 1 1)
					(thickness 0.15)
				)
			)
		)
		(sheetname "/X710 DCDC converters/")
		(sheetfile "DCDC_converters_X710.kicad_sch")
		(attr smd)
		(fp_line
			(start -1.18 -0.319)
			(end -1.18 0.321)
			(stroke
				(width 0.15)
				(type solid)
			)
			(layer "F.SilkS")
		)
		(fp_line
			(start -0.094672 0.001008)
			(end -0.24 0.001008)
			(stroke
				(width 0.1)
				(type solid)
			)
			(layer "F.SilkS")
		)
		(fp_line
			(start -0.094672 0.001008)
			(end 0.105328 -0.198992)
			(stroke
				(width 0.1)
				(type solid)
			)
			(layer "F.SilkS")
		)
		(fp_line
			(start -0.094672 0.201008)
			(end -0.094672 -0.198992)
			(stroke
				(width 0.1)
				(type solid)
			)
			(layer "F.SilkS")
		)
		(fp_line
			(start 0.105328 0.001008)
			(end 0.24 0.001)
			(stroke
				(width 0.1)
				(type solid)
			)
			(layer "F.SilkS")
		)
		(fp_line
			(start 0.105328 0.201008)
			(end -0.094672 0.001008)
			(stroke
				(width 0.1)
				(type solid)
			)
			(layer "F.SilkS")
		)
		(fp_line
			(start 0.105328 0.201008)
			(end 0.105328 -0.198992)
			(stroke
				(width 0.1)
				(type solid)
			)
			(layer "F.SilkS")
		)
		(fp_line
			(start 0.22 -0.35)
			(end -0.22 -0.35)
			(stroke
				(width 0.15)
				(type solid)
			)
			(layer "F.SilkS")
		)
		(fp_line
			(start 0.22 0.35)
			(end -0.22 0.35)
			(stroke
				(width 0.15)
				(type solid)
			)
			(layer "F.SilkS")
		)
		(fp_rect
			(start 1.25 0.65)
			(end -1.25 -0.65)
			(stroke
				(width 0.05)
				(type solid)
			)
			(fill no)
			(layer "F.CrtYd")
		)
		(fp_line
			(start -0.199 -0.202)
			(end -0.199 0.1)
			(stroke
				(width 0.15)
				(type solid)
			)
			(layer "F.Fab")
		)
		(fp_line
			(start -0.199 0)
			(end -0.597 0)
			(stroke
				(width 0.15)
				(type solid)
			)
			(layer "F.Fab")
		)
		(fp_line
			(start -0.199 0.2)
			(end -0.199 0.1)
			(stroke
				(width 0.15)
				(type solid)
			)
			(layer "F.Fab")
		)
		(fp_line
			(start -0.101 0)
			(end 0.201 0.2)
			(stroke
				(width 0.15)
				(type solid)
			)
			(layer "F.Fab")
		)
		(fp_line
			(start 0.201 -0.202)
			(end -0.101 0)
			(stroke
				(width 0.15)
				(type solid)
			)
			(layer "F.Fab")
		)
		(fp_line
			(start 0.201 0)
			(end 0.201 -0.202)
			(stroke
				(width 0.15)
				(type solid)
			)
			(layer "F.Fab")
		)
		(fp_line
			(start 0.201 0.2)
			(end 0.201 0)
			(stroke
				(width 0.15)
				(type solid)
			)
			(layer "F.Fab")
		)
		(fp_line
			(start 0.599 0)
			(end 0.201 0)
			(stroke
				(width 0.15)
				(type solid)
			)
			(layer "F.Fab")
		)
		(fp_rect
			(start 0.848 0.4)
			(end -0.85 -0.402)
			(stroke
				(width 0.15)
				(type solid)
			)
			(fill no)
			(layer "F.Fab")
		)
		(fp_text user "${REFERENCE}"
			(at -1.4224 5.999 0)
			(layer "F.Fab")
			(effects
				(font
					(size 0.7 0.7)
					(thickness 0.15)
				)
				(justify left bottom)
			)
		)
		(fp_text user "License: Apache-2.0"
			(at -1.4224 3.599 0)
			(layer "F.Fab")
			(effects
				(font
					(size 0.7 0.7)
					(thickness 0.15)
				)
				(justify left bottom)
			)
		)
		(fp_text user "Author: Antmicro"
			(at -1.4224 4.799 0)
			(layer "F.Fab")
			(effects
				(font
					(size 0.7 0.7)
					(thickness 0.15)
				)
				(justify left bottom)
			)
		)
		(pad "1" smd roundrect
			(at -0.7 0 180)
			(size 0.8 1)
			(layers "F.Cu" "F.Mask" "F.Paste")
			(roundrect_rratio 0.2)
			(net 54 "Net-(D8-C)")
			(pinfunction "C")
			(pintype "passive")
		)
		(pad "2" smd roundrect
			(at 0.7 0 180)
			(size 0.8 1)
			(layers "F.Cu" "F.Mask" "F.Paste")
			(roundrect_rratio 0.2)
			(net 334 "/X710 DCDC converters/+3V3_OUT")
			(pinfunction "A")
			(pintype "passive")
		)
	)
	(footprint "antmicro-footprints:C_0603_1608Metric_EIA"
		(layer "F.Cu")
		(at 135.320002 92.600002)
		(descr "Capacitor SMD 0603, IPC-7351 Density Level A")
		(tags "Capacitor 0603")
		(property "Reference" "C134"
			(at 36.934999 -9.199999 0)
			(layer "F.SilkS")
			(effects
				(font
					(size 0.7 0.7)
					(thickness 0.15)
				)
			)
		)
		(property "Value" "C_22u_16V_0603"
			(at -1.42757 1.770288 0)
			(layer "F.Fab")
			(effects
				(font
					(size 0.7 0.7)
					(thickness 0.15)
				)
				(justify left bottom)
			)
		)
		(property "Datasheet" "https://product.samsungsem.com/mlcc/CL10A226MO7JZN.do"
			(at 0 0 0)
			(layer "F.Fab")
			(hide yes)
			(effects
				(font
					(size 1.27 1.27)
					(thickness 0.15)
				)
			)
		)
		(property "Description" "SMD Multilayer Ceramic Capacitor"
			(at 0 0 0)
			(layer "F.Fab")
			(hide yes)
			(effects
				(font
					(size 1.27 1.27)
					(thickness 0.15)
				)
			)
		)
		(property "MPN" "CL10A226MO7JZNC"
			(at 0 0 0)
			(unlocked yes)
			(layer "F.Fab")
			(hide yes)
			(effects
				(font
					(size 1 1)
					(thickness 0.15)
				)
			)
		)
		(property "Manufacturer" "Samsung Electro-Mechanics"
			(at 0 0 0)
			(unlocked yes)
			(layer "F.Fab")
			(hide yes)
			(effects
				(font
					(size 1 1)
					(thickness 0.15)
				)
			)
		)
		(property "License" "Apache-2.0"
			(at 0 0 0)
			(unlocked yes)
			(layer "F.Fab")
			(hide yes)
			(effects
				(font
					(size 1 1)
					(thickness 0.15)
				)
			)
		)
		(property "Author" "Antmicro"
			(at 0 0 0)
			(unlocked yes)
			(layer "F.Fab")
			(hide yes)
			(effects
				(font
					(size 1 1)
					(thickness 0.15)
				)
			)
		)
		(property "Val" "22u"
			(at 0 0 0)
			(unlocked yes)
			(layer "F.Fab")
			(hide yes)
			(effects
				(font
					(size 1 1)
					(thickness 0.15)
				)
			)
		)
		(property "Voltage" "16V"
			(at 0 0 0)
			(unlocked yes)
			(layer "F.Fab")
			(hide yes)
			(effects
				(font
					(size 1 1)
					(thickness 0.15)
				)
			)
		)
		(property "Dielectric" ""
			(at 0 0 0)
			(unlocked yes)
			(layer "F.Fab")
			(hide yes)
			(effects
				(font
					(size 1 1)
					(thickness 0.15)
				)
			)
		)
		(sheetname "/X710 DCDC converters/")
		(sheetfile "DCDC_converters_X710.kicad_sch")
		(attr smd)
		(fp_line
			(start -0.15 -0.55)
			(end 0.15 -0.55)
			(stroke
				(width 0.15)
				(type solid)
			)
			(layer "F.SilkS")
		)
		(fp_line
			(start -0.15 0.55)
			(end 0.15 0.55)
			(stroke
				(width 0.15)
				(type solid)
			)
			(layer "F.SilkS")
		)
		(fp_rect
			(start -1.25 -0.65)
			(end 1.25 0.65)
			(stroke
				(width 0.05)
				(type solid)
			)
			(fill no)
			(layer "F.CrtYd")
		)
		(fp_rect
			(start -0.8 -0.45)
			(end 0.8 0.45)
			(stroke
				(width 0.15)
				(type solid)
			)
			(fill no)
			(layer "F.Fab")
		)
		(fp_text user "License: Apache-2.0"
			(at -1.682 5.895 0)
			(layer "F.Fab")
			(effects
				(font
					(size 0.7 0.7)
					(thickness 0.15)
				)
				(justify left bottom)
			)
		)
		(fp_text user "${REFERENCE}"
			(at -1.682 3.895 0)
			(layer "F.Fab")
			(effects
				(font
					(size 0.7 0.7)
					(thickness 0.15)
				)
				(justify left bottom)
			)
		)
		(fp_text user "Author: Antmicro"
			(at -1.682 4.894 0)
			(layer "F.Fab")
			(effects
				(font
					(size 0.7 0.7)
					(thickness 0.15)
				)
				(justify left bottom)
			)
		)
		(pad "1" smd roundrect
			(at -0.7 0)
			(size 0.8 1.1)
			(layers "F.Cu" "F.Mask" "F.Paste")
			(roundrect_rratio 0.2)
			(net 23 "GND")
			(pintype "passive")
		)
		(pad "2" smd roundrect
			(at 0.7 0)
			(size 0.8 1.1)
			(layers "F.Cu" "F.Mask" "F.Paste")
			(roundrect_rratio 0.2)
			(net 334 "/X710 DCDC converters/+3V3_OUT")
			(pintype "passive")
		)
	)
	(footprint "antmicro-footprints:R_0402_1005Metric"
		(layer "F.Cu")
		(at 153.8 47.9 180)
		(descr "Resistor SMD 0402")
		(tags "resistor SMD 0402")
		(property "Reference" "R226"
			(at 1.8 -1.4 180)
			(layer "F.SilkS")
			(effects
				(font
					(size 0.7 0.7)
					(thickness 0.15)
				)
				(justify left bottom)
			)
		)
		(property "Value" "R_20k_0402"
			(at -1.011843 1.772047 180)
			(layer "F.Fab")
			(effects
				(font
					(size 0.7 0.7)
					(thickness 0.15)
				)
				(justify left bottom)
			)
		)
		(property "Datasheet" "https://www.bourns.com/docs/product-datasheets/cr.pdf"
			(at 0 0 180)
			(layer "F.Fab")
			(hide yes)
			(effects
				(font
					(size 1.27 1.27)
					(thickness 0.15)
				)
			)
		)
		(property "Description" "SMD Chip Resistor, 20 kohm, ± 1%, 62.5 mW, 0402 [1005 Metric], Thick Film, General Purpose"
			(at 0 0 180)
			(layer "F.Fab")
			(hide yes)
			(effects
				(font
					(size 1.27 1.27)
					(thickness 0.15)
				)
			)
		)
		(property "MPN" "CR0402-FX-2002GLF"
			(at 0 0 180)
			(unlocked yes)
			(layer "F.Fab")
			(hide yes)
			(effects
				(font
					(size 1 1)
					(thickness 0.15)
				)
			)
		)
		(property "Manufacturer" "Bourns"
			(at 0 0 180)
			(unlocked yes)
			(layer "F.Fab")
			(hide yes)
			(effects
				(font
					(size 1 1)
					(thickness 0.15)
				)
			)
		)
		(property "License" "Apache-2.0"
			(at 0 0 180)
			(unlocked yes)
			(layer "F.Fab")
			(hide yes)
			(effects
				(font
					(size 1 1)
					(thickness 0.15)
				)
			)
		)
		(property "Author" "Antmicro"
			(at 0 0 180)
			(unlocked yes)
			(layer "F.Fab")
			(hide yes)
			(effects
				(font
					(size 1 1)
					(thickness 0.15)
				)
			)
		)
		(property "Val" "20k"
			(at 0 0 180)
			(unlocked yes)
			(layer "F.Fab")
			(hide yes)
			(effects
				(font
					(size 1 1)
					(thickness 0.15)
				)
			)
		)
		(property "Tolerance" "1%"
			(at 0 0 180)
			(unlocked yes)
			(layer "F.Fab")
			(hide yes)
			(effects
				(font
					(size 1 1)
					(thickness 0.15)
				)
			)
		)
		(sheetname "/Power input/")
		(sheetfile "power_input.kicad_sch")
		(attr smd)
		(fp_rect
			(start -0.925 -0.47)
			(end 0.925 0.47)
			(stroke
				(width 0.05)
				(type default)
			)
			(fill no)
			(layer "F.CrtYd")
		)
		(fp_rect
			(start -0.5 -0.25)
			(end 0.5 0.25)
			(stroke
				(width 0.15)
				(type solid)
			)
			(fill no)
			(layer "F.Fab")
		)
		(fp_text user "Author: Antmicro"
			(at -0.95 4.169 180)
			(layer "F.Fab")
			(effects
				(font
					(size 0.7 0.7)
					(thickness 0.15)
				)
				(justify left bottom)
			)
		)
		(fp_text user "${REFERENCE}"
			(at -0.95 3.168 180)
			(layer "F.Fab")
			(effects
				(font
					(size 0.7 0.7)
					(thickness 0.15)
				)
				(justify left bottom)
			)
		)
		(fp_text user "License: Apache-2.0"
			(at -0.95 5.169 180)
			(layer "F.Fab")
			(effects
				(font
					(size 0.7 0.7)
					(thickness 0.15)
				)
				(justify left bottom)
			)
		)
		(pad "1" smd roundrect
			(at -0.48 0 180)
			(size 0.59 0.64)
			(layers "F.Cu" "F.Mask" "F.Paste")
			(roundrect_rratio 0.25)
			(net 344 "/Power input/5V_EN")
			(pintype "passive")
		)
		(pad "2" smd roundrect
			(at 0.48 0 180)
			(size 0.59 0.64)
			(layers "F.Cu" "F.Mask" "F.Paste")
			(roundrect_rratio 0.25)
			(net 412 "Net-(D15-C)")
			(pintype "passive")
		)
	)
	(footprint "antmicro-footprints:R_0603_1608Metric"
		(layer "F.Cu")
		(at 150.500001 103.05 90)
		(descr "Resistor SMD 0603")
		(tags "resistor SMD 0603")
		(property "Reference" "R110"
			(at -17.649996 14.449998 90)
			(layer "F.SilkS")
			(effects
				(font
					(size 0.7 0.7)
					(thickness 0.15)
				)
			)
		)
		(property "Value" "R_0R_22.4A_0603"
			(at 0 1.6 90)
			(layer "F.Fab")
			(effects
				(font
					(size 0.7 0.7)
					(thickness 0.15)
				)
				(justify left bottom)
			)
		)
		(property "Datasheet" "https://fscdn.rohm.com/en/products/databook/datasheet/passive/resistor/chip_resistor/pmr-jpw-e.pdf"
			(at 0 0 90)
			(layer "F.Fab")
			(hide yes)
			(effects
				(font
					(size 1.27 1.27)
					(thickness 0.15)
				)
			)
		)
		(property "Description" "SMD Chip Resistor"
			(at 0 0 90)
			(layer "F.Fab")
			(hide yes)
			(effects
				(font
					(size 1.27 1.27)
					(thickness 0.15)
				)
			)
		)
		(property "MPN" "PMR03EZPJ000"
			(at 0 0 90)
			(unlocked yes)
			(layer "F.Fab")
			(hide yes)
			(effects
				(font
					(size 1 1)
					(thickness 0.15)
				)
			)
		)
		(property "Manufacturer" "ROHM Semiconductor"
			(at 0 0 90)
			(unlocked yes)
			(layer "F.Fab")
			(hide yes)
			(effects
				(font
					(size 1 1)
					(thickness 0.15)
				)
			)
		)
		(property "Val" "0R"
			(at 0 0 90)
			(unlocked yes)
			(layer "F.Fab")
			(hide yes)
			(effects
				(font
					(size 1 1)
					(thickness 0.15)
				)
			)
		)
		(property "Max. Curr." "22.4A"
			(at 0 0 90)
			(unlocked yes)
			(layer "F.Fab")
			(hide yes)
			(effects
				(font
					(size 1 1)
					(thickness 0.15)
				)
			)
		)
		(property "Author" "Antmicro"
			(at 0 0 90)
			(unlocked yes)
			(layer "F.Fab")
			(hide yes)
			(effects
				(font
					(size 1 1)
					(thickness 0.15)
				)
			)
		)
		(property "License" "Apache-2.0"
			(at 0 0 90)
			(unlocked yes)
			(layer "F.Fab")
			(hide yes)
			(effects
				(font
					(size 1 1)
					(thickness 0.15)
				)
			)
		)
		(property "Tolerance" "template_tolerance"
			(at 0 0 90)
			(unlocked yes)
			(layer "F.Fab")
			(hide yes)
			(effects
				(font
					(size 1 1)
					(thickness 0.15)
				)
			)
		)
		(sheetname "/X710 DCDC converters/")
		(sheetfile "DCDC_converters_X710.kicad_sch")
		(attr smd)
		(fp_line
			(start -0.15 -0.4)
			(end 0.15 -0.4)
			(stroke
				(width 0.15)
				(type solid)
			)
			(layer "F.SilkS")
		)
		(fp_line
			(start -0.15 0.4)
			(end 0.15 0.4)
			(stroke
				(width 0.15)
				(type solid)
			)
			(layer "F.SilkS")
		)
		(fp_rect
			(start -1.25 -0.65)
			(end 1.25 0.65)
			(stroke
				(width 0.05)
				(type solid)
			)
			(fill no)
			(layer "F.CrtYd")
		)
		(fp_rect
			(start -0.8 -0.4)
			(end 0.8 0.4)
			(stroke
				(width 0.15)
				(type solid)
			)
			(fill no)
			(layer "F.Fab")
		)
		(fp_text user "Author: Antmicro"
			(at -1.25 4.9 90)
			(layer "F.Fab")
			(effects
				(font
					(size 0.7 0.7)
					(thickness 0.15)
				)
				(justify left bottom)
			)
		)
		(fp_text user "License: Apache-2.0"
			(at -1.25 5.9 90)
			(layer "F.Fab")
			(effects
				(font
					(size 0.7 0.7)
					(thickness 0.15)
				)
				(justify left bottom)
			)
		)
		(fp_text user "${REFERENCE}"
			(at -1.25 3.898 90)
			(layer "F.Fab")
			(effects
				(font
					(size 0.7 0.7)
					(thickness 0.15)
				)
				(justify left bottom)
			)
		)
		(pad "1" smd roundrect
			(at -0.7 0 90)
			(size 0.8 1)
			(layers "F.Cu" "F.Mask" "F.Paste")
			(roundrect_rratio 0.2)
			(net 338 "/X710 DCDC converters/+1V88_OUT")
			(pintype "passive")
		)
		(pad "2" smd roundrect
			(at 0.7 0 90)
			(size 0.8 1)
			(layers "F.Cu" "F.Mask" "F.Paste")
			(roundrect_rratio 0.2)
			(net 18 "+1V88")
			(pintype "passive")
		)
	)
	(footprint "antmicro-footprints:C_0805_2012Metric"
		(layer "F.Cu")
		(at 147.1 56.8 -90)
		(descr "Capacitor SMD 0805")
		(tags "capacitor SMD 0805")
		(property "Reference" "C318"
			(at 4.6 -0.65 270)
			(layer "F.SilkS")
			(effects
				(font
					(size 0.7 0.7)
					(thickness 0.15)
				)
				(justify left bottom)
			)
		)
		(property "Value" "C_22u_25V_0805"
			(at -2.055717 1.963152 270)
			(layer "F.Fab")
			(effects
				(font
					(size 0.7 0.7)
					(thickness 0.15)
				)
				(justify left bottom)
			)
		)
		(property "Datasheet" "https://product.samsungsem.com/mlcc/CL21A226MAYNNN.do"
			(at 0 0 270)
			(layer "F.Fab")
			(hide yes)
			(effects
				(font
					(size 1.27 1.27)
					(thickness 0.15)
				)
			)
		)
		(property "Description" "SMT Multilayer Ceramic Capacitor, 22uF, +/-20%, 25V, X5R, 0805 [2012 Metric]"
			(at 0 0 270)
			(layer "F.Fab")
			(hide yes)
			(effects
				(font
					(size 1.27 1.27)
					(thickness 0.15)
				)
			)
		)
		(property "MPN" "CL21A226MAYNNNE"
			(at 0 0 270)
			(unlocked yes)
			(layer "F.Fab")
			(hide yes)
			(effects
				(font
					(size 1 1)
					(thickness 0.15)
				)
			)
		)
		(property "Manufacturer" "Samsung Electro-Mechanics"
			(at 0 0 270)
			(unlocked yes)
			(layer "F.Fab")
			(hide yes)
			(effects
				(font
					(size 1 1)
					(thickness 0.15)
				)
			)
		)
		(property "License" "Apache-2.0"
			(at 0 0 270)
			(unlocked yes)
			(layer "F.Fab")
			(hide yes)
			(effects
				(font
					(size 1 1)
					(thickness 0.15)
				)
			)
		)
		(property "Author" "Antmicro"
			(at 0 0 270)
			(unlocked yes)
			(layer "F.Fab")
			(hide yes)
			(effects
				(font
					(size 1 1)
					(thickness 0.15)
				)
			)
		)
		(property "Val" "22u"
			(at 0 0 270)
			(unlocked yes)
			(layer "F.Fab")
			(hide yes)
			(effects
				(font
					(size 1 1)
					(thickness 0.15)
				)
			)
		)
		(property "Voltage" "25V"
			(at 0 0 270)
			(unlocked yes)
			(layer "F.Fab")
			(hide yes)
			(effects
				(font
					(size 1 1)
					(thickness 0.15)
				)
			)
		)
		(property "Dielectric" "X5R"
			(at 0 0 270)
			(unlocked yes)
			(layer "F.Fab")
			(hide yes)
			(effects
				(font
					(size 1 1)
					(thickness 0.15)
				)
			)
		)
		(property "Public" "False"
			(at 0 0 270)
			(unlocked yes)
			(layer "F.Fab")
			(hide yes)
			(effects
				(font
					(size 1 1)
					(thickness 0.15)
				)
			)
		)
		(sheetname "/Power input/")
		(sheetfile "power_input.kicad_sch")
		(attr smd)
		(fp_line
			(start -0.3 0.7)
			(end 0.3 0.7)
			(stroke
				(width 0.15)
				(type solid)
			)
			(layer "F.SilkS")
		)
		(fp_line
			(start -0.3 -0.7)
			(end 0.3 -0.7)
			(stroke
				(width 0.15)
				(type solid)
			)
			(layer "F.SilkS")
		)
		(fp_rect
			(start 1.95 -0.9)
			(end -1.95 0.9)
			(stroke
				(width 0.05)
				(type default)
			)
			(fill no)
			(layer "F.CrtYd")
		)
		(fp_rect
			(start -0.95 -0.675)
			(end 0.95 0.675)
			(stroke
				(width 0.15)
				(type solid)
			)
			(fill no)
			(layer "F.Fab")
		)
		(fp_text user "${REFERENCE}"
			(at -1.9 3.947 270)
			(layer "F.Fab")
			(effects
				(font
					(size 0.7 0.7)
					(thickness 0.15)
				)
				(justify left bottom)
			)
		)
		(fp_text user "License: Apache-2.0"
			(at -1.9 4.947 270)
			(layer "F.Fab")
			(effects
				(font
					(size 0.7 0.7)
					(thickness 0.15)
				)
				(justify left bottom)
			)
		)
		(fp_text user "Author: Antmicro"
			(at -1.9 5.947 270)
			(layer "F.Fab")
			(effects
				(font
					(size 0.7 0.7)
					(thickness 0.15)
				)
				(justify left bottom)
			)
		)
		(pad "1" smd roundrect
			(at -1.1 0 270)
			(size 1.2 1.3)
			(layers "F.Cu" "F.Mask" "F.Paste")
			(roundrect_rratio 0.25)
			(net 23 "GND")
			(pintype "passive")
		)
		(pad "2" smd roundrect
			(at 1.1 0 270)
			(size 1.2 1.3)
			(layers "F.Cu" "F.Mask" "F.Paste")
			(roundrect_rratio 0.25)
			(net 349 "/Power input/5V_OUT")
			(pintype "passive")
		)
	)
	(footprint "antmicro-footprints:Fiducial_1mm_Mask2mm"
		(layer "F.Cu")
		(at 127 145)
		(descr "Circular Fiducial, 1mm bare copper, 3mm soldermask opening")
		(tags "fiducial")
		(property "Reference" "FD5"
			(at -1 -1.4 0)
			(layer "F.SilkS")
			(effects
				(font
					(size 0.7 0.7)
					(thickness 0.15)
				)
				(justify left bottom)
			)
		)
		(property "Value" "Fiducial_1mm_Mask2mm"
			(at 0 2.2 0)
			(layer "F.Fab")
			(effects
				(font
					(size 0.7 0.7)
					(thickness 0.15)
				)
				(justify left bottom)
			)
		)
		(property "Description" "Fiducial mask"
			(at 0 0 0)
			(layer "F.Fab")
			(hide yes)
			(effects
				(font
					(size 1.27 1.27)
					(thickness 0.15)
				)
			)
		)
		(property "Author" "Antmicro"
			(at 0 0 0)
			(unlocked yes)
			(layer "F.Fab")
			(hide yes)
			(effects
				(font
					(size 1 1)
					(thickness 0.15)
				)
			)
		)
		(property "License" "Apache-2.0"
			(at 0 0 0)
			(unlocked yes)
			(layer "F.Fab")
			(hide yes)
			(effects
				(font
					(size 1 1)
					(thickness 0.15)
				)
			)
		)
		(sheetname "/")
		(sheetfile "thunderbolt-to-10gbe-adapter.kicad_sch")
		(attr exclude_from_pos_files exclude_from_bom)
		(fp_circle
			(center 0 0)
			(end 1.24 0)
			(stroke
				(width 0.05)
				(type solid)
			)
			(fill no)
			(layer "F.CrtYd")
		)
		(fp_circle
			(center 0 0)
			(end 0.999 0)
			(stroke
				(width 0.15)
				(type solid)
			)
			(fill no)
			(layer "F.Fab")
		)
		(fp_text user "Author: Antmicro"
			(at -1.25 5.803 0)
			(layer "F.Fab")
			(effects
				(font
					(size 0.7 0.7)
					(thickness 0.15)
				)
				(justify left bottom)
			)
		)
		(fp_text user "${REFERENCE}"
			(at -1.25 4.603 0)
			(layer "F.Fab")
			(effects
				(font
					(size 0.7 0.7)
					(thickness 0.15)
				)
				(justify left bottom)
			)
		)
		(fp_text user "License: Apache-2.0"
			(at -1.25 7.003 0)
			(layer "F.Fab")
			(effects
				(font
					(size 0.7 0.7)
					(thickness 0.15)
				)
				(justify left bottom)
			)
		)
		(pad "" smd circle
			(at 0 0)
			(size 1 1)
			(layers "F.Cu" "F.Mask")
			(solder_mask_margin 0.5)
			(clearance 0.5)
		)
	)
	(footprint "antmicro-footprints:C_0603_1608Metric_EIA"
		(layer "F.Cu")
		(at 137.870001 92.600003 180)
		(descr "Capacitor SMD 0603, IPC-7351 Density Level A")
		(tags "Capacitor 0603")
		(property "Reference" "C139"
			(at -37.144997 9.199999 180)
			(layer "F.SilkS")
			(effects
				(font
					(size 0.7 0.7)
					(thickness 0.15)
				)
			)
		)
		(property "Value" "C_22u_16V_0603"
			(at -1.42757 1.770288 180)
			(layer "F.Fab")
			(effects
				(font
					(size 0.7 0.7)
					(thickness 0.15)
				)
				(justify left bottom)
			)
		)
		(property "Datasheet" "https://product.samsungsem.com/mlcc/CL10A226MO7JZN.do"
			(at 0 0 180)
			(layer "F.Fab")
			(hide yes)
			(effects
				(font
					(size 1.27 1.27)
					(thickness 0.15)
				)
			)
		)
		(property "Description" "SMD Multilayer Ceramic Capacitor"
			(at 0 0 180)
			(layer "F.Fab")
			(hide yes)
			(effects
				(font
					(size 1.27 1.27)
					(thickness 0.15)
				)
			)
		)
		(property "MPN" "CL10A226MO7JZNC"
			(at 0 0 180)
			(unlocked yes)
			(layer "F.Fab")
			(hide yes)
			(effects
				(font
					(size 1 1)
					(thickness 0.15)
				)
			)
		)
		(property "Manufacturer" "Samsung Electro-Mechanics"
			(at 0 0 180)
			(unlocked yes)
			(layer "F.Fab")
			(hide yes)
			(effects
				(font
					(size 1 1)
					(thickness 0.15)
				)
			)
		)
		(property "License" "Apache-2.0"
			(at 0 0 180)
			(unlocked yes)
			(layer "F.Fab")
			(hide yes)
			(effects
				(font
					(size 1 1)
					(thickness 0.15)
				)
			)
		)
		(property "Author" "Antmicro"
			(at 0 0 180)
			(unlocked yes)
			(layer "F.Fab")
			(hide yes)
			(effects
				(font
					(size 1 1)
					(thickness 0.15)
				)
			)
		)
		(property "Val" "22u"
			(at 0 0 180)
			(unlocked yes)
			(layer "F.Fab")
			(hide yes)
			(effects
				(font
					(size 1 1)
					(thickness 0.15)
				)
			)
		)
		(property "Voltage" "16V"
			(at 0 0 180)
			(unlocked yes)
			(layer "F.Fab")
			(hide yes)
			(effects
				(font
					(size 1 1)
					(thickness 0.15)
				)
			)
		)
		(property "Dielectric" ""
			(at 0 0 180)
			(unlocked yes)
			(layer "F.Fab")
			(hide yes)
			(effects
				(font
					(size 1 1)
					(thickness 0.15)
				)
			)
		)
		(sheetname "/X710 DCDC converters/")
		(sheetfile "DCDC_converters_X710.kicad_sch")
		(attr smd)
		(fp_line
			(start -0.15 0.55)
			(end 0.15 0.55)
			(stroke
				(width 0.15)
				(type solid)
			)
			(layer "F.SilkS")
		)
		(fp_line
			(start -0.15 -0.55)
			(end 0.15 -0.55)
			(stroke
				(width 0.15)
				(type solid)
			)
			(layer "F.SilkS")
		)
		(fp_rect
			(start -1.25 -0.65)
			(end 1.25 0.65)
			(stroke
				(width 0.05)
				(type solid)
			)
			(fill no)
			(layer "F.CrtYd")
		)
		(fp_rect
			(start -0.8 -0.45)
			(end 0.8 0.45)
			(stroke
				(width 0.15)
				(type solid)
			)
			(fill no)
			(layer "F.Fab")
		)
		(fp_text user "License: Apache-2.0"
			(at -1.682 5.895 180)
			(layer "F.Fab")
			(effects
				(font
					(size 0.7 0.7)
					(thickness 0.15)
				)
				(justify left bottom)
			)
		)
		(fp_text user "Author: Antmicro"
			(at -1.682 4.894 180)
			(layer "F.Fab")
			(effects
				(font
					(size 0.7 0.7)
					(thickness 0.15)
				)
				(justify left bottom)
			)
		)
		(fp_text user "${REFERENCE}"
			(at -1.682 3.895 180)
			(layer "F.Fab")
			(effects
				(font
					(size 0.7 0.7)
					(thickness 0.15)
				)
				(justify left bottom)
			)
		)
		(pad "1" smd roundrect
			(at -0.7 0 180)
			(size 0.8 1.1)
			(layers "F.Cu" "F.Mask" "F.Paste")
			(roundrect_rratio 0.2)
			(net 23 "GND")
			(pintype "passive")
		)
		(pad "2" smd roundrect
			(at 0.7 0 180)
			(size 0.8 1.1)
			(layers "F.Cu" "F.Mask" "F.Paste")
			(roundrect_rratio 0.2)
			(net 334 "/X710 DCDC converters/+3V3_OUT")
			(pintype "passive")
		)
	)
	(footprint "antmicro-footprints:R_0402_1005Metric"
		(layer "F.Cu")
		(at 154.304999 65.174999 90)
		(descr "Resistor SMD 0402")
		(tags "resistor SMD 0402")
		(property "Reference" "R148"
			(at 2.374999 0.095001 90)
			(layer "F.SilkS")
			(effects
				(font
					(size 0.7 0.7)
					(thickness 0.15)
				)
			)
		)
		(property "Value" "R_100k_0402"
			(at -1.011843 1.772047 90)
			(layer "F.Fab")
			(effects
				(font
					(size 0.7 0.7)
					(thickness 0.15)
				)
				(justify left bottom)
			)
		)
		(property "Datasheet" "https://www.bourns.com/docs/product-datasheets/cr.pdf"
			(at 0 0 90)
			(layer "F.Fab")
			(hide yes)
			(effects
				(font
					(size 1.27 1.27)
					(thickness 0.15)
				)
			)
		)
		(property "Description" "SMD Chip Resistor, 100 kohm, ± 1%, 62.5 mW, 0402 [1005 Metric], Thick Film, General Purpose"
			(at 0 0 90)
			(layer "F.Fab")
			(hide yes)
			(effects
				(font
					(size 1.27 1.27)
					(thickness 0.15)
				)
			)
		)
		(property "MPN" "CR0402-FX-1003GLF"
			(at 0 0 90)
			(unlocked yes)
			(layer "F.Fab")
			(hide yes)
			(effects
				(font
					(size 1 1)
					(thickness 0.15)
				)
			)
		)
		(property "Manufacturer" "Bourns"
			(at 0 0 90)
			(unlocked yes)
			(layer "F.Fab")
			(hide yes)
			(effects
				(font
					(size 1 1)
					(thickness 0.15)
				)
			)
		)
		(property "License" "Apache-2.0"
			(at 0 0 90)
			(unlocked yes)
			(layer "F.Fab")
			(hide yes)
			(effects
				(font
					(size 1 1)
					(thickness 0.15)
				)
			)
		)
		(property "Author" "Antmicro"
			(at 0 0 90)
			(unlocked yes)
			(layer "F.Fab")
			(hide yes)
			(effects
				(font
					(size 1 1)
					(thickness 0.15)
				)
			)
		)
		(property "Val" "100k"
			(at 0 0 90)
			(unlocked yes)
			(layer "F.Fab")
			(hide yes)
			(effects
				(font
					(size 1 1)
					(thickness 0.15)
				)
			)
		)
		(property "Tolerance" "1%"
			(at 0 0 90)
			(unlocked yes)
			(layer "F.Fab")
			(hide yes)
			(effects
				(font
					(size 1 1)
					(thickness 0.15)
				)
			)
		)
		(sheetname "/X710-AT2 Misc/")
		(sheetfile "x710-at2-mics.kicad_sch")
		(attr smd)
		(fp_rect
			(start -0.925 -0.47)
			(end 0.925 0.47)
			(stroke
				(width 0.05)
				(type default)
			)
			(fill no)
			(layer "F.CrtYd")
		)
		(fp_rect
			(start -0.5 -0.25)
			(end 0.5 0.25)
			(stroke
				(width 0.15)
				(type solid)
			)
			(fill no)
			(layer "F.Fab")
		)
		(fp_text user "License: Apache-2.0"
			(at -0.95 5.169 90)
			(layer "F.Fab")
			(effects
				(font
					(size 0.7 0.7)
					(thickness 0.15)
				)
				(justify left bottom)
			)
		)
		(fp_text user "${REFERENCE}"
			(at -0.95 3.168 90)
			(layer "F.Fab")
			(effects
				(font
					(size 0.7 0.7)
					(thickness 0.15)
				)
				(justify left bottom)
			)
		)
		(fp_text user "Author: Antmicro"
			(at -0.95 4.169 90)
			(layer "F.Fab")
			(effects
				(font
					(size 0.7 0.7)
					(thickness 0.15)
				)
				(justify left bottom)
			)
		)
		(pad "1" smd roundrect
			(at -0.48 0 90)
			(size 0.59 0.64)
			(layers "F.Cu" "F.Mask" "F.Paste")
			(roundrect_rratio 0.25)
			(net 23 "GND")
			(pintype "passive")
		)
		(pad "2" smd roundrect
			(at 0.48 0 90)
			(size 0.59 0.64)
			(layers "F.Cu" "F.Mask" "F.Paste")
			(roundrect_rratio 0.25)
			(net 143 "/X710-AT2 Misc/NCSI.TX_EN")
			(pintype "passive")
		)
	)
	(footprint "antmicro-footprints:C_0805_2012Metric"
		(layer "F.Cu")
		(at 119.65 109.75 180)
		(descr "Capacitor SMD 0805")
		(tags "capacitor SMD 0805")
		(property "Reference" "C8"
			(at -6.55 -5.45 180)
			(layer "F.SilkS")
			(effects
				(font
					(size 0.7 0.7)
					(thickness 0.15)
				)
			)
		)
		(property "Value" "C_22u_25V_0805"
			(at -2.055717 1.963152 180)
			(layer "F.Fab")
			(effects
				(font
					(size 0.7 0.7)
					(thickness 0.15)
				)
				(justify left bottom)
			)
		)
		(property "Datasheet" "https://product.samsungsem.com/mlcc/CL21A226MAYNNN.do"
			(at 0 0 180)
			(layer "F.Fab")
			(hide yes)
			(effects
				(font
					(size 1.27 1.27)
					(thickness 0.15)
				)
			)
		)
		(property "Description" "SMT Multilayer Ceramic Capacitor, 22uF, +/-20%, 25V, X5R, 0805 [2012 Metric]"
			(at 0 0 180)
			(layer "F.Fab")
			(hide yes)
			(effects
				(font
					(size 1.27 1.27)
					(thickness 0.15)
				)
			)
		)
		(property "MPN" "CL21A226MAYNNNE"
			(at 0 0 180)
			(unlocked yes)
			(layer "F.Fab")
			(hide yes)
			(effects
				(font
					(size 1 1)
					(thickness 0.15)
				)
			)
		)
		(property "Manufacturer" "Samsung Electro-Mechanics"
			(at 0 0 180)
			(unlocked yes)
			(layer "F.Fab")
			(hide yes)
			(effects
				(font
					(size 1 1)
					(thickness 0.15)
				)
			)
		)
		(property "License" "Apache-2.0"
			(at 0 0 180)
			(unlocked yes)
			(layer "F.Fab")
			(hide yes)
			(effects
				(font
					(size 1 1)
					(thickness 0.15)
				)
			)
		)
		(property "Author" "Antmicro"
			(at 0 0 180)
			(unlocked yes)
			(layer "F.Fab")
			(hide yes)
			(effects
				(font
					(size 1 1)
					(thickness 0.15)
				)
			)
		)
		(property "Val" "22u"
			(at 0 0 180)
			(unlocked yes)
			(layer "F.Fab")
			(hide yes)
			(effects
				(font
					(size 1 1)
					(thickness 0.15)
				)
			)
		)
		(property "Voltage" "25V"
			(at 0 0 180)
			(unlocked yes)
			(layer "F.Fab")
			(hide yes)
			(effects
				(font
					(size 1 1)
					(thickness 0.15)
				)
			)
		)
		(property "Dielectric" "X5R"
			(at 0 0 180)
			(unlocked yes)
			(layer "F.Fab")
			(hide yes)
			(effects
				(font
					(size 1 1)
					(thickness 0.15)
				)
			)
		)
		(property "Public" "False"
			(at 0 0 180)
			(unlocked yes)
			(layer "F.Fab")
			(hide yes)
			(effects
				(font
					(size 1 1)
					(thickness 0.15)
				)
			)
		)
		(sheetname "/PD and TB DC-DC/")
		(sheetfile "PD_and_TB_DC_DC.kicad_sch")
		(attr smd)
		(fp_line
			(start -0.3 0.7)
			(end 0.3 0.7)
			(stroke
				(width 0.15)
				(type solid)
			)
			(layer "F.SilkS")
		)
		(fp_line
			(start -0.3 -0.7)
			(end 0.3 -0.7)
			(stroke
				(width 0.15)
				(type solid)
			)
			(layer "F.SilkS")
		)
		(fp_rect
			(start 1.95 -0.9)
			(end -1.95 0.9)
			(stroke
				(width 0.05)
				(type default)
			)
			(fill no)
			(layer "F.CrtYd")
		)
		(fp_rect
			(start -0.95 -0.675)
			(end 0.95 0.675)
			(stroke
				(width 0.15)
				(type solid)
			)
			(fill no)
			(layer "F.Fab")
		)
		(fp_text user "${REFERENCE}"
			(at -1.9 3.947 180)
			(layer "F.Fab")
			(effects
				(font
					(size 0.7 0.7)
					(thickness 0.15)
				)
				(justify left bottom)
			)
		)
		(fp_text user "Author: Antmicro"
			(at -1.9 5.947 180)
			(layer "F.Fab")
			(effects
				(font
					(size 0.7 0.7)
					(thickness 0.15)
				)
				(justify left bottom)
			)
		)
		(fp_text user "License: Apache-2.0"
			(at -1.9 4.947 180)
			(layer "F.Fab")
			(effects
				(font
					(size 0.7 0.7)
					(thickness 0.15)
				)
				(justify left bottom)
			)
		)
		(pad "1" smd roundrect
			(at -1.1 0 180)
			(size 1.2 1.3)
			(layers "F.Cu" "F.Mask" "F.Paste")
			(roundrect_rratio 0.25)
			(net 23 "GND")
			(pintype "passive")
		)
		(pad "2" smd roundrect
			(at 1.1 0 180)
			(size 1.2 1.3)
			(layers "F.Cu" "F.Mask" "F.Paste")
			(roundrect_rratio 0.25)
			(net 161 "Net-(U2-VIN)")
			(pintype "passive")
		)
	)
	(footprint "antmicro-footprints:R_0402_1005Metric"
		(layer "F.Cu")
		(at 157.155001 67.124999 -90)
		(descr "Resistor SMD 0402")
		(tags "resistor SMD 0402")
		(property "Reference" "R158"
			(at -12.324999 -20.295 270)
			(layer "F.SilkS")
			(effects
				(font
					(size 0.7 0.7)
					(thickness 0.15)
				)
			)
		)
		(property "Value" "R_100k_0402"
			(at -1.011843 1.772047 270)
			(layer "F.Fab")
			(effects
				(font
					(size 0.7 0.7)
					(thickness 0.15)
				)
				(justify left bottom)
			)
		)
		(property "Datasheet" "https://www.bourns.com/docs/product-datasheets/cr.pdf"
			(at 0 0 270)
			(layer "F.Fab")
			(hide yes)
			(effects
				(font
					(size 1.27 1.27)
					(thickness 0.15)
				)
			)
		)
		(property "Description" "SMD Chip Resistor, 100 kohm, ± 1%, 62.5 mW, 0402 [1005 Metric], Thick Film, General Purpose"
			(at 0 0 270)
			(layer "F.Fab")
			(hide yes)
			(effects
				(font
					(size 1.27 1.27)
					(thickness 0.15)
				)
			)
		)
		(property "MPN" "CR0402-FX-1003GLF"
			(at 0 0 270)
			(unlocked yes)
			(layer "F.Fab")
			(hide yes)
			(effects
				(font
					(size 1 1)
					(thickness 0.15)
				)
			)
		)
		(property "Manufacturer" "Bourns"
			(at 0 0 270)
			(unlocked yes)
			(layer "F.Fab")
			(hide yes)
			(effects
				(font
					(size 1 1)
					(thickness 0.15)
				)
			)
		)
		(property "License" "Apache-2.0"
			(at 0 0 270)
			(unlocked yes)
			(layer "F.Fab")
			(hide yes)
			(effects
				(font
					(size 1 1)
					(thickness 0.15)
				)
			)
		)
		(property "Author" "Antmicro"
			(at 0 0 270)
			(unlocked yes)
			(layer "F.Fab")
			(hide yes)
			(effects
				(font
					(size 1 1)
					(thickness 0.15)
				)
			)
		)
		(property "Val" "100k"
			(at 0 0 270)
			(unlocked yes)
			(layer "F.Fab")
			(hide yes)
			(effects
				(font
					(size 1 1)
					(thickness 0.15)
				)
			)
		)
		(property "Tolerance" "1%"
			(at 0 0 270)
			(unlocked yes)
			(layer "F.Fab")
			(hide yes)
			(effects
				(font
					(size 1 1)
					(thickness 0.15)
				)
			)
		)
		(sheetname "/X710-AT2 Misc/")
		(sheetfile "x710-at2-mics.kicad_sch")
		(attr smd dnp)
		(fp_rect
			(start -0.925 -0.47)
			(end 0.925 0.47)
			(stroke
				(width 0.05)
				(type default)
			)
			(fill no)
			(layer "F.CrtYd")
		)
		(fp_rect
			(start -0.5 -0.25)
			(end 0.5 0.25)
			(stroke
				(width 0.15)
				(type solid)
			)
			(fill no)
			(layer "F.Fab")
		)
		(fp_text user "License: Apache-2.0"
			(at -0.95 5.169 270)
			(layer "F.Fab")
			(effects
				(font
					(size 0.7 0.7)
					(thickness 0.15)
				)
				(justify left bottom)
			)
		)
		(fp_text user "${REFERENCE}"
			(at -0.95 3.168 270)
			(layer "F.Fab")
			(effects
				(font
					(size 0.7 0.7)
					(thickness 0.15)
				)
				(justify left bottom)
			)
		)
		(fp_text user "Author: Antmicro"
			(at -0.95 4.169 270)
			(layer "F.Fab")
			(effects
				(font
					(size 0.7 0.7)
					(thickness 0.15)
				)
				(justify left bottom)
			)
		)
		(pad "1" smd roundrect
			(at -0.48 0 270)
			(size 0.59 0.64)
			(layers "F.Cu" "F.Mask" "F.Paste")
			(roundrect_rratio 0.25)
			(net 141 "/X710-AT2 Misc/NCSI.ARB_OUT")
			(pintype "passive")
		)
		(pad "2" smd roundrect
			(at 0.48 0 270)
			(size 0.59 0.64)
			(layers "F.Cu" "F.Mask" "F.Paste")
			(roundrect_rratio 0.25)
			(net 7 "+3V3")
			(pintype "passive")
		)
	)
	(footprint "antmicro-footprints:R_0402_1005Metric"
		(layer "F.Cu")
		(at 116.4 109.1 180)
		(descr "Resistor SMD 0402")
		(tags "resistor SMD 0402")
		(property "Reference" "R6"
			(at 0 8.1 180)
			(layer "F.SilkS")
			(effects
				(font
					(size 0.7 0.7)
					(thickness 0.15)
				)
			)
		)
		(property "Value" "R_10k_0402"
			(at -1.011843 1.772047 180)
			(layer "F.Fab")
			(effects
				(font
					(size 0.7 0.7)
					(thickness 0.15)
				)
				(justify left bottom)
			)
		)
		(property "Datasheet" "https://www.bourns.com/docs/product-datasheets/cr.pdf"
			(at 0 0 180)
			(layer "F.Fab")
			(hide yes)
			(effects
				(font
					(size 1.27 1.27)
					(thickness 0.15)
				)
			)
		)
		(property "Description" "SMD Chip Resistor, 10 kohm, ± 1%, 62.5 mW, 0402 [1005 Metric], Thick Film, General Purpose"
			(at 0 0 180)
			(layer "F.Fab")
			(hide yes)
			(effects
				(font
					(size 1.27 1.27)
					(thickness 0.15)
				)
			)
		)
		(property "MPN" "CR0402-FX-1002GLF"
			(at 0 0 180)
			(unlocked yes)
			(layer "F.Fab")
			(hide yes)
			(effects
				(font
					(size 1 1)
					(thickness 0.15)
				)
			)
		)
		(property "Manufacturer" "Bourns"
			(at 0 0 180)
			(unlocked yes)
			(layer "F.Fab")
			(hide yes)
			(effects
				(font
					(size 1 1)
					(thickness 0.15)
				)
			)
		)
		(property "License" "Apache-2.0"
			(at 0 0 180)
			(unlocked yes)
			(layer "F.Fab")
			(hide yes)
			(effects
				(font
					(size 1 1)
					(thickness 0.15)
				)
			)
		)
		(property "Val" "10k"
			(at 0 0 180)
			(unlocked yes)
			(layer "F.Fab")
			(hide yes)
			(effects
				(font
					(size 1 1)
					(thickness 0.15)
				)
			)
		)
		(property "Tolerance" "1%"
			(at 0 0 180)
			(unlocked yes)
			(layer "F.Fab")
			(hide yes)
			(effects
				(font
					(size 1 1)
					(thickness 0.15)
				)
			)
		)
		(property "Author" "Antmicro"
			(at 0 0 180)
			(unlocked yes)
			(layer "F.Fab")
			(hide yes)
			(effects
				(font
					(size 1 1)
					(thickness 0.15)
				)
			)
		)
		(sheetname "/PD and TB DC-DC/")
		(sheetfile "PD_and_TB_DC_DC.kicad_sch")
		(attr smd)
		(fp_rect
			(start -0.925 -0.47)
			(end 0.925 0.47)
			(stroke
				(width 0.05)
				(type default)
			)
			(fill no)
			(layer "F.CrtYd")
		)
		(fp_rect
			(start -0.5 -0.25)
			(end 0.5 0.25)
			(stroke
				(width 0.15)
				(type solid)
			)
			(fill no)
			(layer "F.Fab")
		)
		(fp_text user "${REFERENCE}"
			(at -0.95 3.168 180)
			(layer "F.Fab")
			(effects
				(font
					(size 0.7 0.7)
					(thickness 0.15)
				)
				(justify left bottom)
			)
		)
		(fp_text user "License: Apache-2.0"
			(at -0.95 5.169 180)
			(layer "F.Fab")
			(effects
				(font
					(size 0.7 0.7)
					(thickness 0.15)
				)
				(justify left bottom)
			)
		)
		(fp_text user "Author: Antmicro"
			(at -0.95 4.169 180)
			(layer "F.Fab")
			(effects
				(font
					(size 0.7 0.7)
					(thickness 0.15)
				)
				(justify left bottom)
			)
		)
		(pad "1" smd roundrect
			(at -0.48 0 180)
			(size 0.59 0.64)
			(layers "F.Cu" "F.Mask" "F.Paste")
			(roundrect_rratio 0.25)
			(net 413 "Net-(D3-C)")
			(pintype "passive")
		)
		(pad "2" smd roundrect
			(at 0.48 0 180)
			(size 0.59 0.64)
			(layers "F.Cu" "F.Mask" "F.Paste")
			(roundrect_rratio 0.25)
			(net 161 "Net-(U2-VIN)")
			(pintype "passive")
		)
	)
	(footprint "antmicro-footprints:R_0402_1005Metric"
		(layer "F.Cu")
		(at 164 80.4)
		(descr "Resistor SMD 0402")
		(tags "resistor SMD 0402")
		(property "Reference" "R204"
			(at -1 6.4 0)
			(layer "F.SilkS")
			(effects
				(font
					(size 0.7 0.7)
					(thickness 0.15)
				)
				(justify left bottom)
			)
		)
		(property "Value" "R_1k_0402"
			(at -1.011843 1.772047 0)
			(layer "F.Fab")
			(effects
				(font
					(size 0.7 0.7)
					(thickness 0.15)
				)
				(justify left bottom)
			)
		)
		(property "Datasheet" "https://www.bourns.com/docs/product-datasheets/cr.pdf"
			(at 0 0 0)
			(layer "F.Fab")
			(hide yes)
			(effects
				(font
					(size 1.27 1.27)
					(thickness 0.15)
				)
			)
		)
		(property "Description" "SMD Chip Resistor, 1 kohm, ± 1%, 63 mW, 0402 [1005 Metric], Thick Film, General Purpose"
			(at 0 0 0)
			(layer "F.Fab")
			(hide yes)
			(effects
				(font
					(size 1.27 1.27)
					(thickness 0.15)
				)
			)
		)
		(property "MPN" "CR0402-FX-1001GLF"
			(at 0 0 0)
			(unlocked yes)
			(layer "F.Fab")
			(hide yes)
			(effects
				(font
					(size 1 1)
					(thickness 0.15)
				)
			)
		)
		(property "Manufacturer" "Bourns"
			(at 0 0 0)
			(unlocked yes)
			(layer "F.Fab")
			(hide yes)
			(effects
				(font
					(size 1 1)
					(thickness 0.15)
				)
			)
		)
		(property "License" "Apache-2.0"
			(at 0 0 0)
			(unlocked yes)
			(layer "F.Fab")
			(hide yes)
			(effects
				(font
					(size 1 1)
					(thickness 0.15)
				)
			)
		)
		(property "Author" "Antmicro"
			(at 0 0 0)
			(unlocked yes)
			(layer "F.Fab")
			(hide yes)
			(effects
				(font
					(size 1 1)
					(thickness 0.15)
				)
			)
		)
		(property "Val" "1k"
			(at 0 0 0)
			(unlocked yes)
			(layer "F.Fab")
			(hide yes)
			(effects
				(font
					(size 1 1)
					(thickness 0.15)
				)
			)
		)
		(property "Tolerance" "1%"
			(at 0 0 0)
			(unlocked yes)
			(layer "F.Fab")
			(hide yes)
			(effects
				(font
					(size 1 1)
					(thickness 0.15)
				)
			)
		)
		(sheetname "/X710-AT2 10GbE/")
		(sheetfile "x710-at2-10gbe.kicad_sch")
		(attr smd dnp)
		(fp_rect
			(start -0.925 -0.47)
			(end 0.925 0.47)
			(stroke
				(width 0.05)
				(type default)
			)
			(fill no)
			(layer "F.CrtYd")
		)
		(fp_rect
			(start -0.5 -0.25)
			(end 0.5 0.25)
			(stroke
				(width 0.15)
				(type solid)
			)
			(fill no)
			(layer "F.Fab")
		)
		(fp_text user "Author: Antmicro"
			(at -0.95 4.169 0)
			(layer "F.Fab")
			(effects
				(font
					(size 0.7 0.7)
					(thickness 0.15)
				)
				(justify left bottom)
			)
		)
		(fp_text user "License: Apache-2.0"
			(at -0.95 5.169 0)
			(layer "F.Fab")
			(effects
				(font
					(size 0.7 0.7)
					(thickness 0.15)
				)
				(justify left bottom)
			)
		)
		(fp_text user "${REFERENCE}"
			(at -0.95 3.168 0)
			(layer "F.Fab")
			(effects
				(font
					(size 0.7 0.7)
					(thickness 0.15)
				)
				(justify left bottom)
			)
		)
		(pad "1" smd roundrect
			(at -0.48 0)
			(size 0.59 0.64)
			(layers "F.Cu" "F.Mask" "F.Paste")
			(roundrect_rratio 0.25)
			(net 130 "/X710-AT2 10GbE/TPIN_3")
			(pintype "passive")
		)
		(pad "2" smd roundrect
			(at 0.48 0)
			(size 0.59 0.64)
			(layers "F.Cu" "F.Mask" "F.Paste")
			(roundrect_rratio 0.25)
			(net 18 "+1V88")
			(pintype "passive")
		)
	)
	(footprint "antmicro-footprints:Conn_Molex_KK_1x4_0470531000"
		(layer "F.Cu")
		(at 118.5 83.62 90)
		(property "Reference" "J7"
			(at 9.32 2.3 180)
			(layer "F.SilkS")
			(effects
				(font
					(size 0.7 0.7)
					(thickness 0.15)
				)
				(justify left bottom)
			)
		)
		(property "Value" "Molex_KK_1x4_0470531000"
			(at 0 4.7 90)
			(layer "F.Fab")
			(effects
				(font
					(size 0.7 0.7)
					(thickness 0.15)
				)
				(justify left bottom)
			)
		)
		(property "Datasheet" "https://tools.molex.com/pdm_docs/sd/470531000_sd.pdf"
			(at 0 0 90)
			(layer "F.Fab")
			(hide yes)
			(effects
				(font
					(size 1.27 1.27)
					(thickness 0.15)
				)
			)
		)
		(property "Description" "Connector Header, THT,  4x1"
			(at 0 0 90)
			(layer "F.Fab")
			(hide yes)
			(effects
				(font
					(size 1.27 1.27)
					(thickness 0.15)
				)
			)
		)
		(property "MPN" "0470531000"
			(at 0 0 90)
			(unlocked yes)
			(layer "F.Fab")
			(hide yes)
			(effects
				(font
					(size 1 1)
					(thickness 0.15)
				)
			)
		)
		(property "Manufacturer" "Molex"
			(at 0 0 90)
			(unlocked yes)
			(layer "F.Fab")
			(hide yes)
			(effects
				(font
					(size 1 1)
					(thickness 0.15)
				)
			)
		)
		(property "Author" "Antmicro"
			(at 0 0 90)
			(unlocked yes)
			(layer "F.Fab")
			(hide yes)
			(effects
				(font
					(size 1 1)
					(thickness 0.15)
				)
			)
		)
		(property "License" "Apache-2.0"
			(at 0 0 90)
			(unlocked yes)
			(layer "F.Fab")
			(hide yes)
			(effects
				(font
					(size 1 1)
					(thickness 0.15)
				)
			)
		)
		(sheetname "/Fan controller/")
		(sheetfile "fan-controller.kicad_sch")
		(attr through_hole)
		(fp_line
			(start -1.35 -2.6)
			(end 4.4 -2.6)
			(stroke
				(width 0.15)
				(type solid)
			)
			(layer "F.SilkS")
		)
		(fp_line
			(start 8.95 -2.55)
			(end 8.95 3.4)
			(stroke
				(width 0.15)
				(type solid)
			)
			(layer "F.SilkS")
		)
		(fp_line
			(start 5.75 -2.55)
			(end 8.95 -2.55)
			(stroke
				(width 0.15)
				(type solid)
			)
			(layer "F.SilkS")
		)
		(fp_line
			(start 5.08 2.29)
			(end 5.08 3.3)
			(stroke
				(width 0.15)
				(type solid)
			)
			(layer "F.SilkS")
		)
		(fp_line
			(start 0 2.29)
			(end 5.08 2.29)
			(stroke
				(width 0.15)
				(type solid)
			)
			(layer "F.SilkS")
		)
		(fp_line
			(start 0 3.3)
			(end 0 2.29)
			(stroke
				(width 0.15)
				(type solid)
			)
			(layer "F.SilkS")
		)
		(fp_line
			(start 8.95 3.4)
			(end -1.35 3.4)
			(stroke
				(width 0.15)
				(type solid)
			)
			(layer "F.SilkS")
		)
		(fp_line
			(start -1.35 3.4)
			(end -1.35 -2.6)
			(stroke
				(width 0.15)
				(type solid)
			)
			(layer "F.SilkS")
		)
		(fp_circle
			(center 0 -3)
			(end 0.05 -3)
			(stroke
				(width 0.15)
				(type solid)
			)
			(fill yes)
			(layer "F.SilkS")
		)
		(fp_rect
			(start -1.54 -2.96)
			(end 9.16 3.55)
			(stroke
				(width 0.05)
				(type solid)
			)
			(fill no)
			(layer "F.CrtYd")
		)
		(fp_line
			(start 8.85 -2.5)
			(end 8.85 3.3)
			(stroke
				(width 0.15)
				(type solid)
			)
			(layer "F.Fab")
		)
		(fp_line
			(start 5.75 -2.5)
			(end 8.85 -2.5)
			(stroke
				(width 0.15)
				(type solid)
			)
			(layer "F.Fab")
		)
		(fp_line
			(start -1.25 -2.5)
			(end 4.4 -2.5)
			(stroke
				(width 0.15)
				(type solid)
			)
			(layer "F.Fab")
		)
		(fp_line
			(start 5.1 2.3)
			(end 0 2.3)
			(stroke
				(width 0.15)
				(type solid)
			)
			(layer "F.Fab")
		)
		(fp_line
			(start 0 2.3)
			(end 0 3.3)
			(stroke
				(width 0.15)
				(type solid)
			)
			(layer "F.Fab")
		)
		(fp_line
			(start 8.85 3.3)
			(end -1.2 3.3)
			(stroke
				(width 0.15)
				(type solid)
			)
			(layer "F.Fab")
		)
		(fp_line
			(start 5.1 3.3)
			(end 5.1 2.3)
			(stroke
				(width 0.15)
				(type solid)
			)
			(layer "F.Fab")
		)
		(fp_line
			(start -1.2 3.3)
			(end -1.25 3.3)
			(stroke
				(width 0.15)
				(type solid)
			)
			(layer "F.Fab")
		)
		(fp_line
			(start -1.25 3.3)
			(end -1.25 -2.5)
			(stroke
				(width 0.15)
				(type solid)
			)
			(layer "F.Fab")
		)
		(fp_text user "Author: Antmicro"
			(at -2.1 7.55 90)
			(layer "F.Fab")
			(effects
				(font
					(size 0.7 0.7)
					(thickness 0.15)
				)
				(justify left bottom)
			)
		)
		(fp_text user "License: Apache-2.0"
			(at -2.1 8.75 90)
			(layer "F.Fab")
			(effects
				(font
					(size 0.7 0.7)
					(thickness 0.15)
				)
				(justify left bottom)
			)
		)
		(fp_text user "${REFERENCE}"
			(at -2.1 6.35 90)
			(layer "F.Fab")
			(effects
				(font
					(size 0.7 0.7)
					(thickness 0.15)
				)
				(justify left bottom)
			)
		)
		(pad "" np_thru_hole circle
			(at 5.08 -2.16 180)
			(size 1.1 1.1)
			(drill 1.1)
			(layers "*.Cu" "*.Mask")
		)
		(pad "1" thru_hole rect
			(at 0 0 180)
			(size 2.03 1.73)
			(drill 1.02)
			(layers "*.Cu" "*.Mask")
			(remove_unused_layers no)
			(net 23 "GND")
			(pintype "passive")
		)
		(pad "2" thru_hole oval
			(at 2.54 0 180)
			(size 2.03 1.73)
			(drill 1.02)
			(layers "*.Cu" "*.Mask")
			(remove_unused_layers no)
			(net 40 "+5V")
			(pintype "passive")
		)
		(pad "3" thru_hole oval
			(at 5.08 0 180)
			(size 2.03 1.73)
			(drill 1.02)
			(layers "*.Cu" "*.Mask")
			(remove_unused_layers no)
			(net 155 "/Fan controller/TACH")
			(pintype "passive+no_connect")
		)
		(pad "4" thru_hole oval
			(at 7.62 0 180)
			(size 2.03 1.73)
			(drill 1.02)
			(layers "*.Cu" "*.Mask")
			(remove_unused_layers no)
			(net 154 "/Fan controller/PWM")
			(pintype "passive")
		)
	)
	(footprint "antmicro-footprints:LED_0603_1608Metric_G"
		(layer "F.Cu")
		(at 183.2 74.5)
		(descr "LED SMD 0603 Green")
		(tags "LED SMD 0603 Green")
		(property "Reference" "D9"
			(at -1.2 6.25 0)
			(layer "F.SilkS")
			(effects
				(font
					(size 0.7 0.7)
					(thickness 0.15)
				)
				(justify left bottom)
			)
		)
		(property "Value" "LED_G_0603_LG_L29K-G2J1-24-Z"
			(at -0.001 1.599 0)
			(layer "F.Fab")
			(effects
				(font
					(size 0.7 0.7)
					(thickness 0.15)
				)
				(justify left bottom)
			)
		)
		(property "Datasheet" "https://look.ams-osram.com/m/19ee86b3ae0ee95b/original/LG-L29K.pdf"
			(at 0 0 0)
			(layer "F.Fab")
			(hide yes)
			(effects
				(font
					(size 1.27 1.27)
					(thickness 0.15)
				)
			)
		)
		(property "Description" "LED, Green, SMD, 0603, 20 mA, 1.7 V, 570 nm"
			(at 0 0 0)
			(layer "F.Fab")
			(hide yes)
			(effects
				(font
					(size 1.27 1.27)
					(thickness 0.15)
				)
			)
		)
		(property "MPN" "LG L29K-G2J1-24-Z"
			(at 0 0 0)
			(unlocked yes)
			(layer "F.Fab")
			(hide yes)
			(effects
				(font
					(size 1 1)
					(thickness 0.15)
				)
			)
		)
		(property "Manufacturer" "OSRAM"
			(at 0 0 0)
			(unlocked yes)
			(layer "F.Fab")
			(hide yes)
			(effects
				(font
					(size 1 1)
					(thickness 0.15)
				)
			)
		)
		(property "Color" "Green"
			(at 0 0 0)
			(unlocked yes)
			(layer "F.Fab")
			(hide yes)
			(effects
				(font
					(size 1 1)
					(thickness 0.15)
				)
			)
		)
		(property "Author" "Antmicro"
			(at 0 0 0)
			(unlocked yes)
			(layer "F.Fab")
			(hide yes)
			(effects
				(font
					(size 1 1)
					(thickness 0.15)
				)
			)
		)
		(property "License" "Apache-2.0"
			(at 0 0 0)
			(unlocked yes)
			(layer "F.Fab")
			(hide yes)
			(effects
				(font
					(size 1 1)
					(thickness 0.15)
				)
			)
		)
		(sheetname "/X710 DCDC converters/")
		(sheetfile "DCDC_converters_X710.kicad_sch")
		(attr smd)
		(fp_line
			(start -1.18 -0.319)
			(end -1.18 0.321)
			(stroke
				(width 0.15)
				(type solid)
			)
			(layer "F.SilkS")
		)
		(fp_line
			(start -0.094672 0.001008)
			(end -0.24 0.001008)
			(stroke
				(width 0.1)
				(type solid)
			)
			(layer "F.SilkS")
		)
		(fp_line
			(start -0.094672 0.001008)
			(end 0.105328 -0.198992)
			(stroke
				(width 0.1)
				(type solid)
			)
			(layer "F.SilkS")
		)
		(fp_line
			(start -0.094672 0.201008)
			(end -0.094672 -0.198992)
			(stroke
				(width 0.1)
				(type solid)
			)
			(layer "F.SilkS")
		)
		(fp_line
			(start 0.105328 0.001008)
			(end 0.24 0.001)
			(stroke
				(width 0.1)
				(type solid)
			)
			(layer "F.SilkS")
		)
		(fp_line
			(start 0.105328 0.201008)
			(end -0.094672 0.001008)
			(stroke
				(width 0.1)
				(type solid)
			)
			(layer "F.SilkS")
		)
		(fp_line
			(start 0.105328 0.201008)
			(end 0.105328 -0.198992)
			(stroke
				(width 0.1)
				(type solid)
			)
			(layer "F.SilkS")
		)
		(fp_line
			(start 0.22 -0.35)
			(end -0.22 -0.35)
			(stroke
				(width 0.15)
				(type solid)
			)
			(layer "F.SilkS")
		)
		(fp_line
			(start 0.22 0.35)
			(end -0.22 0.35)
			(stroke
				(width 0.15)
				(type solid)
			)
			(layer "F.SilkS")
		)
		(fp_rect
			(start 1.25 0.65)
			(end -1.25 -0.65)
			(stroke
				(width 0.05)
				(type solid)
			)
			(fill no)
			(layer "F.CrtYd")
		)
		(fp_line
			(start -0.199 -0.202)
			(end -0.199 0.1)
			(stroke
				(width 0.15)
				(type solid)
			)
			(layer "F.Fab")
		)
		(fp_line
			(start -0.199 0)
			(end -0.597 0)
			(stroke
				(width 0.15)
				(type solid)
			)
			(layer "F.Fab")
		)
		(fp_line
			(start -0.199 0.2)
			(end -0.199 0.1)
			(stroke
				(width 0.15)
				(type solid)
			)
			(layer "F.Fab")
		)
		(fp_line
			(start -0.101 0)
			(end 0.201 0.2)
			(stroke
				(width 0.15)
				(type solid)
			)
			(layer "F.Fab")
		)
		(fp_line
			(start 0.201 -0.202)
			(end -0.101 0)
			(stroke
				(width 0.15)
				(type solid)
			)
			(layer "F.Fab")
		)
		(fp_line
			(start 0.201 0)
			(end 0.201 -0.202)
			(stroke
				(width 0.15)
				(type solid)
			)
			(layer "F.Fab")
		)
		(fp_line
			(start 0.201 0.2)
			(end 0.201 0)
			(stroke
				(width 0.15)
				(type solid)
			)
			(layer "F.Fab")
		)
		(fp_line
			(start 0.599 0)
			(end 0.201 0)
			(stroke
				(width 0.15)
				(type solid)
			)
			(layer "F.Fab")
		)
		(fp_rect
			(start 0.848 0.4)
			(end -0.85 -0.402)
			(stroke
				(width 0.15)
				(type solid)
			)
			(fill no)
			(layer "F.Fab")
		)
		(fp_text user "${REFERENCE}"
			(at -1.4224 5.999 0)
			(layer "F.Fab")
			(effects
				(font
					(size 0.7 0.7)
					(thickness 0.15)
				)
				(justify left bottom)
			)
		)
		(fp_text user "License: Apache-2.0"
			(at -1.4224 3.599 0)
			(layer "F.Fab")
			(effects
				(font
					(size 0.7 0.7)
					(thickness 0.15)
				)
				(justify left bottom)
			)
		)
		(fp_text user "Author: Antmicro"
			(at -1.4224 4.799 0)
			(layer "F.Fab")
			(effects
				(font
					(size 0.7 0.7)
					(thickness 0.15)
				)
				(justify left bottom)
			)
		)
		(pad "1" smd roundrect
			(at -0.7 0 180)
			(size 0.8 1)
			(layers "F.Cu" "F.Mask" "F.Paste")
			(roundrect_rratio 0.2)
			(net 416 "Net-(D9-C)")
			(pinfunction "C")
			(pintype "passive")
		)
		(pad "2" smd roundrect
			(at 0.7 0 180)
			(size 0.8 1)
			(layers "F.Cu" "F.Mask" "F.Paste")
			(roundrect_rratio 0.2)
			(net 334 "/X710 DCDC converters/+3V3_OUT")
			(pinfunction "A")
			(pintype "passive")
		)
	)
	(footprint "antmicro-footprints:MP_Pad6mm_Drill3.2mm"
		(layer "F.Cu")
		(at 128 108 90)
		(property "Reference" "MP5"
			(at -0.4 3.4 180)
			(layer "F.SilkS")
			(effects
				(font
					(size 0.7 0.7)
					(thickness 0.15)
				)
				(justify left bottom)
			)
		)
		(property "Value" "MP_Pad6mm_Drill3.2mm"
			(at 0 3.9 90)
			(layer "F.Fab")
			(effects
				(font
					(size 0.7 0.7)
					(thickness 0.15)
				)
				(justify left bottom)
			)
		)
		(property "Description" "Mechanical part"
			(at 0 0 90)
			(layer "F.Fab")
			(hide yes)
			(effects
				(font
					(size 1.27 1.27)
					(thickness 0.15)
				)
			)
		)
		(property "Author" "Antmicro"
			(at 0 0 90)
			(unlocked yes)
			(layer "F.Fab")
			(hide yes)
			(effects
				(font
					(size 1 1)
					(thickness 0.15)
				)
			)
		)
		(property "License" "Apache-2.0"
			(at 0 0 90)
			(unlocked yes)
			(layer "F.Fab")
			(hide yes)
			(effects
				(font
					(size 1 1)
					(thickness 0.15)
				)
			)
		)
		(sheetname "/")
		(sheetfile "thunderbolt-to-10gbe-adapter.kicad_sch")
		(attr exclude_from_pos_files exclude_from_bom)
		(fp_circle
			(center 0 0)
			(end 3.25 0)
			(stroke
				(width 0.05)
				(type default)
			)
			(fill no)
			(layer "F.CrtYd")
		)
		(fp_text user "License: Apache-2.0"
			(at -0.178 8.425 90)
			(layer "F.Fab")
			(effects
				(font
					(size 0.7 0.7)
					(thickness 0.15)
				)
				(justify left bottom)
			)
		)
		(fp_text user "${REFERENCE}"
			(at -0.178 6.025 90)
			(layer "F.Fab")
			(effects
				(font
					(size 0.7 0.7)
					(thickness 0.15)
				)
				(justify left bottom)
			)
		)
		(fp_text user "Author: Antmicro"
			(at -0.178 7.225 90)
			(layer "F.Fab")
			(effects
				(font
					(size 0.7 0.7)
					(thickness 0.15)
				)
				(justify left bottom)
			)
		)
		(pad "1" thru_hole circle
			(at 0 0 90)
			(size 6 6)
			(drill 3.2)
			(layers "*.Cu" "*.Mask")
			(remove_unused_layers no)
			(net 23 "GND")
			(pintype "passive")
		)
	)
	(footprint "antmicro-footprints:C_Pol_EIA-B"
		(layer "F.Cu")
		(at 121.2 114.5 180)
		(property "Reference" "C32"
			(at 0 -2.3 180)
			(layer "F.SilkS")
			(effects
				(font
					(size 0.7 0.7)
					(thickness 0.15)
				)
			)
		)
		(property "Value" "C_Pol_330u_6.3V_KEMET-T520-B"
			(at 0 2.85 180)
			(layer "F.Fab")
			(effects
				(font
					(size 0.7 0.7)
					(thickness 0.15)
				)
				(justify left bottom)
			)
		)
		(property "Datasheet" "https://www.kemet.com/en/us/capacitors/product/T520B337M006ATE040.html"
			(at 0 0 180)
			(layer "F.Fab")
			(hide yes)
			(effects
				(font
					(size 1.27 1.27)
					(thickness 0.15)
				)
			)
		)
		(property "Description" "Tantalum Polymer Capacitor, KO-CAP®, 330 µF, ± 20%, 6.3 V, B, 0.04 ohm, 1411 [3528 Metric]"
			(at 0 0 180)
			(layer "F.Fab")
			(hide yes)
			(effects
				(font
					(size 1.27 1.27)
					(thickness 0.15)
				)
			)
		)
		(property "Val" "330u"
			(at 0 0 180)
			(unlocked yes)
			(layer "F.Fab")
			(hide yes)
			(effects
				(font
					(size 1 1)
					(thickness 0.15)
				)
			)
		)
		(property "MPN" "T520B337M006ATE040"
			(at 0 0 180)
			(unlocked yes)
			(layer "F.Fab")
			(hide yes)
			(effects
				(font
					(size 1 1)
					(thickness 0.15)
				)
			)
		)
		(property "Manufacturer" "KEMET"
			(at 0 0 180)
			(unlocked yes)
			(layer "F.Fab")
			(hide yes)
			(effects
				(font
					(size 1 1)
					(thickness 0.15)
				)
			)
		)
		(property "License" "Apache-2.0"
			(at 0 0 180)
			(unlocked yes)
			(layer "F.Fab")
			(hide yes)
			(effects
				(font
					(size 1 1)
					(thickness 0.15)
				)
			)
		)
		(property "Author" "Antmicro"
			(at 0 0 180)
			(unlocked yes)
			(layer "F.Fab")
			(hide yes)
			(effects
				(font
					(size 1 1)
					(thickness 0.15)
				)
			)
		)
		(property "Voltage" "6.3V"
			(at 0 0 180)
			(unlocked yes)
			(layer "F.Fab")
			(hide yes)
			(effects
				(font
					(size 1 1)
					(thickness 0.15)
				)
			)
		)
		(property "Dielectric" "template_dielectric"
			(at 0 0 180)
			(unlocked yes)
			(layer "F.Fab")
			(hide yes)
			(effects
				(font
					(size 1 1)
					(thickness 0.15)
				)
			)
		)
		(sheetname "/PD and TB DC-DC/")
		(sheetfile "PD_and_TB_DC_DC.kicad_sch")
		(attr smd)
		(fp_line
			(start 1.8 1.6)
			(end -1.8 1.6)
			(stroke
				(width 0.15)
				(type solid)
			)
			(layer "F.SilkS")
		)
		(fp_line
			(start 1.8 1.3)
			(end 1.8 1.6)
			(stroke
				(width 0.15)
				(type solid)
			)
			(layer "F.SilkS")
		)
		(fp_line
			(start 1.8 -1.3)
			(end 1.8 -1.6)
			(stroke
				(width 0.15)
				(type solid)
			)
			(layer "F.SilkS")
		)
		(fp_line
			(start -1.8 1.3)
			(end -1.8 1.6)
			(stroke
				(width 0.15)
				(type solid)
			)
			(layer "F.SilkS")
		)
		(fp_line
			(start -1.8 -1.3)
			(end -1.8 -1.6)
			(stroke
				(width 0.15)
				(type solid)
			)
			(layer "F.SilkS")
		)
		(fp_line
			(start -1.8 -1.6)
			(end 1.8 -1.6)
			(stroke
				(width 0.15)
				(type solid)
			)
			(layer "F.SilkS")
		)
		(fp_line
			(start -2.325 -1.475)
			(end -2.325 -1.878)
			(stroke
				(width 0.15)
				(type solid)
			)
			(layer "F.SilkS")
		)
		(fp_line
			(start -2.521 -1.676)
			(end -2.123 -1.676)
			(stroke
				(width 0.15)
				(type solid)
			)
			(layer "F.SilkS")
		)
		(fp_line
			(start 2.4 1.35)
			(end 1.96 1.35)
			(stroke
				(width 0.05)
				(type solid)
			)
			(layer "F.CrtYd")
		)
		(fp_line
			(start 2.399 -1.35)
			(end 2.4 1.35)
			(stroke
				(width 0.05)
				(type solid)
			)
			(layer "F.CrtYd")
		)
		(fp_line
			(start 2.399 -1.35)
			(end 1.959 -1.35)
			(stroke
				(width 0.05)
				(type solid)
			)
			(layer "F.CrtYd")
		)
		(fp_line
			(start 1.96 1.75)
			(end -1.97 1.75)
			(stroke
				(width 0.05)
				(type solid)
			)
			(layer "F.CrtYd")
		)
		(fp_line
			(start 1.96 1.35)
			(end 1.96 1.75)
			(stroke
				(width 0.05)
				(type solid)
			)
			(layer "F.CrtYd")
		)
		(fp_line
			(start 1.959 -1.75)
			(end 1.959 -1.35)
			(stroke
				(width 0.05)
				(type solid)
			)
			(layer "F.CrtYd")
		)
		(fp_line
			(start 1.959 -1.75)
			(end -1.97 -1.75)
			(stroke
				(width 0.05)
				(type solid)
			)
			(layer "F.CrtYd")
		)
		(fp_line
			(start -1.97 1.35)
			(end -1.97 1.75)
			(stroke
				(width 0.05)
				(type solid)
			)
			(layer "F.CrtYd")
		)
		(fp_line
			(start -1.97 1.35)
			(end -2.41 1.35)
			(stroke
				(width 0.05)
				(type solid)
			)
			(layer "F.CrtYd")
		)
		(fp_line
			(start -1.97 -1.35)
			(end -2.41 -1.35)
			(stroke
				(width 0.05)
				(type solid)
			)
			(layer "F.CrtYd")
		)
		(fp_line
			(start -1.97 -1.75)
			(end -1.97 -1.35)
			(stroke
				(width 0.05)
				(type solid)
			)
			(layer "F.CrtYd")
		)
		(fp_line
			(start -2.411 -1.35)
			(end -2.41 1.35)
			(stroke
				(width 0.05)
				(type solid)
			)
			(layer "F.CrtYd")
		)
		(fp_line
			(start -1.7 1.324)
			(end -1.551 1.475)
			(stroke
				(width 0.15)
				(type solid)
			)
			(layer "F.Fab")
		)
		(fp_rect
			(start -1.72 -1.5)
			(end 1.719 1.499)
			(stroke
				(width 0.15)
				(type solid)
			)
			(fill no)
			(layer "F.Fab")
		)
		(fp_text user "License: Apache-2.0"
			(at -2.665 5.65 180)
			(layer "F.Fab")
			(effects
				(font
					(size 0.7 0.7)
					(thickness 0.15)
				)
				(justify left bottom)
			)
		)
		(fp_text user "Author: Antmicro"
			(at -2.665 6.85 180)
			(layer "F.Fab")
			(effects
				(font
					(size 0.7 0.7)
					(thickness 0.15)
				)
				(justify left bottom)
			)
		)
		(fp_text user "${REFERENCE}"
			(at -2.665 4.45 180)
			(layer "F.Fab")
			(effects
				(font
					(size 0.7 0.7)
					(thickness 0.15)
				)
				(justify left bottom)
			)
		)
		(pad "1" smd roundrect
			(at -1.551 0 180)
			(size 1.2 2.2)
			(layers "F.Cu" "F.Mask" "F.Paste")
			(roundrect_rratio 0.1)
			(net 57 "+3V3_TB")
			(pintype "passive")
		)
		(pad "2" smd roundrect
			(at 1.55 0 180)
			(size 1.2 2.2)
			(layers "F.Cu" "F.Mask" "F.Paste")
			(roundrect_rratio 0.1)
			(net 23 "GND")
			(pintype "passive")
		)
	)
	(footprint "antmicro-footprints:MP_Pad6mm_Drill3.2mm"
		(layer "F.Cu")
		(at 180 124)
		(property "Reference" "MP2"
			(at 1 -3.25 0)
			(layer "F.SilkS")
			(effects
				(font
					(size 0.7 0.7)
					(thickness 0.15)
				)
				(justify left bottom)
			)
		)
		(property "Value" "MP_Pad6mm_Drill3.2mm"
			(at 0 3.9 0)
			(layer "F.Fab")
			(effects
				(font
					(size 0.7 0.7)
					(thickness 0.15)
				)
				(justify left bottom)
			)
		)
		(property "Description" "Mechanical part"
			(at 0 0 0)
			(layer "F.Fab")
			(hide yes)
			(effects
				(font
					(size 1.27 1.27)
					(thickness 0.15)
				)
			)
		)
		(property "Author" "Antmicro"
			(at 0 0 0)
			(unlocked yes)
			(layer "F.Fab")
			(hide yes)
			(effects
				(font
					(size 1 1)
					(thickness 0.15)
				)
			)
		)
		(property "License" "Apache-2.0"
			(at 0 0 0)
			(unlocked yes)
			(layer "F.Fab")
			(hide yes)
			(effects
				(font
					(size 1 1)
					(thickness 0.15)
				)
			)
		)
		(sheetname "/")
		(sheetfile "thunderbolt-to-10gbe-adapter.kicad_sch")
		(attr exclude_from_pos_files exclude_from_bom)
		(fp_circle
			(center 0 0)
			(end 3.25 0)
			(stroke
				(width 0.05)
				(type default)
			)
			(fill no)
			(layer "F.CrtYd")
		)
		(fp_text user "${REFERENCE}"
			(at -0.178 6.025 0)
			(layer "F.Fab")
			(effects
				(font
					(size 0.7 0.7)
					(thickness 0.15)
				)
				(justify left bottom)
			)
		)
		(fp_text user "License: Apache-2.0"
			(at -0.178 8.425 0)
			(layer "F.Fab")
			(effects
				(font
					(size 0.7 0.7)
					(thickness 0.15)
				)
				(justify left bottom)
			)
		)
		(fp_text user "Author: Antmicro"
			(at -0.178 7.225 0)
			(layer "F.Fab")
			(effects
				(font
					(size 0.7 0.7)
					(thickness 0.15)
				)
				(justify left bottom)
			)
		)
		(pad "1" thru_hole circle
			(at 0 0)
			(size 6 6)
			(drill 3.2)
			(layers "*.Cu" "*.Mask")
			(remove_unused_layers no)
			(net 23 "GND")
			(pintype "passive")
		)
	)
	(footprint "antmicro-footprints:R_0402_1005Metric"
		(layer "F.Cu")
		(at 147.2 116.4 -90)
		(descr "Resistor SMD 0402")
		(tags "resistor SMD 0402")
		(property "Reference" "R81"
			(at 0 -1 270)
			(layer "F.SilkS")
			(effects
				(font
					(size 0.7 0.7)
					(thickness 0.15)
				)
			)
		)
		(property "Value" "R_3k3_0402"
			(at -1.011843 1.772047 270)
			(layer "F.Fab")
			(effects
				(font
					(size 0.7 0.7)
					(thickness 0.15)
				)
				(justify left bottom)
			)
		)
		(property "Datasheet" "https://www.bourns.com/docs/product-datasheets/cr.pdf"
			(at 0 0 270)
			(layer "F.Fab")
			(hide yes)
			(effects
				(font
					(size 1.27 1.27)
					(thickness 0.15)
				)
			)
		)
		(property "Description" "SMD Chip Resistor, 3.3 kohm, ± 1%, 63 mW, 0402 [1005 Metric], Thick Film, General Purpose"
			(at 0 0 270)
			(layer "F.Fab")
			(hide yes)
			(effects
				(font
					(size 1.27 1.27)
					(thickness 0.15)
				)
			)
		)
		(property "MPN" "CR0402-FX-3301GLF"
			(at 0 0 270)
			(unlocked yes)
			(layer "F.Fab")
			(hide yes)
			(effects
				(font
					(size 1 1)
					(thickness 0.15)
				)
			)
		)
		(property "Manufacturer" "Bourns"
			(at 0 0 270)
			(unlocked yes)
			(layer "F.Fab")
			(hide yes)
			(effects
				(font
					(size 1 1)
					(thickness 0.15)
				)
			)
		)
		(property "License" "Apache-2.0"
			(at 0 0 270)
			(unlocked yes)
			(layer "F.Fab")
			(hide yes)
			(effects
				(font
					(size 1 1)
					(thickness 0.15)
				)
			)
		)
		(property "Val" "3k3"
			(at 0 0 270)
			(unlocked yes)
			(layer "F.Fab")
			(hide yes)
			(effects
				(font
					(size 1 1)
					(thickness 0.15)
				)
			)
		)
		(property "Tolerance" "1%"
			(at 0 0 270)
			(unlocked yes)
			(layer "F.Fab")
			(hide yes)
			(effects
				(font
					(size 1 1)
					(thickness 0.15)
				)
			)
		)
		(property "Author" "Antmicro"
			(at 0 0 270)
			(unlocked yes)
			(layer "F.Fab")
			(hide yes)
			(effects
				(font
					(size 1 1)
					(thickness 0.15)
				)
			)
		)
		(sheetname "/TB flash memory/")
		(sheetfile "flash-memory.kicad_sch")
		(attr smd)
		(fp_rect
			(start -0.925 -0.47)
			(end 0.925 0.47)
			(stroke
				(width 0.05)
				(type default)
			)
			(fill no)
			(layer "F.CrtYd")
		)
		(fp_rect
			(start -0.5 -0.25)
			(end 0.5 0.25)
			(stroke
				(width 0.15)
				(type solid)
			)
			(fill no)
			(layer "F.Fab")
		)
		(fp_text user "License: Apache-2.0"
			(at -0.95 5.169 270)
			(layer "F.Fab")
			(effects
				(font
					(size 0.7 0.7)
					(thickness 0.15)
				)
				(justify left bottom)
			)
		)
		(fp_text user "${REFERENCE}"
			(at -0.95 3.168 270)
			(layer "F.Fab")
			(effects
				(font
					(size 0.7 0.7)
					(thickness 0.15)
				)
				(justify left bottom)
			)
		)
		(fp_text user "Author: Antmicro"
			(at -0.95 4.169 270)
			(layer "F.Fab")
			(effects
				(font
					(size 0.7 0.7)
					(thickness 0.15)
				)
				(justify left bottom)
			)
		)
		(pad "1" smd roundrect
			(at -0.48 0 270)
			(size 0.59 0.64)
			(layers "F.Cu" "F.Mask" "F.Paste")
			(roundrect_rratio 0.25)
			(net 57 "+3V3_TB")
			(pintype "passive")
		)
		(pad "2" smd roundrect
			(at 0.48 0 270)
			(size 0.59 0.64)
			(layers "F.Cu" "F.Mask" "F.Paste")
			(roundrect_rratio 0.25)
			(net 370 "/TB flash memory/FLASH_HOLD")
			(pintype "passive")
		)
	)
	(footprint "antmicro-footprints:C_0402_1005Metric"
		(layer "F.Cu")
		(at 161.4 51.5 -90)
		(descr "Capacitor SMD 0402")
		(tags "capacitor SMD 0402")
		(property "Reference" "C316"
			(at 1.65 -1.8 270)
			(layer "F.SilkS")
			(effects
				(font
					(size 0.7 0.7)
					(thickness 0.15)
				)
				(justify left bottom)
			)
		)
		(property "Value" "C_4u7_25V_0402"
			(at -1.022927 2.155213 270)
			(layer "F.Fab")
			(effects
				(font
					(size 0.7 0.7)
					(thickness 0.15)
				)
				(justify left bottom)
			)
		)
		(property "Datasheet" "https://www.murata.com/products/productdetail?partno=GRM155C61E475ME15%23"
			(at 0 0 270)
			(layer "F.Fab")
			(hide yes)
			(effects
				(font
					(size 1.27 1.27)
					(thickness 0.15)
				)
			)
		)
		(property "Description" "SMD Multilayer Ceramic Capacitor"
			(at 0 0 270)
			(layer "F.Fab")
			(hide yes)
			(effects
				(font
					(size 1.27 1.27)
					(thickness 0.15)
				)
			)
		)
		(property "MPN" "GRM155C61E475ME15J"
			(at 0 0 270)
			(unlocked yes)
			(layer "F.Fab")
			(hide yes)
			(effects
				(font
					(size 1 1)
					(thickness 0.15)
				)
			)
		)
		(property "Manufacturer" "Murata"
			(at 0 0 270)
			(unlocked yes)
			(layer "F.Fab")
			(hide yes)
			(effects
				(font
					(size 1 1)
					(thickness 0.15)
				)
			)
		)
		(property "License" "Apache-2.0"
			(at 0 0 270)
			(unlocked yes)
			(layer "F.Fab")
			(hide yes)
			(effects
				(font
					(size 1 1)
					(thickness 0.15)
				)
			)
		)
		(property "Author" "Antmicro"
			(at 0 0 270)
			(unlocked yes)
			(layer "F.Fab")
			(hide yes)
			(effects
				(font
					(size 1 1)
					(thickness 0.15)
				)
			)
		)
		(property "Val" "4u7"
			(at 0 0 270)
			(unlocked yes)
			(layer "F.Fab")
			(hide yes)
			(effects
				(font
					(size 1 1)
					(thickness 0.15)
				)
			)
		)
		(property "Voltage" "25V"
			(at 0 0 270)
			(unlocked yes)
			(layer "F.Fab")
			(hide yes)
			(effects
				(font
					(size 1 1)
					(thickness 0.15)
				)
			)
		)
		(property "Dielectric" "X5S"
			(at 0 0 270)
			(unlocked yes)
			(layer "F.Fab")
			(hide yes)
			(effects
				(font
					(size 1 1)
					(thickness 0.15)
				)
			)
		)
		(sheetname "/Power input/")
		(sheetfile "power_input.kicad_sch")
		(attr smd)
		(fp_rect
			(start -0.925 -0.47)
			(end 0.925 0.47)
			(stroke
				(width 0.05)
				(type default)
			)
			(fill no)
			(layer "F.CrtYd")
		)
		(fp_line
			(start -0.494 0.248)
			(end -0.494 -0.25)
			(stroke
				(width 0.15)
				(type solid)
			)
			(layer "F.Fab")
		)
		(fp_line
			(start 0.504 0.248)
			(end -0.494 0.248)
			(stroke
				(width 0.15)
				(type solid)
			)
			(layer "F.Fab")
		)
		(fp_line
			(start -0.494 -0.25)
			(end 0.504 -0.25)
			(stroke
				(width 0.15)
				(type solid)
			)
			(layer "F.Fab")
		)
		(fp_line
			(start 0.504 -0.25)
			(end 0.504 0.248)
			(stroke
				(width 0.15)
				(type solid)
			)
			(layer "F.Fab")
		)
		(fp_text user "License: Apache-2.0"
			(at -0.939 5.799 270)
			(layer "F.Fab")
			(effects
				(font
					(size 0.7 0.7)
					(thickness 0.15)
				)
				(justify left bottom)
			)
		)
		(fp_text user "${REFERENCE}"
			(at -0.939 4.599 270)
			(layer "F.Fab")
			(effects
				(font
					(size 0.7 0.7)
					(thickness 0.15)
				)
				(justify left bottom)
			)
		)
		(fp_text user "Author: Antmicro"
			(at -0.939 3.399 270)
			(layer "F.Fab")
			(effects
				(font
					(size 0.7 0.7)
					(thickness 0.15)
				)
				(justify left bottom)
			)
		)
		(pad "1" smd roundrect
			(at -0.48 0 270)
			(size 0.59 0.64)
			(layers "F.Cu" "F.Mask" "F.Paste")
			(roundrect_rratio 0.25)
			(net 23 "GND")
			(pintype "passive")
		)
		(pad "2" smd roundrect
			(at 0.48 0 270)
			(size 0.59 0.64)
			(layers "F.Cu" "F.Mask" "F.Paste")
			(roundrect_rratio 0.25)
			(net 346 "/Power input/5V_VDRV")
			(pintype "passive")
		)
	)
	(footprint "antmicro-footprints:R_0402_1005Metric"
		(layer "F.Cu")
		(at 116.4 107.1)
		(descr "Resistor SMD 0402")
		(tags "resistor SMD 0402")
		(property "Reference" "R22"
			(at 0 -8.1 0)
			(layer "F.SilkS")
			(effects
				(font
					(size 0.7 0.7)
					(thickness 0.15)
				)
			)
		)
		(property "Value" "R_8k87_0402"
			(at -1.011843 1.772047 0)
			(layer "F.Fab")
			(effects
				(font
					(size 0.7 0.7)
					(thickness 0.15)
				)
				(justify left bottom)
			)
		)
		(property "Datasheet" "https://www.bourns.com/docs/product-datasheets/cr.pdf"
			(at 0 0 0)
			(layer "F.Fab")
			(hide yes)
			(effects
				(font
					(size 1.27 1.27)
					(thickness 0.15)
				)
			)
		)
		(property "Description" "SMD Chip Resistor, 8.87 kohm, ± 1%, 100 mW, 0402 [1005 Metric], Thick Film, Precision"
			(at 0 0 0)
			(layer "F.Fab")
			(hide yes)
			(effects
				(font
					(size 1.27 1.27)
					(thickness 0.15)
				)
			)
		)
		(property "MPN" "CR0402-FX-8871GLF"
			(at 0 0 0)
			(unlocked yes)
			(layer "F.Fab")
			(hide yes)
			(effects
				(font
					(size 1 1)
					(thickness 0.15)
				)
			)
		)
		(property "Manufacturer" "Bourns"
			(at 0 0 0)
			(unlocked yes)
			(layer "F.Fab")
			(hide yes)
			(effects
				(font
					(size 1 1)
					(thickness 0.15)
				)
			)
		)
		(property "License" "Apache-2.0"
			(at 0 0 0)
			(unlocked yes)
			(layer "F.Fab")
			(hide yes)
			(effects
				(font
					(size 1 1)
					(thickness 0.15)
				)
			)
		)
		(property "Val" "8k87"
			(at 0 0 0)
			(unlocked yes)
			(layer "F.Fab")
			(hide yes)
			(effects
				(font
					(size 1 1)
					(thickness 0.15)
				)
			)
		)
		(property "Tolerance" "1%"
			(at 0 0 0)
			(unlocked yes)
			(layer "F.Fab")
			(hide yes)
			(effects
				(font
					(size 1 1)
					(thickness 0.15)
				)
			)
		)
		(property "Author" "Antmicro"
			(at 0 0 0)
			(unlocked yes)
			(layer "F.Fab")
			(hide yes)
			(effects
				(font
					(size 1 1)
					(thickness 0.15)
				)
			)
		)
		(sheetname "/PD and TB DC-DC/")
		(sheetfile "PD_and_TB_DC_DC.kicad_sch")
		(attr smd)
		(fp_rect
			(start -0.925 -0.47)
			(end 0.925 0.47)
			(stroke
				(width 0.05)
				(type default)
			)
			(fill no)
			(layer "F.CrtYd")
		)
		(fp_rect
			(start -0.5 -0.25)
			(end 0.5 0.25)
			(stroke
				(width 0.15)
				(type solid)
			)
			(fill no)
			(layer "F.Fab")
		)
		(fp_text user "License: Apache-2.0"
			(at -0.95 5.169 0)
			(layer "F.Fab")
			(effects
				(font
					(size 0.7 0.7)
					(thickness 0.15)
				)
				(justify left bottom)
			)
		)
		(fp_text user "Author: Antmicro"
			(at -0.95 4.169 0)
			(layer "F.Fab")
			(effects
				(font
					(size 0.7 0.7)
					(thickness 0.15)
				)
				(justify left bottom)
			)
		)
		(fp_text user "${REFERENCE}"
			(at -0.95 3.168 0)
			(layer "F.Fab")
			(effects
				(font
					(size 0.7 0.7)
					(thickness 0.15)
				)
				(justify left bottom)
			)
		)
		(pad "1" smd roundrect
			(at -0.48 0)
			(size 0.59 0.64)
			(layers "F.Cu" "F.Mask" "F.Paste")
			(roundrect_rratio 0.25)
			(net 23 "GND")
			(pintype "passive")
		)
		(pad "2" smd roundrect
			(at 0.48 0)
			(size 0.59 0.64)
			(layers "F.Cu" "F.Mask" "F.Paste")
			(roundrect_rratio 0.25)
			(net 166 "Net-(U2-FB)")
			(pintype "passive")
		)
	)
	(footprint "antmicro-footprints:R_0402_1005Metric"
		(layer "F.Cu")
		(at 142.31 95.674999 180)
		(descr "Resistor SMD 0402")
		(tags "resistor SMD 0402")
		(property "Reference" "R178"
			(at -2.190001 -0.025001 180)
			(layer "F.SilkS")
			(effects
				(font
					(size 0.7 0.7)
					(thickness 0.15)
				)
			)
		)
		(property "Value" "R_22R_0402"
			(at -1.011843 1.772047 180)
			(layer "F.Fab")
			(effects
				(font
					(size 0.7 0.7)
					(thickness 0.15)
				)
				(justify left bottom)
			)
		)
		(property "Datasheet" "https://www.bourns.com/docs/product-datasheets/cr.pdf"
			(at 0 0 180)
			(layer "F.Fab")
			(hide yes)
			(effects
				(font
					(size 1.27 1.27)
					(thickness 0.15)
				)
			)
		)
		(property "Description" "SMD Chip Resistor, 22 ohm, ± 1%, 62.5 mW, 0402 [1005 Metric], Thick Film, General Purpose"
			(at 0 0 180)
			(layer "F.Fab")
			(hide yes)
			(effects
				(font
					(size 1.27 1.27)
					(thickness 0.15)
				)
			)
		)
		(property "MPN" "CR0402-FX-22R0GLF"
			(at 0 0 180)
			(unlocked yes)
			(layer "F.Fab")
			(hide yes)
			(effects
				(font
					(size 1 1)
					(thickness 0.15)
				)
			)
		)
		(property "Manufacturer" "Bourns"
			(at 0 0 180)
			(unlocked yes)
			(layer "F.Fab")
			(hide yes)
			(effects
				(font
					(size 1 1)
					(thickness 0.15)
				)
			)
		)
		(property "License" "Apache-2.0"
			(at 0 0 180)
			(unlocked yes)
			(layer "F.Fab")
			(hide yes)
			(effects
				(font
					(size 1 1)
					(thickness 0.15)
				)
			)
		)
		(property "Author" "Antmicro"
			(at 0 0 180)
			(unlocked yes)
			(layer "F.Fab")
			(hide yes)
			(effects
				(font
					(size 1 1)
					(thickness 0.15)
				)
			)
		)
		(property "Val" "22R"
			(at 0 0 180)
			(unlocked yes)
			(layer "F.Fab")
			(hide yes)
			(effects
				(font
					(size 1 1)
					(thickness 0.15)
				)
			)
		)
		(property "Tolerance" "1%"
			(at 0 0 180)
			(unlocked yes)
			(layer "F.Fab")
			(hide yes)
			(effects
				(font
					(size 1 1)
					(thickness 0.15)
				)
			)
		)
		(sheetname "/X710-AT2 Misc/")
		(sheetfile "x710-at2-mics.kicad_sch")
		(attr smd)
		(fp_rect
			(start -0.925 -0.47)
			(end 0.925 0.47)
			(stroke
				(width 0.05)
				(type default)
			)
			(fill no)
			(layer "F.CrtYd")
		)
		(fp_rect
			(start -0.5 -0.25)
			(end 0.5 0.25)
			(stroke
				(width 0.15)
				(type solid)
			)
			(fill no)
			(layer "F.Fab")
		)
		(fp_text user "License: Apache-2.0"
			(at -0.95 5.169 180)
			(layer "F.Fab")
			(effects
				(font
					(size 0.7 0.7)
					(thickness 0.15)
				)
				(justify left bottom)
			)
		)
		(fp_text user "Author: Antmicro"
			(at -0.95 4.169 180)
			(layer "F.Fab")
			(effects
				(font
					(size 0.7 0.7)
					(thickness 0.15)
				)
				(justify left bottom)
			)
		)
		(fp_text user "${REFERENCE}"
			(at -0.95 3.168 180)
			(layer "F.Fab")
			(effects
				(font
					(size 0.7 0.7)
					(thickness 0.15)
				)
				(justify left bottom)
			)
		)
		(pad "1" smd roundrect
			(at -0.48 0 180)
			(size 0.59 0.64)
			(layers "F.Cu" "F.Mask" "F.Paste")
			(roundrect_rratio 0.25)
			(net 81 "/X710-AT2 Misc/FLSH_SCK")
			(pintype "passive")
		)
		(pad "2" smd roundrect
			(at 0.48 0 180)
			(size 0.59 0.64)
			(layers "F.Cu" "F.Mask" "F.Paste")
			(roundrect_rratio 0.25)
			(net 353 "/X710 flash memory/FLASH.CLK")
			(pintype "passive")
		)
	)
	(footprint "antmicro-footprints:MP_Pad6mm_Drill3.2mm"
		(layer "F.Cu")
		(at 180 50)
		(property "Reference" "MP3"
			(at -1 -3.6 0)
			(layer "F.SilkS")
			(effects
				(font
					(size 0.7 0.7)
					(thickness 0.15)
				)
				(justify left bottom)
			)
		)
		(property "Value" "MP_Pad6mm_Drill3.2mm"
			(at 0 3.9 0)
			(layer "F.Fab")
			(effects
				(font
					(size 0.7 0.7)
					(thickness 0.15)
				)
				(justify left bottom)
			)
		)
		(property "Description" "Mechanical part"
			(at 0 0 0)
			(layer "F.Fab")
			(hide yes)
			(effects
				(font
					(size 1.27 1.27)
					(thickness 0.15)
				)
			)
		)
		(property "Author" "Antmicro"
			(at 0 0 0)
			(unlocked yes)
			(layer "F.Fab")
			(hide yes)
			(effects
				(font
					(size 1 1)
					(thickness 0.15)
				)
			)
		)
		(property "License" "Apache-2.0"
			(at 0 0 0)
			(unlocked yes)
			(layer "F.Fab")
			(hide yes)
			(effects
				(font
					(size 1 1)
					(thickness 0.15)
				)
			)
		)
		(sheetname "/")
		(sheetfile "thunderbolt-to-10gbe-adapter.kicad_sch")
		(attr exclude_from_pos_files exclude_from_bom)
		(fp_circle
			(center 0 0)
			(end 3.25 0)
			(stroke
				(width 0.05)
				(type default)
			)
			(fill no)
			(layer "F.CrtYd")
		)
		(fp_text user "License: Apache-2.0"
			(at -0.178 8.425 0)
			(layer "F.Fab")
			(effects
				(font
					(size 0.7 0.7)
					(thickness 0.15)
				)
				(justify left bottom)
			)
		)
		(fp_text user "Author: Antmicro"
			(at -0.178 7.225 0)
			(layer "F.Fab")
			(effects
				(font
					(size 0.7 0.7)
					(thickness 0.15)
				)
				(justify left bottom)
			)
		)
		(fp_text user "${REFERENCE}"
			(at -0.178 6.025 0)
			(layer "F.Fab")
			(effects
				(font
					(size 0.7 0.7)
					(thickness 0.15)
				)
				(justify left bottom)
			)
		)
		(pad "1" thru_hole circle
			(at 0 0)
			(size 6 6)
			(drill 3.2)
			(layers "*.Cu" "*.Mask")
			(remove_unused_layers no)
			(net 23 "GND")
			(pintype "passive")
		)
	)
	(footprint "antmicro-footprints:R_0402_1005Metric"
		(layer "F.Cu")
		(at 138 70.2)
		(descr "Resistor SMD 0402")
		(tags "resistor SMD 0402")
		(property "Reference" "RT1"
			(at -1.8 -0.6 0)
			(layer "F.SilkS")
			(effects
				(font
					(size 0.7 0.7)
					(thickness 0.15)
				)
				(justify left bottom)
			)
		)
		(property "Value" "RT_NTC_10k_0402"
			(at -1.011843 1.772047 0)
			(layer "F.Fab")
			(effects
				(font
					(size 0.7 0.7)
					(thickness 0.15)
				)
				(justify left bottom)
			)
		)
		(property "Datasheet" "https://eu.mouser.com/datasheet/2/281/r44e-522712.pdf"
			(at 0 0 0)
			(layer "F.Fab")
			(hide yes)
			(effects
				(font
					(size 1.27 1.27)
					(thickness 0.15)
				)
			)
		)
		(property "Description" "10k NTC in 0402 package with 5V max voltage"
			(at 0 0 0)
			(layer "F.Fab")
			(hide yes)
			(effects
				(font
					(size 1.27 1.27)
					(thickness 0.15)
				)
			)
		)
		(property "MPN" "NCP15XH103F03RC"
			(at 0 0 0)
			(unlocked yes)
			(layer "F.Fab")
			(hide yes)
			(effects
				(font
					(size 1 1)
					(thickness 0.15)
				)
			)
		)
		(property "Manufacturer" "Murata"
			(at 0 0 0)
			(unlocked yes)
			(layer "F.Fab")
			(hide yes)
			(effects
				(font
					(size 1 1)
					(thickness 0.15)
				)
			)
		)
		(property "License" "Apache-2.0"
			(at 0 0 0)
			(unlocked yes)
			(layer "F.Fab")
			(hide yes)
			(effects
				(font
					(size 1 1)
					(thickness 0.15)
				)
			)
		)
		(property "Author" "Antmicro"
			(at 0 0 0)
			(unlocked yes)
			(layer "F.Fab")
			(hide yes)
			(effects
				(font
					(size 1 1)
					(thickness 0.15)
				)
			)
		)
		(property "Val" "10k"
			(at 0 0 0)
			(unlocked yes)
			(layer "F.Fab")
			(hide yes)
			(effects
				(font
					(size 1 1)
					(thickness 0.15)
				)
			)
		)
		(property "Voltage" "5V"
			(at 0 0 0)
			(unlocked yes)
			(layer "F.Fab")
			(hide yes)
			(effects
				(font
					(size 1 1)
					(thickness 0.15)
				)
			)
		)
		(sheetname "/Fan controller/")
		(sheetfile "fan-controller.kicad_sch")
		(attr smd)
		(fp_rect
			(start -0.925 -0.47)
			(end 0.925 0.47)
			(stroke
				(width 0.05)
				(type default)
			)
			(fill no)
			(layer "F.CrtYd")
		)
		(fp_rect
			(start -0.5 -0.25)
			(end 0.5 0.25)
			(stroke
				(width 0.15)
				(type solid)
			)
			(fill no)
			(layer "F.Fab")
		)
		(fp_text user "License: Apache-2.0"
			(at -0.95 5.169 0)
			(layer "F.Fab")
			(effects
				(font
					(size 0.7 0.7)
					(thickness 0.15)
				)
				(justify left bottom)
			)
		)
		(fp_text user "Author: Antmicro"
			(at -0.95 4.169 0)
			(layer "F.Fab")
			(effects
				(font
					(size 0.7 0.7)
					(thickness 0.15)
				)
				(justify left bottom)
			)
		)
		(fp_text user "${REFERENCE}"
			(at -0.95 3.168 0)
			(layer "F.Fab")
			(effects
				(font
					(size 0.7 0.7)
					(thickness 0.15)
				)
				(justify left bottom)
			)
		)
		(pad "1" smd roundrect
			(at -0.48 0)
			(size 0.59 0.64)
			(layers "F.Cu" "F.Mask" "F.Paste")
			(roundrect_rratio 0.25)
			(net 446 "Net-(R216-Pad1)")
			(pintype "passive")
		)
		(pad "2" smd roundrect
			(at 0.48 0)
			(size 0.59 0.64)
			(layers "F.Cu" "F.Mask" "F.Paste")
			(roundrect_rratio 0.25)
			(net 23 "GND")
			(pintype "passive")
		)
	)
	(footprint "antmicro-footprints:C_0402_1005Metric"
		(layer "F.Cu")
		(at 165.304999 99.204999 -90)
		(descr "Capacitor SMD 0402")
		(tags "capacitor SMD 0402")
		(property "Reference" "C164"
			(at 0 -7.695 270)
			(layer "F.SilkS")
			(effects
				(font
					(size 0.7 0.7)
					(thickness 0.15)
				)
			)
		)
		(property "Value" "C_100n_0402"
			(at -1.022927 2.155213 270)
			(layer "F.Fab")
			(effects
				(font
					(size 0.7 0.7)
					(thickness 0.15)
				)
				(justify left bottom)
			)
		)
		(property "Datasheet" "https://www.murata.com/products/productdetail?partno=GRM155R61H104KE14%23"
			(at 0 0 270)
			(layer "F.Fab")
			(hide yes)
			(effects
				(font
					(size 1.27 1.27)
					(thickness 0.15)
				)
			)
		)
		(property "Description" "SMD Multilayer Ceramic Capacitor, 0.1 µF, 50 V, 0402 [1005 Metric], ± 10%, X5R, GRM Series"
			(at 0 0 270)
			(layer "F.Fab")
			(hide yes)
			(effects
				(font
					(size 1.27 1.27)
					(thickness 0.15)
				)
			)
		)
		(property "MPN" "GRM155R61H104KE14D"
			(at 0 0 270)
			(unlocked yes)
			(layer "F.Fab")
			(hide yes)
			(effects
				(font
					(size 1 1)
					(thickness 0.15)
				)
			)
		)
		(property "Val" "100n"
			(at 0 0 270)
			(unlocked yes)
			(layer "F.Fab")
			(hide yes)
			(effects
				(font
					(size 1 1)
					(thickness 0.15)
				)
			)
		)
		(property "Voltage" "50V"
			(at 0 0 270)
			(unlocked yes)
			(layer "F.Fab")
			(hide yes)
			(effects
				(font
					(size 1 1)
					(thickness 0.15)
				)
			)
		)
		(property "Dielectric" "X5R"
			(at 0 0 270)
			(unlocked yes)
			(layer "F.Fab")
			(hide yes)
			(effects
				(font
					(size 1 1)
					(thickness 0.15)
				)
			)
		)
		(property "Manufacturer" "Murata"
			(at 0 0 270)
			(unlocked yes)
			(layer "F.Fab")
			(hide yes)
			(effects
				(font
					(size 1 1)
					(thickness 0.15)
				)
			)
		)
		(property "License" "Apache-2.0"
			(at 0 0 270)
			(unlocked yes)
			(layer "F.Fab")
			(hide yes)
			(effects
				(font
					(size 1 1)
					(thickness 0.15)
				)
			)
		)
		(property "Author" "Antmicro"
			(at 0 0 270)
			(unlocked yes)
			(layer "F.Fab")
			(hide yes)
			(effects
				(font
					(size 1 1)
					(thickness 0.15)
				)
			)
		)
		(sheetname "/X710-AT2 power/")
		(sheetfile "x710-at2-power.kicad_sch")
		(attr smd)
		(fp_rect
			(start -0.925 -0.47)
			(end 0.925 0.47)
			(stroke
				(width 0.05)
				(type default)
			)
			(fill no)
			(layer "F.CrtYd")
		)
		(fp_line
			(start -0.494 0.248)
			(end -0.494 -0.25)
			(stroke
				(width 0.15)
				(type solid)
			)
			(layer "F.Fab")
		)
		(fp_line
			(start 0.504 0.248)
			(end -0.494 0.248)
			(stroke
				(width 0.15)
				(type solid)
			)
			(layer "F.Fab")
		)
		(fp_line
			(start -0.494 -0.25)
			(end 0.504 -0.25)
			(stroke
				(width 0.15)
				(type solid)
			)
			(layer "F.Fab")
		)
		(fp_line
			(start 0.504 -0.25)
			(end 0.504 0.248)
			(stroke
				(width 0.15)
				(type solid)
			)
			(layer "F.Fab")
		)
		(fp_text user "License: Apache-2.0"
			(at -0.939 5.799 270)
			(layer "F.Fab")
			(effects
				(font
					(size 0.7 0.7)
					(thickness 0.15)
				)
				(justify left bottom)
			)
		)
		(fp_text user "Author: Antmicro"
			(at -0.939 3.399 270)
			(layer "F.Fab")
			(effects
				(font
					(size 0.7 0.7)
					(thickness 0.15)
				)
				(justify left bottom)
			)
		)
		(fp_text user "${REFERENCE}"
			(at -0.939 4.599 270)
			(layer "F.Fab")
			(effects
				(font
					(size 0.7 0.7)
					(thickness 0.15)
				)
				(justify left bottom)
			)
		)
		(pad "1" smd roundrect
			(at -0.48 0 270)
			(size 0.59 0.64)
			(layers "F.Cu" "F.Mask" "F.Paste")
			(roundrect_rratio 0.25)
			(net 23 "GND")
			(pintype "passive")
		)
		(pad "2" smd roundrect
			(at 0.48 0 270)
			(size 0.59 0.64)
			(layers "F.Cu" "F.Mask" "F.Paste")
			(roundrect_rratio 0.25)
			(net 136 "+1V0")
			(pintype "passive")
		)
	)
	(footprint "antmicro-footprints:C_0402_1005Metric"
		(layer "F.Cu")
		(at 138 74.75)
		(descr "Capacitor SMD 0402")
		(tags "capacitor SMD 0402")
		(property "Reference" "C271"
			(at -3.8 0.45 0)
			(layer "F.SilkS")
			(effects
				(font
					(size 0.7 0.7)
					(thickness 0.15)
				)
				(justify left bottom)
			)
		)
		(property "Value" "C_220n_16V_0402"
			(at -1.022927 2.155213 0)
			(layer "F.Fab")
			(effects
				(font
					(size 0.7 0.7)
					(thickness 0.15)
				)
				(justify left bottom)
			)
		)
		(property "Datasheet" "https://www.murata.com/products/productdetail?partno=GRM155R71C224KA12%23"
			(at 0 0 0)
			(layer "F.Fab")
			(hide yes)
			(effects
				(font
					(size 1.27 1.27)
					(thickness 0.15)
				)
			)
		)
		(property "Description" "SMD Multilayer Ceramic Capacitor, 0.22 µF, 16 V, 0402 [1005 Metric], ± 10%, X7R, GRM Series"
			(at 0 0 0)
			(layer "F.Fab")
			(hide yes)
			(effects
				(font
					(size 1.27 1.27)
					(thickness 0.15)
				)
			)
		)
		(property "MPN" "GRM155R71C224KA12D"
			(at 0 0 0)
			(unlocked yes)
			(layer "F.Fab")
			(hide yes)
			(effects
				(font
					(size 1 1)
					(thickness 0.15)
				)
			)
		)
		(property "Manufacturer" "Murata"
			(at 0 0 0)
			(unlocked yes)
			(layer "F.Fab")
			(hide yes)
			(effects
				(font
					(size 1 1)
					(thickness 0.15)
				)
			)
		)
		(property "License" "Apache-2.0"
			(at 0 0 0)
			(unlocked yes)
			(layer "F.Fab")
			(hide yes)
			(effects
				(font
					(size 1 1)
					(thickness 0.15)
				)
			)
		)
		(property "Author" "Antmicro"
			(at 0 0 0)
			(unlocked yes)
			(layer "F.Fab")
			(hide yes)
			(effects
				(font
					(size 1 1)
					(thickness 0.15)
				)
			)
		)
		(property "Val" "220n"
			(at 0 0 0)
			(unlocked yes)
			(layer "F.Fab")
			(hide yes)
			(effects
				(font
					(size 1 1)
					(thickness 0.15)
				)
			)
		)
		(property "Voltage" "16V"
			(at 0 0 0)
			(unlocked yes)
			(layer "F.Fab")
			(hide yes)
			(effects
				(font
					(size 1 1)
					(thickness 0.15)
				)
			)
		)
		(property "Dielectric" "X7R"
			(at 0 0 0)
			(unlocked yes)
			(layer "F.Fab")
			(hide yes)
			(effects
				(font
					(size 1 1)
					(thickness 0.15)
				)
			)
		)
		(sheetname "/X710-AT2 PCIe/")
		(sheetfile "x710-at2-pcie.kicad_sch")
		(attr smd)
		(fp_rect
			(start -0.925 -0.47)
			(end 0.925 0.47)
			(stroke
				(width 0.05)
				(type default)
			)
			(fill no)
			(layer "F.CrtYd")
		)
		(fp_line
			(start -0.494 -0.25)
			(end 0.504 -0.25)
			(stroke
				(width 0.15)
				(type solid)
			)
			(layer "F.Fab")
		)
		(fp_line
			(start -0.494 0.248)
			(end -0.494 -0.25)
			(stroke
				(width 0.15)
				(type solid)
			)
			(layer "F.Fab")
		)
		(fp_line
			(start 0.504 -0.25)
			(end 0.504 0.248)
			(stroke
				(width 0.15)
				(type solid)
			)
			(layer "F.Fab")
		)
		(fp_line
			(start 0.504 0.248)
			(end -0.494 0.248)
			(stroke
				(width 0.15)
				(type solid)
			)
			(layer "F.Fab")
		)
		(fp_text user "License: Apache-2.0"
			(at -0.939 5.799 0)
			(layer "F.Fab")
			(effects
				(font
					(size 0.7 0.7)
					(thickness 0.15)
				)
				(justify left bottom)
			)
		)
		(fp_text user "${REFERENCE}"
			(at -0.939 4.599 0)
			(layer "F.Fab")
			(effects
				(font
					(size 0.7 0.7)
					(thickness 0.15)
				)
				(justify left bottom)
			)
		)
		(fp_text user "Author: Antmicro"
			(at -0.939 3.399 0)
			(layer "F.Fab")
			(effects
				(font
					(size 0.7 0.7)
					(thickness 0.15)
				)
				(justify left bottom)
			)
		)
		(pad "1" smd roundrect
			(at -0.48 0)
			(size 0.59 0.64)
			(layers "F.Cu" "F.Mask" "F.Paste")
			(roundrect_rratio 0.25)
			(net 600 "/TB Controller/PCIex4.TX1+")
			(pintype "passive")
		)
		(pad "2" smd roundrect
			(at 0.48 0)
			(size 0.59 0.64)
			(layers "F.Cu" "F.Mask" "F.Paste")
			(roundrect_rratio 0.25)
			(net 29 "/X710-AT2 PCIe/PCIe_{x4}_AC.TX1+")
			(pintype "passive")
		)
	)
	(footprint "antmicro-footprints:R_0402_1005Metric"
		(layer "F.Cu")
		(at 159.105 67.125 -90)
		(descr "Resistor SMD 0402")
		(tags "resistor SMD 0402")
		(property "Reference" "R188"
			(at -12.324999 -20.295 270)
			(layer "F.SilkS")
			(effects
				(font
					(size 0.7 0.7)
					(thickness 0.15)
				)
			)
		)
		(property "Value" "R_22R_0402"
			(at -1.011843 1.772047 270)
			(layer "F.Fab")
			(effects
				(font
					(size 0.7 0.7)
					(thickness 0.15)
				)
				(justify left bottom)
			)
		)
		(property "Datasheet" "https://www.bourns.com/docs/product-datasheets/cr.pdf"
			(at 0 0 270)
			(layer "F.Fab")
			(hide yes)
			(effects
				(font
					(size 1.27 1.27)
					(thickness 0.15)
				)
			)
		)
		(property "Description" "SMD Chip Resistor, 22 ohm, ± 1%, 62.5 mW, 0402 [1005 Metric], Thick Film, General Purpose"
			(at 0 0 270)
			(layer "F.Fab")
			(hide yes)
			(effects
				(font
					(size 1.27 1.27)
					(thickness 0.15)
				)
			)
		)
		(property "MPN" "CR0402-FX-22R0GLF"
			(at 0 0 270)
			(unlocked yes)
			(layer "F.Fab")
			(hide yes)
			(effects
				(font
					(size 1 1)
					(thickness 0.15)
				)
			)
		)
		(property "Manufacturer" "Bourns"
			(at 0 0 270)
			(unlocked yes)
			(layer "F.Fab")
			(hide yes)
			(effects
				(font
					(size 1 1)
					(thickness 0.15)
				)
			)
		)
		(property "License" "Apache-2.0"
			(at 0 0 270)
			(unlocked yes)
			(layer "F.Fab")
			(hide yes)
			(effects
				(font
					(size 1 1)
					(thickness 0.15)
				)
			)
		)
		(property "Author" "Antmicro"
			(at 0 0 270)
			(unlocked yes)
			(layer "F.Fab")
			(hide yes)
			(effects
				(font
					(size 1 1)
					(thickness 0.15)
				)
			)
		)
		(property "Val" "22R"
			(at 0 0 270)
			(unlocked yes)
			(layer "F.Fab")
			(hide yes)
			(effects
				(font
					(size 1 1)
					(thickness 0.15)
				)
			)
		)
		(property "Tolerance" "1%"
			(at 0 0 270)
			(unlocked yes)
			(layer "F.Fab")
			(hide yes)
			(effects
				(font
					(size 1 1)
					(thickness 0.15)
				)
			)
		)
		(sheetname "/X710-AT2 10GbE/")
		(sheetfile "x710-at2-10gbe.kicad_sch")
		(attr smd)
		(fp_rect
			(start -0.925 -0.47)
			(end 0.925 0.47)
			(stroke
				(width 0.05)
				(type default)
			)
			(fill no)
			(layer "F.CrtYd")
		)
		(fp_rect
			(start -0.5 -0.25)
			(end 0.5 0.25)
			(stroke
				(width 0.15)
				(type solid)
			)
			(fill no)
			(layer "F.Fab")
		)
		(fp_text user "License: Apache-2.0"
			(at -0.95 5.169 270)
			(layer "F.Fab")
			(effects
				(font
					(size 0.7 0.7)
					(thickness 0.15)
				)
				(justify left bottom)
			)
		)
		(fp_text user "Author: Antmicro"
			(at -0.95 4.169 270)
			(layer "F.Fab")
			(effects
				(font
					(size 0.7 0.7)
					(thickness 0.15)
				)
				(justify left bottom)
			)
		)
		(fp_text user "${REFERENCE}"
			(at -0.95 3.168 270)
			(layer "F.Fab")
			(effects
				(font
					(size 0.7 0.7)
					(thickness 0.15)
				)
				(justify left bottom)
			)
		)
		(pad "1" smd roundrect
			(at -0.48 0 270)
			(size 0.59 0.64)
			(layers "F.Cu" "F.Mask" "F.Paste")
			(roundrect_rratio 0.25)
			(net 112 "/X710-AT2 10GbE/25MHZ_OSC_R.+")
			(pintype "passive")
		)
		(pad "2" smd roundrect
			(at 0.48 0 270)
			(size 0.59 0.64)
			(layers "F.Cu" "F.Mask" "F.Paste")
			(roundrect_rratio 0.25)
			(net 25 "/X710-AT2 10GbE/25MHZ_OSC_AC.+")
			(pintype "passive")
		)
	)
	(footprint "antmicro-footprints:VQFN-HR-9_2x1.5mm"
		(layer "F.Cu")
		(at 146.75 110.150001)
		(property "Reference" "U13"
			(at 14.850002 17.049998 0)
			(layer "F.SilkS")
			(effects
				(font
					(size 0.7 0.7)
					(thickness 0.15)
				)
			)
		)
		(property "Value" "TPS566231P"
			(at -1.65 2.15 0)
			(layer "F.Fab")
			(effects
				(font
					(size 0.7 0.7)
					(thickness 0.15)
				)
				(justify left bottom)
			)
		)
		(property "Datasheet" "https://www.ti.com/lit/ds/symlink/tps566231.pdf"
			(at 0 -0.045 0)
			(layer "F.Fab")
			(effects
				(font
					(size 0.7 0.7)
					(thickness 0.15)
				)
				(justify left bottom)
			)
		)
		(property "Description" "Switching Voltage Regulators 3-V to 18-V, 6-A synchronous buck converter"
			(at -1.45 3.65 0)
			(layer "F.Fab")
			(effects
				(font
					(size 0.7 0.7)
					(thickness 0.15)
				)
				(justify left bottom)
			)
		)
		(property "Manufacturer" "Texas Instruments"
			(at 0 0 0)
			(unlocked yes)
			(layer "F.Fab")
			(hide yes)
			(effects
				(font
					(size 1 1)
					(thickness 0.15)
				)
			)
		)
		(property "MPN" "TPS566231PRQFR"
			(at 0 0 0)
			(unlocked yes)
			(layer "F.Fab")
			(hide yes)
			(effects
				(font
					(size 1 1)
					(thickness 0.15)
				)
			)
		)
		(property "Author" "Antmicro"
			(at 0 0 0)
			(unlocked yes)
			(layer "F.Fab")
			(hide yes)
			(effects
				(font
					(size 1 1)
					(thickness 0.15)
				)
			)
		)
		(property "License" "Apache-2.0"
			(at 0 0 0)
			(unlocked yes)
			(layer "F.Fab")
			(hide yes)
			(effects
				(font
					(size 1 1)
					(thickness 0.15)
				)
			)
		)
		(sheetname "/X710 DCDC converters/")
		(sheetfile "DCDC_converters_X710.kicad_sch")
		(attr smd)
		(fp_line
			(start -1 -0.945)
			(end -0.695 -0.945)
			(stroke
				(width 0.15)
				(type solid)
			)
			(layer "F.SilkS")
		)
		(fp_line
			(start -1 0.945)
			(end -0.695 0.945)
			(stroke
				(width 0.15)
				(type solid)
			)
			(layer "F.SilkS")
		)
		(fp_line
			(start 1 -0.945)
			(end 0.695 -0.945)
			(stroke
				(width 0.15)
				(type solid)
			)
			(layer "F.SilkS")
		)
		(fp_line
			(start 1 0.945)
			(end 0.2 0.945)
			(stroke
				(width 0.15)
				(type solid)
			)
			(layer "F.SilkS")
		)
		(fp_circle
			(center -1.18 -0.77)
			(end -1.13 -0.77)
			(stroke
				(width 0.15)
				(type solid)
			)
			(fill yes)
			(layer "F.SilkS")
		)
		(fp_rect
			(start -1.3 -1.05)
			(end 1.3 1.05)
			(stroke
				(width 0.05)
				(type solid)
			)
			(fill no)
			(layer "F.CrtYd")
		)
		(fp_rect
			(start -1 -0.75)
			(end 1 0.75)
			(stroke
				(width 0.15)
				(type solid)
			)
			(fill no)
			(layer "F.Fab")
		)
		(fp_text user "${REFERENCE}"
			(at -1.65 3.35 0)
			(layer "F.Fab")
			(effects
				(font
					(size 0.7 0.7)
					(thickness 0.15)
				)
				(justify left bottom)
			)
		)
		(fp_text user "Author: Antmicro"
			(at -1.65 4.55 0)
			(layer "F.Fab")
			(effects
				(font
					(size 0.7 0.7)
					(thickness 0.15)
				)
				(justify left bottom)
			)
		)
		(fp_text user "License: Apache-2.0"
			(at -1.65 5.75 0)
			(layer "F.Fab")
			(effects
				(font
					(size 0.7 0.7)
					(thickness 0.15)
				)
				(justify left bottom)
			)
		)
		(pad "1" smd roundrect
			(at -0.925 -0.5)
			(size 0.55 0.25)
			(layers "F.Cu" "F.Mask" "F.Paste")
			(roundrect_rratio 0.125)
			(net 116 "/X710 DCDC converters/DVDD_VCC")
			(pinfunction "V_{CC}")
			(pintype "passive")
		)
		(pad "2" smd roundrect
			(at -0.925 0)
			(size 0.55 0.25)
			(layers "F.Cu" "F.Mask" "F.Paste")
			(roundrect_rratio 0.125)
			(net 342 "/X710 DCDC converters/DVDD_FB")
			(pinfunction "FB")
			(pintype "input")
		)
		(pad "3" smd roundrect
			(at -0.925 0.5)
			(size 0.55 0.25)
			(layers "F.Cu" "F.Mask" "F.Paste")
			(roundrect_rratio 0.125)
			(net 386 "/X710 DCDC converters/DVDD_EN")
			(pinfunction "EN")
			(pintype "input")
		)
		(pad "4" smd roundrect
			(at -0.25 0.45)
			(size 0.25 1)
			(layers "F.Cu" "F.Mask" "F.Paste")
			(roundrect_rratio 0.125)
			(net 23 "GND")
			(pinfunction "PGND")
			(pintype "power_in")
		)
		(pad "5" smd roundrect
			(at 0.925 0.5)
			(size 0.55 0.25)
			(layers "F.Cu" "F.Mask" "F.Paste")
			(roundrect_rratio 0.125)
			(net 40 "+5V")
			(pinfunction "V_{IN}")
			(pintype "power_in")
		)
		(pad "6" smd roundrect
			(at 0.925 0)
			(size 0.55 0.25)
			(layers "F.Cu" "F.Mask" "F.Paste")
			(roundrect_rratio 0.125)
			(net 40 "+5V")
			(pinfunction "V_{IN}")
			(pintype "passive")
		)
		(pad "7" smd roundrect
			(at 0.925 -0.5)
			(size 0.55 0.25)
			(layers "F.Cu" "F.Mask" "F.Paste")
			(roundrect_rratio 0.125)
			(net 332 "/X710 DCDC converters/DVDD_BST")
			(pinfunction "BST")
			(pintype "passive")
		)
		(pad "8" smd roundrect
			(at 0.25 -0.3)
			(size 0.25 1.3)
			(layers "F.Cu" "F.Mask" "F.Paste")
			(roundrect_rratio 0.125)
			(net 313 "/X710 DCDC converters/DVDD_SW")
			(pinfunction "SW")
			(pintype "power_out")
		)
		(pad "9" smd roundrect
			(at -0.25 -0.675)
			(size 0.25 0.55)
			(layers "F.Cu" "F.Mask" "F.Paste")
			(roundrect_rratio 0.125)
			(net 355 "/X710 DCDC converters/DVDD_PG")
			(pinfunction "PG")
			(pintype "passive")
		)
	)
	(footprint "antmicro-footprints:C_0402_1005Metric"
		(layer "F.Cu")
		(at 168 77 -90)
		(descr "Capacitor SMD 0402")
		(tags "capacitor SMD 0402")
		(property "Reference" "C278"
			(at 3.8 -0.4 270)
			(layer "F.SilkS")
			(effects
				(font
					(size 0.7 0.7)
					(thickness 0.15)
				)
				(justify left bottom)
			)
		)
		(property "Value" "C_100n_0402"
			(at -1.022927 2.155213 270)
			(layer "F.Fab")
			(effects
				(font
					(size 0.7 0.7)
					(thickness 0.15)
				)
				(justify left bottom)
			)
		)
		(property "Datasheet" "https://www.murata.com/products/productdetail?partno=GRM155R61H104KE14%23"
			(at 0 0 270)
			(layer "F.Fab")
			(hide yes)
			(effects
				(font
					(size 1.27 1.27)
					(thickness 0.15)
				)
			)
		)
		(property "Description" "SMD Multilayer Ceramic Capacitor, 0.1 µF, 50 V, 0402 [1005 Metric], ± 10%, X5R, GRM Series"
			(at 0 0 270)
			(layer "F.Fab")
			(hide yes)
			(effects
				(font
					(size 1.27 1.27)
					(thickness 0.15)
				)
			)
		)
		(property "MPN" "GRM155R61H104KE14D"
			(at 0 0 270)
			(unlocked yes)
			(layer "F.Fab")
			(hide yes)
			(effects
				(font
					(size 1 1)
					(thickness 0.15)
				)
			)
		)
		(property "Val" "100n"
			(at 0 0 270)
			(unlocked yes)
			(layer "F.Fab")
			(hide yes)
			(effects
				(font
					(size 1 1)
					(thickness 0.15)
				)
			)
		)
		(property "Voltage" "50V"
			(at 0 0 270)
			(unlocked yes)
			(layer "F.Fab")
			(hide yes)
			(effects
				(font
					(size 1 1)
					(thickness 0.15)
				)
			)
		)
		(property "Dielectric" "X5R"
			(at 0 0 270)
			(unlocked yes)
			(layer "F.Fab")
			(hide yes)
			(effects
				(font
					(size 1 1)
					(thickness 0.15)
				)
			)
		)
		(property "Manufacturer" "Murata"
			(at 0 0 270)
			(unlocked yes)
			(layer "F.Fab")
			(hide yes)
			(effects
				(font
					(size 1 1)
					(thickness 0.15)
				)
			)
		)
		(property "License" "Apache-2.0"
			(at 0 0 270)
			(unlocked yes)
			(layer "F.Fab")
			(hide yes)
			(effects
				(font
					(size 1 1)
					(thickness 0.15)
				)
			)
		)
		(property "Author" "Antmicro"
			(at 0 0 270)
			(unlocked yes)
			(layer "F.Fab")
			(hide yes)
			(effects
				(font
					(size 1 1)
					(thickness 0.15)
				)
			)
		)
		(sheetname "/X710-AT2 Misc/")
		(sheetfile "x710-at2-mics.kicad_sch")
		(attr smd)
		(fp_rect
			(start -0.925 -0.47)
			(end 0.925 0.47)
			(stroke
				(width 0.05)
				(type default)
			)
			(fill no)
			(layer "F.CrtYd")
		)
		(fp_line
			(start -0.494 0.248)
			(end -0.494 -0.25)
			(stroke
				(width 0.15)
				(type solid)
			)
			(layer "F.Fab")
		)
		(fp_line
			(start 0.504 0.248)
			(end -0.494 0.248)
			(stroke
				(width 0.15)
				(type solid)
			)
			(layer "F.Fab")
		)
		(fp_line
			(start -0.494 -0.25)
			(end 0.504 -0.25)
			(stroke
				(width 0.15)
				(type solid)
			)
			(layer "F.Fab")
		)
		(fp_line
			(start 0.504 -0.25)
			(end 0.504 0.248)
			(stroke
				(width 0.15)
				(type solid)
			)
			(layer "F.Fab")
		)
		(fp_text user "${REFERENCE}"
			(at -0.939 4.599 270)
			(layer "F.Fab")
			(effects
				(font
					(size 0.7 0.7)
					(thickness 0.15)
				)
				(justify left bottom)
			)
		)
		(fp_text user "Author: Antmicro"
			(at -0.939 3.399 270)
			(layer "F.Fab")
			(effects
				(font
					(size 0.7 0.7)
					(thickness 0.15)
				)
				(justify left bottom)
			)
		)
		(fp_text user "License: Apache-2.0"
			(at -0.939 5.799 270)
			(layer "F.Fab")
			(effects
				(font
					(size 0.7 0.7)
					(thickness 0.15)
				)
				(justify left bottom)
			)
		)
		(pad "1" smd roundrect
			(at -0.48 0 270)
			(size 0.59 0.64)
			(layers "F.Cu" "F.Mask" "F.Paste")
			(roundrect_rratio 0.25)
			(net 23 "GND")
			(pintype "passive")
		)
		(pad "2" smd roundrect
			(at 0.48 0 270)
			(size 0.59 0.64)
			(layers "F.Cu" "F.Mask" "F.Paste")
			(roundrect_rratio 0.25)
			(net 18 "+1V88")
			(pintype "passive")
		)
	)
	(footprint "antmicro-footprints:R_0402_1005Metric"
		(layer "F.Cu")
		(at 127.084 90.309 180)
		(descr "Resistor SMD 0402")
		(tags "resistor SMD 0402")
		(property "Reference" "R119"
			(at 1.084 0.509 180)
			(layer "F.SilkS")
			(effects
				(font
					(size 0.7 0.7)
					(thickness 0.15)
				)
				(justify left bottom)
			)
		)
		(property "Value" "R_8k2_0402"
			(at -1.011843 1.772047 180)
			(layer "F.Fab")
			(effects
				(font
					(size 0.7 0.7)
					(thickness 0.15)
				)
				(justify left bottom)
			)
		)
		(property "Datasheet" "https://www.bourns.com/docs/product-datasheets/cr.pdf"
			(at 0 0 180)
			(layer "F.Fab")
			(hide yes)
			(effects
				(font
					(size 1.27 1.27)
					(thickness 0.15)
				)
			)
		)
		(property "Description" "SMD Chip Resistor"
			(at 0 0 180)
			(layer "F.Fab")
			(hide yes)
			(effects
				(font
					(size 1.27 1.27)
					(thickness 0.15)
				)
			)
		)
		(property "MPN" "CR0402-FX-8201GLF"
			(at 0 0 180)
			(unlocked yes)
			(layer "F.Fab")
			(hide yes)
			(effects
				(font
					(size 1 1)
					(thickness 0.15)
				)
			)
		)
		(property "Manufacturer" "Bourns"
			(at 0 0 180)
			(unlocked yes)
			(layer "F.Fab")
			(hide yes)
			(effects
				(font
					(size 1 1)
					(thickness 0.15)
				)
			)
		)
		(property "License" "Apache-2.0"
			(at 0 0 180)
			(unlocked yes)
			(layer "F.Fab")
			(hide yes)
			(effects
				(font
					(size 1 1)
					(thickness 0.15)
				)
			)
		)
		(property "Author" "Antmicro"
			(at 0 0 180)
			(unlocked yes)
			(layer "F.Fab")
			(hide yes)
			(effects
				(font
					(size 1 1)
					(thickness 0.15)
				)
			)
		)
		(property "Val" "8k2"
			(at 0 0 180)
			(unlocked yes)
			(layer "F.Fab")
			(hide yes)
			(effects
				(font
					(size 1 1)
					(thickness 0.15)
				)
			)
		)
		(property "Tolerance" "1%"
			(at 0 0 180)
			(unlocked yes)
			(layer "F.Fab")
			(hide yes)
			(effects
				(font
					(size 1 1)
					(thickness 0.15)
				)
			)
		)
		(sheetname "/X710-AT2 PCIe/")
		(sheetfile "x710-at2-pcie.kicad_sch")
		(attr smd)
		(fp_rect
			(start -0.925 -0.47)
			(end 0.925 0.47)
			(stroke
				(width 0.05)
				(type default)
			)
			(fill no)
			(layer "F.CrtYd")
		)
		(fp_rect
			(start -0.5 -0.25)
			(end 0.5 0.25)
			(stroke
				(width 0.15)
				(type solid)
			)
			(fill no)
			(layer "F.Fab")
		)
		(fp_text user "License: Apache-2.0"
			(at -0.95 5.169 180)
			(layer "F.Fab")
			(effects
				(font
					(size 0.7 0.7)
					(thickness 0.15)
				)
				(justify left bottom)
			)
		)
		(fp_text user "${REFERENCE}"
			(at -0.95 3.168 180)
			(layer "F.Fab")
			(effects
				(font
					(size 0.7 0.7)
					(thickness 0.15)
				)
				(justify left bottom)
			)
		)
		(fp_text user "Author: Antmicro"
			(at -0.95 4.169 180)
			(layer "F.Fab")
			(effects
				(font
					(size 0.7 0.7)
					(thickness 0.15)
				)
				(justify left bottom)
			)
		)
		(pad "1" smd roundrect
			(at -0.48 0 180)
			(size 0.59 0.64)
			(layers "F.Cu" "F.Mask" "F.Paste")
			(roundrect_rratio 0.25)
			(net 23 "GND")
			(pintype "passive")
		)
		(pad "2" smd roundrect
			(at 0.48 0 180)
			(size 0.59 0.64)
			(layers "F.Cu" "F.Mask" "F.Paste")
			(roundrect_rratio 0.25)
			(net 16 "/X710-AT2 PCIe/PCIe_JTAG.JTCK")
			(pintype "passive")
		)
	)
	(footprint "antmicro-footprints:C_0402_1005Metric"
		(layer "F.Cu")
		(at 136.15 109.150001)
		(descr "Capacitor SMD 0402")
		(tags "capacitor SMD 0402")
		(property "Reference" "C120"
			(at 16.549997 17.25 0)
			(layer "F.SilkS")
			(effects
				(font
					(size 0.7 0.7)
					(thickness 0.15)
				)
			)
		)
		(property "Value" "C_1u_25V_0402"
			(at -1.022927 2.155213 0)
			(layer "F.Fab")
			(effects
				(font
					(size 0.7 0.7)
					(thickness 0.15)
				)
				(justify left bottom)
			)
		)
		(property "Datasheet" "https://www.murata.com/products/productdetail?partno=GRM155R61E105KE11%23"
			(at 0 0 0)
			(layer "F.Fab")
			(hide yes)
			(effects
				(font
					(size 1.27 1.27)
					(thickness 0.15)
				)
			)
		)
		(property "Description" "SMD Multilayer Ceramic Capacitor, 1 µF, 25 V, 0402 [1005 Metric], ± 10%, X5R, GRM Series"
			(at 0 0 0)
			(layer "F.Fab")
			(hide yes)
			(effects
				(font
					(size 1.27 1.27)
					(thickness 0.15)
				)
			)
		)
		(property "MPN" "GRM155R61E105KE11J"
			(at 0 0 0)
			(unlocked yes)
			(layer "F.Fab")
			(hide yes)
			(effects
				(font
					(size 1 1)
					(thickness 0.15)
				)
			)
		)
		(property "Manufacturer" "Murata"
			(at 0 0 0)
			(unlocked yes)
			(layer "F.Fab")
			(hide yes)
			(effects
				(font
					(size 1 1)
					(thickness 0.15)
				)
			)
		)
		(property "License" "Apache-2.0"
			(at 0 0 0)
			(unlocked yes)
			(layer "F.Fab")
			(hide yes)
			(effects
				(font
					(size 1 1)
					(thickness 0.15)
				)
			)
		)
		(property "Author" "Antmicro"
			(at 0 0 0)
			(unlocked yes)
			(layer "F.Fab")
			(hide yes)
			(effects
				(font
					(size 1 1)
					(thickness 0.15)
				)
			)
		)
		(property "Val" "1u"
			(at 0 0 0)
			(unlocked yes)
			(layer "F.Fab")
			(hide yes)
			(effects
				(font
					(size 1 1)
					(thickness 0.15)
				)
			)
		)
		(property "Voltage" "25V"
			(at 0 0 0)
			(unlocked yes)
			(layer "F.Fab")
			(hide yes)
			(effects
				(font
					(size 1 1)
					(thickness 0.15)
				)
			)
		)
		(property "Dielectric" "X5R"
			(at 0 0 0)
			(unlocked yes)
			(layer "F.Fab")
			(hide yes)
			(effects
				(font
					(size 1 1)
					(thickness 0.15)
				)
			)
		)
		(sheetname "/X710 DCDC converters/")
		(sheetfile "DCDC_converters_X710.kicad_sch")
		(attr smd)
		(fp_rect
			(start -0.925 -0.47)
			(end 0.925 0.47)
			(stroke
				(width 0.05)
				(type default)
			)
			(fill no)
			(layer "F.CrtYd")
		)
		(fp_line
			(start -0.494 -0.25)
			(end 0.504 -0.25)
			(stroke
				(width 0.15)
				(type solid)
			)
			(layer "F.Fab")
		)
		(fp_line
			(start -0.494 0.248)
			(end -0.494 -0.25)
			(stroke
				(width 0.15)
				(type solid)
			)
			(layer "F.Fab")
		)
		(fp_line
			(start 0.504 -0.25)
			(end 0.504 0.248)
			(stroke
				(width 0.15)
				(type solid)
			)
			(layer "F.Fab")
		)
		(fp_line
			(start 0.504 0.248)
			(end -0.494 0.248)
			(stroke
				(width 0.15)
				(type solid)
			)
			(layer "F.Fab")
		)
		(fp_text user "License: Apache-2.0"
			(at -0.939 5.799 0)
			(layer "F.Fab")
			(effects
				(font
					(size 0.7 0.7)
					(thickness 0.15)
				)
				(justify left bottom)
			)
		)
		(fp_text user "${REFERENCE}"
			(at -0.939 4.599 0)
			(layer "F.Fab")
			(effects
				(font
					(size 0.7 0.7)
					(thickness 0.15)
				)
				(justify left bottom)
			)
		)
		(fp_text user "Author: Antmicro"
			(at -0.939 3.399 0)
			(layer "F.Fab")
			(effects
				(font
					(size 0.7 0.7)
					(thickness 0.15)
				)
				(justify left bottom)
			)
		)
		(pad "1" smd roundrect
			(at -0.48 0)
			(size 0.59 0.64)
			(layers "F.Cu" "F.Mask" "F.Paste")
			(roundrect_rratio 0.25)
			(net 23 "GND")
			(pintype "passive")
		)
		(pad "2" smd roundrect
			(at 0.48 0)
			(size 0.59 0.64)
			(layers "F.Cu" "F.Mask" "F.Paste")
			(roundrect_rratio 0.25)
			(net 83 "/X710 DCDC converters/VCCD_VCC")
			(pintype "passive")
		)
	)
	(footprint "antmicro-footprints:R_0402_1005Metric"
		(layer "F.Cu")
		(at 119.25 67.5 180)
		(descr "Resistor SMD 0402")
		(tags "resistor SMD 0402")
		(property "Reference" "R136"
			(at -3.45 -1.4 180)
			(layer "F.SilkS")
			(effects
				(font
					(size 0.7 0.7)
					(thickness 0.15)
				)
				(justify left bottom)
			)
		)
		(property "Value" "R_10k_0402"
			(at -1.011843 1.772047 180)
			(layer "F.Fab")
			(effects
				(font
					(size 0.7 0.7)
					(thickness 0.15)
				)
				(justify left bottom)
			)
		)
		(property "Datasheet" "https://www.bourns.com/docs/product-datasheets/cr.pdf"
			(at 0 0 180)
			(layer "F.Fab")
			(hide yes)
			(effects
				(font
					(size 1.27 1.27)
					(thickness 0.15)
				)
			)
		)
		(property "Description" "SMD Chip Resistor, 10 kohm, ± 1%, 62.5 mW, 0402 [1005 Metric], Thick Film, General Purpose"
			(at 0 0 180)
			(layer "F.Fab")
			(hide yes)
			(effects
				(font
					(size 1.27 1.27)
					(thickness 0.15)
				)
			)
		)
		(property "MPN" "CR0402-FX-1002GLF"
			(at 0 0 180)
			(unlocked yes)
			(layer "F.Fab")
			(hide yes)
			(effects
				(font
					(size 1 1)
					(thickness 0.15)
				)
			)
		)
		(property "Manufacturer" "Bourns"
			(at 0 0 180)
			(unlocked yes)
			(layer "F.Fab")
			(hide yes)
			(effects
				(font
					(size 1 1)
					(thickness 0.15)
				)
			)
		)
		(property "License" "Apache-2.0"
			(at 0 0 180)
			(unlocked yes)
			(layer "F.Fab")
			(hide yes)
			(effects
				(font
					(size 1 1)
					(thickness 0.15)
				)
			)
		)
		(property "Author" "Antmicro"
			(at 0 0 180)
			(unlocked yes)
			(layer "F.Fab")
			(hide yes)
			(effects
				(font
					(size 1 1)
					(thickness 0.15)
				)
			)
		)
		(property "Val" "10k"
			(at 0 0 180)
			(unlocked yes)
			(layer "F.Fab")
			(hide yes)
			(effects
				(font
					(size 1 1)
					(thickness 0.15)
				)
			)
		)
		(property "Tolerance" "1%"
			(at 0 0 180)
			(unlocked yes)
			(layer "F.Fab")
			(hide yes)
			(effects
				(font
					(size 1 1)
					(thickness 0.15)
				)
			)
		)
		(sheetname "/X710-AT2 RSVD/")
		(sheetfile "x710-at2-rsvd.kicad_sch")
		(attr smd)
		(fp_rect
			(start -0.925 -0.47)
			(end 0.925 0.47)
			(stroke
				(width 0.05)
				(type default)
			)
			(fill no)
			(layer "F.CrtYd")
		)
		(fp_rect
			(start -0.5 -0.25)
			(end 0.5 0.25)
			(stroke
				(width 0.15)
				(type solid)
			)
			(fill no)
			(layer "F.Fab")
		)
		(fp_text user "${REFERENCE}"
			(at -0.95 3.168 180)
			(layer "F.Fab")
			(effects
				(font
					(size 0.7 0.7)
					(thickness 0.15)
				)
				(justify left bottom)
			)
		)
		(fp_text user "Author: Antmicro"
			(at -0.95 4.169 180)
			(layer "F.Fab")
			(effects
				(font
					(size 0.7 0.7)
					(thickness 0.15)
				)
				(justify left bottom)
			)
		)
		(fp_text user "License: Apache-2.0"
			(at -0.95 5.169 180)
			(layer "F.Fab")
			(effects
				(font
					(size 0.7 0.7)
					(thickness 0.15)
				)
				(justify left bottom)
			)
		)
		(pad "1" smd roundrect
			(at -0.48 0 180)
			(size 0.59 0.64)
			(layers "F.Cu" "F.Mask" "F.Paste")
			(roundrect_rratio 0.25)
			(net 23 "GND")
			(pintype "passive")
		)
		(pad "2" smd roundrect
			(at 0.48 0 180)
			(size 0.59 0.64)
			(layers "F.Cu" "F.Mask" "F.Paste")
			(roundrect_rratio 0.25)
			(net 91 "/X710-AT2 RSVD/DEBUG_Y16")
			(pintype "passive")
		)
	)
	(footprint "antmicro-footprints:D_SOD-123"
		(layer "F.Cu")
		(at 127.8 57.2 -90)
		(property "Reference" "D15"
			(at -1.2 2 90)
			(layer "F.SilkS")
			(effects
				(font
					(size 0.7 0.7)
					(thickness 0.15)
				)
				(justify right top)
			)
		)
		(property "Value" "PTVS26VS1UR,115"
			(at 0 1.95 90)
			(layer "F.Fab")
			(effects
				(font
					(size 0.7 0.7)
					(thickness 0.15)
				)
				(justify right top)
			)
		)
		(property "Datasheet" "https://www.mouser.com/datasheet/2/916/PTVSXS1UR_SER-1545507.pdf"
			(at 0 0 90)
			(layer "F.Fab")
			(hide yes)
			(effects
				(font
					(size 1.27 1.27)
					(thickness 0.15)
				)
			)
		)
		(property "Description" "Unidirectional TVS, 8 kV,  SOD-123F, 26 V, 400 W"
			(at 0 0 90)
			(layer "F.Fab")
			(hide yes)
			(effects
				(font
					(size 1.27 1.27)
					(thickness 0.15)
				)
			)
		)
		(property "Author" "Antmicro"
			(at 0 0 270)
			(unlocked yes)
			(layer "F.Fab")
			(hide yes)
			(effects
				(font
					(size 1 1)
					(thickness 0.15)
				)
			)
		)
		(property "License" "Apache-2.0"
			(at 0 0 270)
			(unlocked yes)
			(layer "F.Fab")
			(hide yes)
			(effects
				(font
					(size 1 1)
					(thickness 0.15)
				)
			)
		)
		(property "Manufacturer" "Nexperia"
			(at 0 0 270)
			(unlocked yes)
			(layer "F.Fab")
			(hide yes)
			(effects
				(font
					(size 1 1)
					(thickness 0.15)
				)
			)
		)
		(property "MPN" "PTVS26VS1UR,115"
			(at 0 0 270)
			(unlocked yes)
			(layer "F.Fab")
			(hide yes)
			(effects
				(font
					(size 1 1)
					(thickness 0.15)
				)
			)
		)
		(sheetname "/Power input/")
		(sheetfile "power_input.kicad_sch")
		(attr smd)
		(fp_line
			(start 1.1 0.8875)
			(end 1.45 0.8875)
			(stroke
				(width 0.15)
				(type solid)
			)
			(layer "F.SilkS")
		)
		(fp_line
			(start -1.45 0.8625)
			(end -1.45 0.5875)
			(stroke
				(width 0.15)
				(type solid)
			)
			(layer "F.SilkS")
		)
		(fp_line
			(start -1.1 0.8625)
			(end -1.45 0.8625)
			(stroke
				(width 0.15)
				(type solid)
			)
			(layer "F.SilkS")
		)
		(fp_line
			(start 1.45 0.6125)
			(end 1.45 0.8875)
			(stroke
				(width 0.15)
				(type solid)
			)
			(layer "F.SilkS")
		)
		(fp_line
			(start -0.925 -0.5)
			(end -0.925 0.5)
			(stroke
				(width 0.15)
				(type solid)
			)
			(layer "F.SilkS")
		)
		(fp_line
			(start -1.45 -0.6)
			(end -1.45 -0.875)
			(stroke
				(width 0.15)
				(type solid)
			)
			(layer "F.SilkS")
		)
		(fp_line
			(start -1.1 -0.875)
			(end -1.45 -0.875)
			(stroke
				(width 0.15)
				(type solid)
			)
			(layer "F.SilkS")
		)
		(fp_line
			(start 1.1 -0.875)
			(end 1.45 -0.875)
			(stroke
				(width 0.15)
				(type solid)
			)
			(layer "F.SilkS")
		)
		(fp_line
			(start 1.45 -0.875)
			(end 1.45 -0.6)
			(stroke
				(width 0.15)
				(type solid)
			)
			(layer "F.SilkS")
		)
		(fp_rect
			(start -2.275 -1.05)
			(end 2.275 1.05)
			(stroke
				(width 0.05)
				(type solid)
			)
			(fill no)
			(layer "F.CrtYd")
		)
		(fp_line
			(start -1.325 0.848)
			(end 1.324 0.848)
			(stroke
				(width 0.15)
				(type solid)
			)
			(layer "F.Fab")
		)
		(fp_line
			(start -1.325 -0.85)
			(end -1.325 0.848)
			(stroke
				(width 0.15)
				(type solid)
			)
			(layer "F.Fab")
		)
		(fp_line
			(start -1.325 -0.85)
			(end 1.324 -0.85)
			(stroke
				(width 0.15)
				(type solid)
			)
			(layer "F.Fab")
		)
		(fp_line
			(start 1.324 -0.85)
			(end 1.324 0.848)
			(stroke
				(width 0.15)
				(type solid)
			)
			(layer "F.Fab")
		)
		(fp_text user "Author: Antmicro"
			(at -2.36 4.6 90)
			(layer "F.Fab")
			(effects
				(font
					(size 0.7 0.7)
					(thickness 0.15)
				)
				(justify right top)
			)
		)
		(fp_text user "${REFERENCE}"
			(at -2.36 3.3 90)
			(layer "F.Fab")
			(effects
				(font
					(size 0.7 0.7)
					(thickness 0.15)
				)
				(justify right top)
			)
		)
		(fp_text user "License: Apache-2.0"
			(at -2.36 5.85 90)
			(layer "F.Fab")
			(effects
				(font
					(size 0.7 0.7)
					(thickness 0.15)
				)
				(justify right top)
			)
		)
		(pad "1" smd roundrect
			(at -1.625 -0.001 270)
			(size 0.9 0.95)
			(layers "F.Cu" "F.Mask" "F.Paste")
			(roundrect_rratio 0.15)
			(net 412 "Net-(D15-C)")
			(pinfunction "C")
			(pintype "passive")
		)
		(pad "2" smd roundrect
			(at 1.625 -0.001 270)
			(size 0.9 0.95)
			(layers "F.Cu" "F.Mask" "F.Paste")
			(roundrect_rratio 0.15)
			(net 23 "GND")
			(pinfunction "A")
			(pintype "passive")
		)
	)
	(footprint "antmicro-footprints:Fiducial_1mm_Mask2mm"
		(layer "F.Cu")
		(at 175 47.5)
		(descr "Circular Fiducial, 1mm bare copper, 3mm soldermask opening")
		(tags "fiducial")
		(property "Reference" "FD3"
			(at -3.6 0.5 0)
			(layer "F.SilkS")
			(effects
				(font
					(size 0.7 0.7)
					(thickness 0.15)
				)
				(justify left bottom)
			)
		)
		(property "Value" "Fiducial_1mm_Mask2mm"
			(at 0 2.2 0)
			(layer "F.Fab")
			(effects
				(font
					(size 0.7 0.7)
					(thickness 0.15)
				)
				(justify left bottom)
			)
		)
		(property "Description" "Fiducial mask"
			(at 0 0 0)
			(layer "F.Fab")
			(hide yes)
			(effects
				(font
					(size 1.27 1.27)
					(thickness 0.15)
				)
			)
		)
		(property "Author" "Antmicro"
			(at 0 0 0)
			(unlocked yes)
			(layer "F.Fab")
			(hide yes)
			(effects
				(font
					(size 1 1)
					(thickness 0.15)
				)
			)
		)
		(property "License" "Apache-2.0"
			(at 0 0 0)
			(unlocked yes)
			(layer "F.Fab")
			(hide yes)
			(effects
				(font
					(size 1 1)
					(thickness 0.15)
				)
			)
		)
		(sheetname "/")
		(sheetfile "thunderbolt-to-10gbe-adapter.kicad_sch")
		(attr exclude_from_pos_files exclude_from_bom)
		(fp_circle
			(center 0 0)
			(end 1.24 0)
			(stroke
				(width 0.05)
				(type solid)
			)
			(fill no)
			(layer "F.CrtYd")
		)
		(fp_circle
			(center 0 0)
			(end 0.999 0)
			(stroke
				(width 0.15)
				(type solid)
			)
			(fill no)
			(layer "F.Fab")
		)
		(fp_text user "${REFERENCE}"
			(at -1.25 4.603 0)
			(layer "F.Fab")
			(effects
				(font
					(size 0.7 0.7)
					(thickness 0.15)
				)
				(justify left bottom)
			)
		)
		(fp_text user "License: Apache-2.0"
			(at -1.25 7.003 0)
			(layer "F.Fab")
			(effects
				(font
					(size 0.7 0.7)
					(thickness 0.15)
				)
				(justify left bottom)
			)
		)
		(fp_text user "Author: Antmicro"
			(at -1.25 5.803 0)
			(layer "F.Fab")
			(effects
				(font
					(size 0.7 0.7)
					(thickness 0.15)
				)
				(justify left bottom)
			)
		)
		(pad "" smd circle
			(at 0 0)
			(size 1 1)
			(layers "F.Cu" "F.Mask")
			(solder_mask_margin 0.5)
			(clearance 0.5)
		)
	)
	(footprint "antmicro-footprints:C_0603_1608Metric"
		(layer "F.Cu")
		(at 154.705001 94.024999 180)
		(descr "Capacitor SMD 0603")
		(tags "capacitor 0603")
		(property "Reference" "C173"
			(at -23.294999 -19.625001 180)
			(layer "F.SilkS")
			(effects
				(font
					(size 0.7 0.7)
					(thickness 0.15)
				)
			)
		)
		(property "Value" "C_10u_10V_X7R_0603"
			(at -1.42757 1.770288 180)
			(layer "F.Fab")
			(effects
				(font
					(size 0.7 0.7)
					(thickness 0.15)
				)
				(justify left bottom)
			)
		)
		(property "Datasheet" "https://www.murata.com/products/productdetail?partno=GRM188Z71A106KA73%23"
			(at 0 0 180)
			(layer "F.Fab")
			(hide yes)
			(effects
				(font
					(size 1.27 1.27)
					(thickness 0.15)
				)
			)
		)
		(property "Description" "SMD Multilayer Ceramic Capacitor,  10µF, 10V, 0603, ±10%, X7R"
			(at 0 0 180)
			(layer "F.Fab")
			(hide yes)
			(effects
				(font
					(size 1.27 1.27)
					(thickness 0.15)
				)
			)
		)
		(property "MPN" "GRM188Z71A106KA73D"
			(at 0 0 180)
			(unlocked yes)
			(layer "F.Fab")
			(hide yes)
			(effects
				(font
					(size 1 1)
					(thickness 0.15)
				)
			)
		)
		(property "Val" "10u"
			(at 0 0 180)
			(unlocked yes)
			(layer "F.Fab")
			(hide yes)
			(effects
				(font
					(size 1 1)
					(thickness 0.15)
				)
			)
		)
		(property "Voltage" "10V"
			(at 0 0 180)
			(unlocked yes)
			(layer "F.Fab")
			(hide yes)
			(effects
				(font
					(size 1 1)
					(thickness 0.15)
				)
			)
		)
		(property "Dielectric" "X7R"
			(at 0 0 180)
			(unlocked yes)
			(layer "F.Fab")
			(hide yes)
			(effects
				(font
					(size 1 1)
					(thickness 0.15)
				)
			)
		)
		(property "Manufacturer" "Murata"
			(at 0 0 180)
			(unlocked yes)
			(layer "F.Fab")
			(hide yes)
			(effects
				(font
					(size 1 1)
					(thickness 0.15)
				)
			)
		)
		(property "License" "Apache-2.0"
			(at 0 0 180)
			(unlocked yes)
			(layer "F.Fab")
			(hide yes)
			(effects
				(font
					(size 1 1)
					(thickness 0.15)
				)
			)
		)
		(property "Author" "Antmicro"
			(at 0 0 180)
			(unlocked yes)
			(layer "F.Fab")
			(hide yes)
			(effects
				(font
					(size 1 1)
					(thickness 0.15)
				)
			)
		)
		(sheetname "/X710-AT2 power/")
		(sheetfile "x710-at2-power.kicad_sch")
		(attr smd)
		(fp_line
			(start -0.15 0.4)
			(end 0.15 0.4)
			(stroke
				(width 0.15)
				(type solid)
			)
			(layer "F.SilkS")
		)
		(fp_line
			(start -0.15 -0.4)
			(end 0.15 -0.4)
			(stroke
				(width 0.15)
				(type solid)
			)
			(layer "F.SilkS")
		)
		(fp_rect
			(start -1.25 -0.65)
			(end 1.25 0.65)
			(stroke
				(width 0.05)
				(type solid)
			)
			(fill no)
			(layer "F.CrtYd")
		)
		(fp_rect
			(start -0.8 -0.4)
			(end 0.8 0.4)
			(stroke
				(width 0.15)
				(type solid)
			)
			(fill no)
			(layer "F.Fab")
		)
		(fp_text user "Author: Antmicro"
			(at -1.682 4.894 180)
			(layer "F.Fab")
			(effects
				(font
					(size 0.7 0.7)
					(thickness 0.15)
				)
				(justify left bottom)
			)
		)
		(fp_text user "${REFERENCE}"
			(at -1.682 3.895 180)
			(layer "F.Fab")
			(effects
				(font
					(size 0.7 0.7)
					(thickness 0.15)
				)
				(justify left bottom)
			)
		)
		(fp_text user "License: Apache-2.0"
			(at -1.682 5.895 180)
			(layer "F.Fab")
			(effects
				(font
					(size 0.7 0.7)
					(thickness 0.15)
				)
				(justify left bottom)
			)
		)
		(pad "1" smd roundrect
			(at -0.7 0 180)
			(size 0.8 1)
			(layers "F.Cu" "F.Mask" "F.Paste")
			(roundrect_rratio 0.2)
			(net 23 "GND")
			(pintype "passive")
		)
		(pad "2" smd roundrect
			(at 0.7 0 180)
			(size 0.8 1)
			(layers "F.Cu" "F.Mask" "F.Paste")
			(roundrect_rratio 0.2)
			(net 21 "XFI_PVDD")
			(pintype "passive")
		)
	)
	(footprint "antmicro-footprints:MLP44-24L_4x4x0.75mm"
		(layer "F.Cu")
		(at 158 50.2)
		(property "Reference" "U20"
			(at -4.8 2.4 0)
			(layer "F.SilkS")
			(effects
				(font
					(size 0.7 0.7)
					(thickness 0.15)
				)
				(justify left bottom)
			)
		)
		(property "Value" "SIC437AED-T1-GE3"
			(at -2.7 3.6 0)
			(layer "F.Fab")
			(effects
				(font
					(size 0.7 0.7)
					(thickness 0.15)
				)
				(justify left bottom)
			)
		)
		(property "Datasheet" "https://www.vishay.com/docs/75921/sic437.pdf"
			(at 0 0 0)
			(layer "F.Fab")
			(hide yes)
			(effects
				(font
					(size 1.27 1.27)
					(thickness 0.15)
				)
			)
		)
		(property "Description" "DC/DC Buck Step Down Regulator Adjustable, 4.5-28V In, 0.6V to 20V/12A Out, 1MHz, PowerPAK MLP44-24"
			(at 0 0 0)
			(layer "F.Fab")
			(hide yes)
			(effects
				(font
					(size 1.27 1.27)
					(thickness 0.15)
				)
			)
		)
		(property "Manufacturer" "Vishay"
			(at 0 0 0)
			(unlocked yes)
			(layer "F.Fab")
			(hide yes)
			(effects
				(font
					(size 1 1)
					(thickness 0.15)
				)
			)
		)
		(property "MPN" "SIC437AED-T1-GE3"
			(at 0 0 0)
			(unlocked yes)
			(layer "F.Fab")
			(hide yes)
			(effects
				(font
					(size 1 1)
					(thickness 0.15)
				)
			)
		)
		(property "Author" "Antmicro"
			(at 0 0 0)
			(unlocked yes)
			(layer "F.Fab")
			(hide yes)
			(effects
				(font
					(size 1 1)
					(thickness 0.15)
				)
			)
		)
		(property "License" "Apache-2.0"
			(at 0 0 0)
			(unlocked yes)
			(layer "F.Fab")
			(hide yes)
			(effects
				(font
					(size 1 1)
					(thickness 0.15)
				)
			)
		)
		(sheetname "/Power input/")
		(sheetfile "power_input.kicad_sch")
		(attr smd)
		(net_tie_pad_groups "1,2,26" "3,4,27" "5,6,7,8,9")
		(fp_line
			(start -2.11 -1.38)
			(end -2.11 -2.1)
			(stroke
				(width 0.15)
				(type solid)
			)
			(layer "F.SilkS")
		)
		(fp_line
			(start -2.11 2.11)
			(end -2.11 1.39)
			(stroke
				(width 0.15)
				(type solid)
			)
			(layer "F.SilkS")
		)
		(fp_line
			(start -1.89 -2.1)
			(end -2.11 -2.1)
			(stroke
				(width 0.15)
				(type solid)
			)
			(layer "F.SilkS")
		)
		(fp_line
			(start -1.89 2.11)
			(end -2.11 2.11)
			(stroke
				(width 0.15)
				(type solid)
			)
			(layer "F.SilkS")
		)
		(fp_line
			(start 1.44 2.11)
			(end 2.11 2.11)
			(stroke
				(width 0.15)
				(type solid)
			)
			(layer "F.SilkS")
		)
		(fp_line
			(start 1.89 -2.11)
			(end 2.11 -2.11)
			(stroke
				(width 0.15)
				(type solid)
			)
			(layer "F.SilkS")
		)
		(fp_line
			(start 2.11 -2.11)
			(end 2.11 -1.69)
			(stroke
				(width 0.15)
				(type solid)
			)
			(layer "F.SilkS")
		)
		(fp_line
			(start 2.11 2.11)
			(end 2.11 1.84)
			(stroke
				(width 0.15)
				(type solid)
			)
			(layer "F.SilkS")
		)
		(fp_circle
			(center -2.25 -1.15)
			(end -2.2 -1.15)
			(stroke
				(width 0.15)
				(type solid)
			)
			(fill yes)
			(layer "F.SilkS")
		)
		(fp_line
			(start -2.55 -2.55)
			(end 2.55 -2.55)
			(stroke
				(width 0.05)
				(type solid)
			)
			(layer "F.CrtYd")
		)
		(fp_line
			(start -2.55 2.55)
			(end -2.55 -2.55)
			(stroke
				(width 0.05)
				(type solid)
			)
			(layer "F.CrtYd")
		)
		(fp_line
			(start 2.55 -2.55)
			(end 2.55 2.55)
			(stroke
				(width 0.05)
				(type solid)
			)
			(layer "F.CrtYd")
		)
		(fp_line
			(start 2.55 2.55)
			(end -2.55 2.55)
			(stroke
				(width 0.05)
				(type solid)
			)
			(layer "F.CrtYd")
		)
		(fp_line
			(start -2 -1)
			(end -2 2)
			(stroke
				(width 0.15)
				(type solid)
			)
			(layer "F.Fab")
		)
		(fp_line
			(start -2 2)
			(end 2 2)
			(stroke
				(width 0.15)
				(type solid)
			)
			(layer "F.Fab")
		)
		(fp_line
			(start -1 -2)
			(end -2 -1)
			(stroke
				(width 0.15)
				(type solid)
			)
			(layer "F.Fab")
		)
		(fp_line
			(start 2 -2)
			(end -1 -2)
			(stroke
				(width 0.15)
				(type solid)
			)
			(layer "F.Fab")
		)
		(fp_line
			(start 2 2)
			(end 2 -2)
			(stroke
				(width 0.15)
				(type solid)
			)
			(layer "F.Fab")
		)
		(fp_text user "${REFERENCE}"
			(at -2.7 6.8 0)
			(layer "F.Fab")
			(effects
				(font
					(size 0.7 0.7)
					(thickness 0.15)
				)
				(justify left bottom)
			)
		)
		(fp_text user "License: Apache-2.0"
			(at -2.7 5.6 0)
			(layer "F.Fab")
			(effects
				(font
					(size 0.7 0.7)
					(thickness 0.15)
				)
				(justify left bottom)
			)
		)
		(fp_text user "Author: Antmicro"
			(at -2.7 8 0)
			(layer "F.Fab")
			(effects
				(font
					(size 0.7 0.7)
					(thickness 0.15)
				)
				(justify left bottom)
			)
		)
		(pad "1" smd roundrect
			(at -1.94 -0.825 90)
			(size 0.3 0.725)
			(layers "F.Cu" "F.Mask" "F.Paste")
			(roundrect_rratio 0.25)
			(net 412 "Net-(D15-C)")
			(pinfunction "V_{IN}")
			(pintype "power_in")
		)
		(pad "2" smd roundrect
			(at -1.94 -0.375 90)
			(size 0.3 0.725)
			(layers "F.Cu" "F.Mask" "F.Paste")
			(roundrect_rratio 0.25)
			(net 412 "Net-(D15-C)")
			(pinfunction "V_{IN}")
			(pintype "passive")
		)
		(pad "3" smd roundrect
			(at -1.94 0.525 90)
			(size 0.3 0.725)
			(layers "F.Cu" "F.Mask" "F.Paste")
			(roundrect_rratio 0.25)
			(net 23 "GND")
			(pinfunction "P_{GND}")
			(pintype "passive")
		)
		(pad "4" smd roundrect
			(at -1.94 0.975 90)
			(size 0.3 0.725)
			(layers "F.Cu" "F.Mask" "F.Paste")
			(roundrect_rratio 0.25)
			(net 23 "GND")
			(pinfunction "P_{GND}")
			(pintype "passive")
		)
		(pad "5" smd custom
			(at -1.475 1.94)
			(size 0.3 0.3)
			(layers "F.Cu" "F.Mask" "F.Paste")
			(net 354 "/Power input/5V_SW")
			(pinfunction "SW")
			(pintype "passive")
			(options
				(clearance outline)
				(anchor circle)
			)
			(primitives
				(gr_poly
					(pts
						(xy -0.15 -0.2875) (xy -0.144291 -0.316201) (xy -0.128033 -0.340533) (xy -0.103701 -0.356791)
						(xy -0.075 -0.3625) (xy 0.075 -0.3625) (xy 0.103701 -0.356791) (xy 0.128033 -0.340533) (xy 0.144291 -0.316201)
						(xy 0.15 -0.2875) (xy 0.15 0.2875) (xy 0.144291 0.316201) (xy 0.128033 0.340533) (xy 0.103701 0.356791)
						(xy 0.075 0.3625) (xy -0.075 0.3625) (xy -0.103701 0.356791) (xy -0.128033 0.340533) (xy -0.144291 0.316201)
						(xy -0.15 0.2875)
					)
					(width 0)
					(fill yes)
				)
				(gr_poly
					(pts
						(xy -0.15 -0.3625) (xy 2.2 -0.3625) (xy 2.2 -0.0875) (xy -0.15 -0.0875)
					)
					(width 0)
					(fill yes)
				)
			)
		)
		(pad "6" smd roundrect
			(at -1.025 1.94)
			(size 0.3 0.725)
			(layers "F.Cu" "F.Mask" "F.Paste")
			(roundrect_rratio 0.25)
			(net 354 "/Power input/5V_SW")
			(pinfunction "SW")
			(pintype "passive")
		)
		(pad "7" smd roundrect
			(at -0.575 1.94)
			(size 0.3 0.725)
			(layers "F.Cu" "F.Mask" "F.Paste")
			(roundrect_rratio 0.25)
			(net 354 "/Power input/5V_SW")
			(pinfunction "SW")
			(pintype "passive")
		)
		(pad "8" smd roundrect
			(at 0.125 1.94)
			(size 0.3 0.725)
			(layers "F.Cu" "F.Mask" "F.Paste")
			(roundrect_rratio 0.25)
			(net 354 "/Power input/5V_SW")
			(pinfunction "SW")
			(pintype "passive")
		)
		(pad "9" smd roundrect
			(at 0.575 1.94)
			(size 0.3 0.725)
			(layers "F.Cu" "F.Mask" "F.Paste")
			(roundrect_rratio 0.25)
			(net 354 "/Power input/5V_SW")
			(pinfunction "SW")
			(pintype "passive")
		)
		(pad "10" smd roundrect
			(at 1.025 1.935)
			(size 0.3 0.725)
			(layers "F.Cu" "F.Mask" "F.Paste")
			(roundrect_rratio 0.25)
			(net 591 "unconnected-(U20-GL-Pad10)_2")
			(pinfunction "GL")
			(pintype "passive+no_connect")
		)
		(pad "11" smd roundrect
			(at 1.94 1.425 90)
			(size 0.3 0.725)
			(layers "F.Cu" "F.Mask" "F.Paste")
			(roundrect_rratio 0.25)
			(net 590 "unconnected-(U20-GL-Pad10)_1")
			(pinfunction "GL")
			(pintype "passive+no_connect")
		)
		(pad "12" smd roundrect
			(at 1.94 0.975 90)
			(size 0.3 0.725)
			(layers "F.Cu" "F.Mask" "F.Paste")
			(roundrect_rratio 0.25)
			(net 346 "/Power input/5V_VDRV")
			(pinfunction "V_{DRV}")
			(pintype "passive")
		)
		(pad "13" smd roundrect
			(at 1.94 0.525 90)
			(size 0.3 0.725)
			(layers "F.Cu" "F.Mask" "F.Paste")
			(roundrect_rratio 0.25)
			(net 23 "GND")
			(pinfunction "P_{GND}")
			(pintype "power_in")
		)
		(pad "14" smd roundrect
			(at 1.94 0.075 90)
			(size 0.3 0.725)
			(layers "F.Cu" "F.Mask" "F.Paste")
			(roundrect_rratio 0.25)
			(net 592 "unconnected-(U20-P_{GOOD}-Pad14)")
			(pinfunction "P_{GOOD}")
			(pintype "output+no_connect")
		)
		(pad "15" smd roundrect
			(at 1.94 -0.375 90)
			(size 0.3 0.725)
			(layers "F.Cu" "F.Mask" "F.Paste")
			(roundrect_rratio 0.25)
			(net 345 "/Power input/5V_VDD")
			(pinfunction "V_{DD}")
			(pintype "passive")
		)
		(pad "16" smd roundrect
			(at 1.94 -0.825 90)
			(size 0.3 0.725)
			(layers "F.Cu" "F.Mask" "F.Paste")
			(roundrect_rratio 0.25)
			(net 23 "GND")
			(pinfunction "A_{GND}")
			(pintype "power_in")
		)
		(pad "17" smd roundrect
			(at 1.94 -1.275 90)
			(size 0.3 0.725)
			(layers "F.Cu" "F.Mask" "F.Paste")
			(roundrect_rratio 0.25)
			(net 391 "/Power input/5V_FB")
			(pinfunction "FB")
			(pintype "passive")
		)
		(pad "18" smd roundrect
			(at 1.475 -1.94)
			(size 0.3 0.725)
			(layers "F.Cu" "F.Mask" "F.Paste")
			(roundrect_rratio 0.25)
			(net 349 "/Power input/5V_OUT")
			(pinfunction "V_{OUT}")
			(pintype "passive")
		)
		(pad "19" smd roundrect
			(at 1.025 -1.94)
			(size 0.3 0.725)
			(layers "F.Cu" "F.Mask" "F.Paste")
			(roundrect_rratio 0.25)
			(net 344 "/Power input/5V_EN")
			(pinfunction "EN")
			(pintype "input")
		)
		(pad "20" smd roundrect
			(at 0.575 -1.94)
			(size 0.3 0.725)
			(layers "F.Cu" "F.Mask" "F.Paste")
			(roundrect_rratio 0.25)
			(net 390 "/Power input/5V_MODE2")
			(pinfunction "MODE2")
			(pintype "input")
		)
		(pad "21" smd roundrect
			(at 0.125 -1.94)
			(size 0.3 0.725)
			(layers "F.Cu" "F.Mask" "F.Paste")
			(roundrect_rratio 0.25)
			(net 389 "/Power input/5V_MODE1")
			(pinfunction "MODE1")
			(pintype "input")
		)
		(pad "22" smd roundrect
			(at -0.575 -1.94)
			(size 0.3 0.725)
			(layers "F.Cu" "F.Mask" "F.Paste")
			(roundrect_rratio 0.25)
			(net 412 "Net-(D15-C)")
			(pinfunction "V_{IN}")
			(pintype "passive")
		)
		(pad "23" smd roundrect
			(at -1.025 -1.94)
			(size 0.3 0.725)
			(layers "F.Cu" "F.Mask" "F.Paste")
			(roundrect_rratio 0.25)
			(net 347 "/Power input/5V_BOOT")
			(pinfunction "BOOT")
			(pintype "passive")
		)
		(pad "24" smd roundrect
			(at -1.475 -1.94)
			(size 0.3 0.725)
			(layers "F.Cu" "F.Mask" "F.Paste")
			(roundrect_rratio 0.25)
			(net 348 "/Power input/5V_PHASE")
			(pinfunction "PHASE")
			(pintype "passive")
		)
		(pad "25" smd rect
			(at 0.49 -0.75 180)
			(size 1.575 1.05)
			(layers "F.Cu" "F.Mask" "F.Paste")
			(net 23 "GND")
			(pinfunction "A_{GND}")
			(pintype "passive")
		)
		(pad "26" smd rect
			(at -1.175 -0.75 180)
			(size 1.15 1.05)
			(layers "F.Cu" "F.Mask" "F.Paste")
			(net 412 "Net-(D15-C)")
			(pinfunction "V_{IN}")
			(pintype "passive")
		)
		(pad "27" smd custom
			(at -0.75 0.775)
			(size 1 1)
			(layers "F.Cu" "F.Mask" "F.Paste")
			(net 23 "GND")
			(pinfunction "P_{GND}")
			(pintype "passive")
			(options
				(clearance outline)
				(anchor rect)
			)
			(primitives
				(gr_poly
					(pts
						(xy -1 0.5) (xy -1 -0.7) (xy 1.825 -0.7) (xy 1.825 -0.245) (xy 1.175 -0.245) (xy 1.175 0.5)
					)
					(width 0)
					(fill yes)
				)
			)
		)
		(pad "28" smd rect
			(at 0.985 0.99 180)
			(size 0.58 0.38)
			(layers "F.Cu" "F.Mask" "F.Paste")
			(net 589 "unconnected-(U20-GL-Pad10)")
			(pinfunction "GL")
			(pintype "passive+no_connect")
		)
	)
	(footprint "antmicro-footprints:C_0402_1005Metric"
		(layer "F.Cu")
		(at 124 73 180)
		(descr "Capacitor SMD 0402")
		(tags "capacitor SMD 0402")
		(property "Reference" "C309"
			(at -1 0.4 180)
			(layer "F.SilkS")
			(effects
				(font
					(size 0.7 0.7)
					(thickness 0.15)
				)
				(justify left bottom)
			)
		)
		(property "Value" "C_470p_0402"
			(at -1.022927 2.155213 180)
			(layer "F.Fab")
			(effects
				(font
					(size 0.7 0.7)
					(thickness 0.15)
				)
				(justify left bottom)
			)
		)
		(property "Datasheet" "https://www.passivecomponent.com/wp-content/uploads/datasheet/WTC_MLCC_General_Purpose.pdf"
			(at 0 0 180)
			(layer "F.Fab")
			(hide yes)
			(effects
				(font
					(size 1.27 1.27)
					(thickness 0.15)
				)
			)
		)
		(property "Description" "SMD Multilayer Ceramic Capacitor, General Purpose, 470 pF, 25 V, 0402 [1005 Metric], ± 10%, X7R"
			(at 0 0 180)
			(layer "F.Fab")
			(hide yes)
			(effects
				(font
					(size 1.27 1.27)
					(thickness 0.15)
				)
			)
		)
		(property "MPN" "0402B471K250CT"
			(at 0 0 180)
			(unlocked yes)
			(layer "F.Fab")
			(hide yes)
			(effects
				(font
					(size 1 1)
					(thickness 0.15)
				)
			)
		)
		(property "Manufacturer" "Walsin"
			(at 0 0 180)
			(unlocked yes)
			(layer "F.Fab")
			(hide yes)
			(effects
				(font
					(size 1 1)
					(thickness 0.15)
				)
			)
		)
		(property "License" "Apache-2.0"
			(at 0 0 180)
			(unlocked yes)
			(layer "F.Fab")
			(hide yes)
			(effects
				(font
					(size 1 1)
					(thickness 0.15)
				)
			)
		)
		(property "Author" "Antmicro"
			(at 0 0 180)
			(unlocked yes)
			(layer "F.Fab")
			(hide yes)
			(effects
				(font
					(size 1 1)
					(thickness 0.15)
				)
			)
		)
		(property "Val" "470p"
			(at 0 0 180)
			(unlocked yes)
			(layer "F.Fab")
			(hide yes)
			(effects
				(font
					(size 1 1)
					(thickness 0.15)
				)
			)
		)
		(property "Voltage" "25V"
			(at 0 0 180)
			(unlocked yes)
			(layer "F.Fab")
			(hide yes)
			(effects
				(font
					(size 1 1)
					(thickness 0.15)
				)
			)
		)
		(property "Dielectric" "X7R"
			(at 0 0 180)
			(unlocked yes)
			(layer "F.Fab")
			(hide yes)
			(effects
				(font
					(size 1 1)
					(thickness 0.15)
				)
			)
		)
		(sheetname "/Fan controller/")
		(sheetfile "fan-controller.kicad_sch")
		(attr smd)
		(fp_rect
			(start -0.925 -0.47)
			(end 0.925 0.47)
			(stroke
				(width 0.05)
				(type default)
			)
			(fill no)
			(layer "F.CrtYd")
		)
		(fp_line
			(start 0.504 0.248)
			(end -0.494 0.248)
			(stroke
				(width 0.15)
				(type solid)
			)
			(layer "F.Fab")
		)
		(fp_line
			(start 0.504 -0.25)
			(end 0.504 0.248)
			(stroke
				(width 0.15)
				(type solid)
			)
			(layer "F.Fab")
		)
		(fp_line
			(start -0.494 0.248)
			(end -0.494 -0.25)
			(stroke
				(width 0.15)
				(type solid)
			)
			(layer "F.Fab")
		)
		(fp_line
			(start -0.494 -0.25)
			(end 0.504 -0.25)
			(stroke
				(width 0.15)
				(type solid)
			)
			(layer "F.Fab")
		)
		(fp_text user "License: Apache-2.0"
			(at -0.939 5.799 180)
			(layer "F.Fab")
			(effects
				(font
					(size 0.7 0.7)
					(thickness 0.15)
				)
				(justify left bottom)
			)
		)
		(fp_text user "${REFERENCE}"
			(at -0.939 4.599 180)
			(layer "F.Fab")
			(effects
				(font
					(size 0.7 0.7)
					(thickness 0.15)
				)
				(justify left bottom)
			)
		)
		(fp_text user "Author: Antmicro"
			(at -0.939 3.399 180)
			(layer "F.Fab")
			(effects
				(font
					(size 0.7 0.7)
					(thickness 0.15)
				)
				(justify left bottom)
			)
		)
		(pad "1" smd roundrect
			(at -0.48 0 180)
			(size 0.59 0.64)
			(layers "F.Cu" "F.Mask" "F.Paste")
			(roundrect_rratio 0.25)
			(net 23 "GND")
			(pintype "passive")
		)
		(pad "2" smd roundrect
			(at 0.48 0 180)
			(size 0.59 0.64)
			(layers "F.Cu" "F.Mask" "F.Paste")
			(roundrect_rratio 0.25)
			(net 152 "/Fan controller/FREQ")
			(pintype "passive")
		)
	)
	(footprint "antmicro-footprints:C_0603_1608Metric"
		(layer "F.Cu")
		(at 122.15 104.7)
		(descr "Capacitor SMD 0603")
		(tags "capacitor 0603")
		(property "Reference" "C26"
			(at 2.35 -0.7 0)
			(layer "F.SilkS")
			(effects
				(font
					(size 0.7 0.7)
					(thickness 0.15)
				)
			)
		)
		(property "Value" "C_22u_0603"
			(at -1.42757 1.770288 0)
			(layer "F.Fab")
			(effects
				(font
					(size 0.7 0.7)
					(thickness 0.15)
				)
				(justify left bottom)
			)
		)
		(property "Datasheet" "https://www.murata.com/products/productdetail?partno=GRM188R60J226MEA0%23"
			(at 0 0 0)
			(layer "F.Fab")
			(hide yes)
			(effects
				(font
					(size 1.27 1.27)
					(thickness 0.15)
				)
			)
		)
		(property "Description" "SMD Multilayer Ceramic Capacitor, 22 µF, 6.3 V, 0603 [1608 Metric], ± 20%, X5R, GRM Series"
			(at 0 0 0)
			(layer "F.Fab")
			(hide yes)
			(effects
				(font
					(size 1.27 1.27)
					(thickness 0.15)
				)
			)
		)
		(property "MPN" "GRM188R60J226MEA0D"
			(at 0 0 0)
			(unlocked yes)
			(layer "F.Fab")
			(hide yes)
			(effects
				(font
					(size 1 1)
					(thickness 0.15)
				)
			)
		)
		(property "Manufacturer" "Murata"
			(at 0 0 0)
			(unlocked yes)
			(layer "F.Fab")
			(hide yes)
			(effects
				(font
					(size 1 1)
					(thickness 0.15)
				)
			)
		)
		(property "License" "Apache-2.0"
			(at 0 0 0)
			(unlocked yes)
			(layer "F.Fab")
			(hide yes)
			(effects
				(font
					(size 1 1)
					(thickness 0.15)
				)
			)
		)
		(property "Val" "22u"
			(at 0 0 0)
			(unlocked yes)
			(layer "F.Fab")
			(hide yes)
			(effects
				(font
					(size 1 1)
					(thickness 0.15)
				)
			)
		)
		(property "Voltage" ""
			(at 0 0 0)
			(unlocked yes)
			(layer "F.Fab")
			(hide yes)
			(effects
				(font
					(size 1 1)
					(thickness 0.15)
				)
			)
		)
		(property "Dielectric" ""
			(at 0 0 0)
			(unlocked yes)
			(layer "F.Fab")
			(hide yes)
			(effects
				(font
					(size 1 1)
					(thickness 0.15)
				)
			)
		)
		(property "Author" "Antmicro"
			(at 0 0 0)
			(unlocked yes)
			(layer "F.Fab")
			(hide yes)
			(effects
				(font
					(size 1 1)
					(thickness 0.15)
				)
			)
		)
		(sheetname "/PD and TB DC-DC/")
		(sheetfile "PD_and_TB_DC_DC.kicad_sch")
		(attr smd)
		(fp_line
			(start -0.15 -0.4)
			(end 0.15 -0.4)
			(stroke
				(width 0.15)
				(type solid)
			)
			(layer "F.SilkS")
		)
		(fp_line
			(start -0.15 0.4)
			(end 0.15 0.4)
			(stroke
				(width 0.15)
				(type solid)
			)
			(layer "F.SilkS")
		)
		(fp_rect
			(start -1.25 -0.65)
			(end 1.25 0.65)
			(stroke
				(width 0.05)
				(type solid)
			)
			(fill no)
			(layer "F.CrtYd")
		)
		(fp_rect
			(start -0.8 -0.4)
			(end 0.8 0.4)
			(stroke
				(width 0.15)
				(type solid)
			)
			(fill no)
			(layer "F.Fab")
		)
		(fp_text user "License: Apache-2.0"
			(at -1.682 5.895 0)
			(layer "F.Fab")
			(effects
				(font
					(size 0.7 0.7)
					(thickness 0.15)
				)
				(justify left bottom)
			)
		)
		(fp_text user "${REFERENCE}"
			(at -1.682 3.895 0)
			(layer "F.Fab")
			(effects
				(font
					(size 0.7 0.7)
					(thickness 0.15)
				)
				(justify left bottom)
			)
		)
		(fp_text user "Author: Antmicro"
			(at -1.682 4.894 0)
			(layer "F.Fab")
			(effects
				(font
					(size 0.7 0.7)
					(thickness 0.15)
				)
				(justify left bottom)
			)
		)
		(pad "1" smd roundrect
			(at -0.7 0)
			(size 0.8 1)
			(layers "F.Cu" "F.Mask" "F.Paste")
			(roundrect_rratio 0.2)
			(net 23 "GND")
			(pintype "passive")
		)
		(pad "2" smd roundrect
			(at 0.7 0)
			(size 0.8 1)
			(layers "F.Cu" "F.Mask" "F.Paste")
			(roundrect_rratio 0.2)
			(net 399 "Net-(D4-A)")
			(pintype "passive")
		)
	)
	(footprint "antmicro-footprints:C_0402_1005Metric"
		(layer "F.Cu")
		(at 134 93.75)
		(descr "Capacitor SMD 0402")
		(tags "capacitor SMD 0402")
		(property "Reference" "C119"
			(at 36.934999 -9.199999 0)
			(layer "F.SilkS")
			(effects
				(font
					(size 0.7 0.7)
					(thickness 0.15)
				)
			)
		)
		(property "Value" "C_1u_25V_0402"
			(at -1.022927 2.155213 0)
			(layer "F.Fab")
			(effects
				(font
					(size 0.7 0.7)
					(thickness 0.15)
				)
				(justify left bottom)
			)
		)
		(property "Datasheet" "https://www.murata.com/products/productdetail?partno=GRM155R61E105KE11%23"
			(at 0 0 0)
			(layer "F.Fab")
			(hide yes)
			(effects
				(font
					(size 1.27 1.27)
					(thickness 0.15)
				)
			)
		)
		(property "Description" "SMD Multilayer Ceramic Capacitor, 1 µF, 25 V, 0402 [1005 Metric], ± 10%, X5R, GRM Series"
			(at 0 0 0)
			(layer "F.Fab")
			(hide yes)
			(effects
				(font
					(size 1.27 1.27)
					(thickness 0.15)
				)
			)
		)
		(property "MPN" "GRM155R61E105KE11J"
			(at 0 0 0)
			(unlocked yes)
			(layer "F.Fab")
			(hide yes)
			(effects
				(font
					(size 1 1)
					(thickness 0.15)
				)
			)
		)
		(property "Manufacturer" "Murata"
			(at 0 0 0)
			(unlocked yes)
			(layer "F.Fab")
			(hide yes)
			(effects
				(font
					(size 1 1)
					(thickness 0.15)
				)
			)
		)
		(property "License" "Apache-2.0"
			(at 0 0 0)
			(unlocked yes)
			(layer "F.Fab")
			(hide yes)
			(effects
				(font
					(size 1 1)
					(thickness 0.15)
				)
			)
		)
		(property "Author" "Antmicro"
			(at 0 0 0)
			(unlocked yes)
			(layer "F.Fab")
			(hide yes)
			(effects
				(font
					(size 1 1)
					(thickness 0.15)
				)
			)
		)
		(property "Val" "1u"
			(at 0 0 0)
			(unlocked yes)
			(layer "F.Fab")
			(hide yes)
			(effects
				(font
					(size 1 1)
					(thickness 0.15)
				)
			)
		)
		(property "Voltage" "25V"
			(at 0 0 0)
			(unlocked yes)
			(layer "F.Fab")
			(hide yes)
			(effects
				(font
					(size 1 1)
					(thickness 0.15)
				)
			)
		)
		(property "Dielectric" "X5R"
			(at 0 0 0)
			(unlocked yes)
			(layer "F.Fab")
			(hide yes)
			(effects
				(font
					(size 1 1)
					(thickness 0.15)
				)
			)
		)
		(sheetname "/X710 DCDC converters/")
		(sheetfile "DCDC_converters_X710.kicad_sch")
		(attr smd)
		(fp_rect
			(start -0.925 -0.47)
			(end 0.925 0.47)
			(stroke
				(width 0.05)
				(type default)
			)
			(fill no)
			(layer "F.CrtYd")
		)
		(fp_line
			(start -0.494 -0.25)
			(end 0.504 -0.25)
			(stroke
				(width 0.15)
				(type solid)
			)
			(layer "F.Fab")
		)
		(fp_line
			(start -0.494 0.248)
			(end -0.494 -0.25)
			(stroke
				(width 0.15)
				(type solid)
			)
			(layer "F.Fab")
		)
		(fp_line
			(start 0.504 -0.25)
			(end 0.504 0.248)
			(stroke
				(width 0.15)
				(type solid)
			)
			(layer "F.Fab")
		)
		(fp_line
			(start 0.504 0.248)
			(end -0.494 0.248)
			(stroke
				(width 0.15)
				(type solid)
			)
			(layer "F.Fab")
		)
		(fp_text user "${REFERENCE}"
			(at -0.939 4.599 0)
			(layer "F.Fab")
			(effects
				(font
					(size 0.7 0.7)
					(thickness 0.15)
				)
				(justify left bottom)
			)
		)
		(fp_text user "Author: Antmicro"
			(at -0.939 3.399 0)
			(layer "F.Fab")
			(effects
				(font
					(size 0.7 0.7)
					(thickness 0.15)
				)
				(justify left bottom)
			)
		)
		(fp_text user "License: Apache-2.0"
			(at -0.939 5.799 0)
			(layer "F.Fab")
			(effects
				(font
					(size 0.7 0.7)
					(thickness 0.15)
				)
				(justify left bottom)
			)
		)
		(pad "1" smd roundrect
			(at -0.48 0)
			(size 0.59 0.64)
			(layers "F.Cu" "F.Mask" "F.Paste")
			(roundrect_rratio 0.25)
			(net 23 "GND")
			(pintype "passive")
		)
		(pad "2" smd roundrect
			(at 0.48 0)
			(size 0.59 0.64)
			(layers "F.Cu" "F.Mask" "F.Paste")
			(roundrect_rratio 0.25)
			(net 80 "/X710 DCDC converters/3V3_VCC")
			(pintype "passive")
		)
	)
	(footprint "antmicro-footprints:Vishay_PowerPAK_1212-8_Single"
		(layer "F.Cu")
		(at 142.243 57.693)
		(descr "PowerPAK 1212-8 Single")
		(tags "Vishay PowerPAK 1212-8 Single")
		(property "Reference" "Q7"
			(at 1.957 -1.893 0)
			(layer "F.SilkS")
			(effects
				(font
					(size 0.7 0.7)
					(thickness 0.15)
				)
				(justify left bottom)
			)
		)
		(property "Value" "SQS401EN-T1_BE3"
			(at 0 2.7 0)
			(layer "F.Fab")
			(effects
				(font
					(size 0.7 0.7)
					(thickness 0.15)
				)
				(justify left bottom)
			)
		)
		(property "Datasheet" "https://www.vishay.com/docs/65529/sqs401en.pdf"
			(at 0 0 0)
			(layer "F.Fab")
			(hide yes)
			(effects
				(font
					(size 1.27 1.27)
					(thickness 0.15)
				)
			)
		)
		(property "Description" "MOSFET, P Channel, 40 V, 16A, 0.047 ohm, PowerPAK 1212-8, Surface Mount"
			(at 0 0 0)
			(layer "F.Fab")
			(hide yes)
			(effects
				(font
					(size 1.27 1.27)
					(thickness 0.15)
				)
			)
		)
		(property "MPN" "SQS401EN-T1_BE3"
			(at 0 0 0)
			(unlocked yes)
			(layer "F.Fab")
			(hide yes)
			(effects
				(font
					(size 1 1)
					(thickness 0.15)
				)
			)
		)
		(property "Manufacturer" "Vishay"
			(at 0 0 0)
			(unlocked yes)
			(layer "F.Fab")
			(hide yes)
			(effects
				(font
					(size 1 1)
					(thickness 0.15)
				)
			)
		)
		(property "Author" "Antmicro"
			(at 0 0 0)
			(unlocked yes)
			(layer "F.Fab")
			(hide yes)
			(effects
				(font
					(size 1 1)
					(thickness 0.15)
				)
			)
		)
		(property "License" "Apache-2.0"
			(at 0 0 0)
			(unlocked yes)
			(layer "F.Fab")
			(hide yes)
			(effects
				(font
					(size 1 1)
					(thickness 0.15)
				)
			)
		)
		(sheetname "/Power input/")
		(sheetfile "power_input.kicad_sch")
		(attr smd)
		(fp_line
			(start -1.651 -1.651)
			(end -1.651 -1.317)
			(stroke
				(width 0.15)
				(type solid)
			)
			(layer "F.SilkS")
		)
		(fp_line
			(start -1.651 -1.651)
			(end 1.648 -1.651)
			(stroke
				(width 0.15)
				(type solid)
			)
			(layer "F.SilkS")
		)
		(fp_line
			(start -1.635 1.3)
			(end -1.635 1.634)
			(stroke
				(width 0.15)
				(type solid)
			)
			(layer "F.SilkS")
		)
		(fp_line
			(start -1.635 1.634)
			(end 1.634 1.634)
			(stroke
				(width 0.15)
				(type solid)
			)
			(layer "F.SilkS")
		)
		(fp_line
			(start 1.634 1.3)
			(end 1.634 1.634)
			(stroke
				(width 0.15)
				(type solid)
			)
			(layer "F.SilkS")
		)
		(fp_line
			(start 1.648 -1.651)
			(end 1.648 -1.317)
			(stroke
				(width 0.15)
				(type solid)
			)
			(layer "F.SilkS")
		)
		(fp_circle
			(center -1.9 -1.4)
			(end -1.85 -1.4)
			(stroke
				(width 0.15)
				(type solid)
			)
			(fill yes)
			(layer "F.SilkS")
		)
		(fp_rect
			(start -2 -1.8)
			(end 2 1.798)
			(stroke
				(width 0.05)
				(type solid)
			)
			(fill no)
			(layer "F.CrtYd")
		)
		(fp_line
			(start -1.6425 -1.4175)
			(end -1.4175 -1.6425)
			(stroke
				(width 0.15)
				(type solid)
			)
			(layer "F.Fab")
		)
		(fp_rect
			(start -1.651 -1.651)
			(end 1.648 1.648)
			(stroke
				(width 0.15)
				(type solid)
			)
			(fill no)
			(layer "F.Fab")
		)
		(fp_text user "License: Apache-2.0"
			(at -8 7.1 0)
			(layer "F.Fab")
			(effects
				(font
					(size 0.7 0.7)
					(thickness 0.15)
				)
				(justify left bottom)
			)
		)
		(fp_text user "Author: Antmicro"
			(at -8 5.9 0)
			(layer "F.Fab")
			(effects
				(font
					(size 0.7 0.7)
					(thickness 0.15)
				)
				(justify left bottom)
			)
		)
		(fp_text user "${REFERENCE}"
			(at -8 4.7 0)
			(layer "F.Fab")
			(effects
				(font
					(size 0.7 0.7)
					(thickness 0.15)
				)
				(justify left bottom)
			)
		)
		(pad "1" smd rect
			(at -1.436 -0.99)
			(size 0.99 0.405)
			(layers "F.Cu" "F.Mask" "F.Paste")
			(net 40 "+5V")
			(pinfunction "S")
			(pintype "passive")
		)
		(pad "2" smd rect
			(at -1.436 -0.332)
			(size 0.99 0.405)
			(layers "F.Cu" "F.Mask" "F.Paste")
			(net 40 "+5V")
			(pinfunction "S")
			(pintype "passive")
		)
		(pad "3" smd rect
			(at -1.436 0.33)
			(size 0.99 0.405)
			(layers "F.Cu" "F.Mask" "F.Paste")
			(net 40 "+5V")
			(pinfunction "S")
			(pintype "passive")
		)
		(pad "4" smd rect
			(at -1.436 0.988)
			(size 0.99 0.405)
			(layers "F.Cu" "F.Mask" "F.Paste")
			(net 432 "Net-(Q7-G)")
			(pinfunction "G")
			(pintype "passive")
		)
		(pad "5" smd custom
			(at 0.557 0)
			(size 1.725 2.235)
			(layers "F.Cu" "F.Mask" "F.Paste")
			(net 13 "/Power input/5V_JACK")
			(pinfunction "D")
			(pintype "passive")
			(zone_connect 2)
			(options
				(clearance outline)
				(anchor rect)
			)
			(primitives
				(gr_poly
					(pts
						(xy 0.8625 0.1275) (xy 0.8625 -0.1275) (xy 1.3725 -0.1275) (xy 1.3725 -0.5325) (xy 0.8625 -0.5325)
						(xy 0.8625 -0.7875) (xy 1.3725 -0.7875) (xy 1.3725 -1.195) (xy 0.6125 -1.195) (xy 0.6125 1.195)
						(xy 1.3725 1.195) (xy 1.3725 0.7875) (xy 0.8625 0.7875) (xy 0.8625 0.5325) (xy 1.3725 0.5325)
						(xy 1.3725 0.1275)
					)
					(width 0)
					(fill yes)
				)
			)
		)
	)
	(footprint "antmicro-footprints:R_0402_1005Metric"
		(layer "F.Cu")
		(at 164 75.4)
		(descr "Resistor SMD 0402")
		(tags "resistor SMD 0402")
		(property "Reference" "R139"
			(at -1 6.4 0)
			(layer "F.SilkS")
			(effects
				(font
					(size 0.7 0.7)
					(thickness 0.15)
				)
				(justify left bottom)
			)
		)
		(property "Value" "R_2k_0402"
			(at -1.011843 1.772047 0)
			(layer "F.Fab")
			(effects
				(font
					(size 0.7 0.7)
					(thickness 0.15)
				)
				(justify left bottom)
			)
		)
		(property "Datasheet" "https://www.bourns.com/docs/product-datasheets/cr.pdf"
			(at 0 0 0)
			(layer "F.Fab")
			(hide yes)
			(effects
				(font
					(size 1.27 1.27)
					(thickness 0.15)
				)
			)
		)
		(property "Description" "SMD Chip Resistor, 2 kohm, ± 1%, 62.5 mW, 0402 [1005 Metric], Thick Film, General Purpose"
			(at 0 0 0)
			(layer "F.Fab")
			(hide yes)
			(effects
				(font
					(size 1.27 1.27)
					(thickness 0.15)
				)
			)
		)
		(property "MPN" "CR0402-FX-2001GLF"
			(at 0 0 0)
			(unlocked yes)
			(layer "F.Fab")
			(hide yes)
			(effects
				(font
					(size 1 1)
					(thickness 0.15)
				)
			)
		)
		(property "Manufacturer" "Bourns"
			(at 0 0 0)
			(unlocked yes)
			(layer "F.Fab")
			(hide yes)
			(effects
				(font
					(size 1 1)
					(thickness 0.15)
				)
			)
		)
		(property "License" "Apache-2.0"
			(at 0 0 0)
			(unlocked yes)
			(layer "F.Fab")
			(hide yes)
			(effects
				(font
					(size 1 1)
					(thickness 0.15)
				)
			)
		)
		(property "Author" "Antmicro"
			(at 0 0 0)
			(unlocked yes)
			(layer "F.Fab")
			(hide yes)
			(effects
				(font
					(size 1 1)
					(thickness 0.15)
				)
			)
		)
		(property "Val" "2k"
			(at 0 0 0)
			(unlocked yes)
			(layer "F.Fab")
			(hide yes)
			(effects
				(font
					(size 1 1)
					(thickness 0.15)
				)
			)
		)
		(property "Tolerance" "1%"
			(at 0 0 0)
			(unlocked yes)
			(layer "F.Fab")
			(hide yes)
			(effects
				(font
					(size 1 1)
					(thickness 0.15)
				)
			)
		)
		(sheetname "/X710-AT2 Misc/")
		(sheetfile "x710-at2-mics.kicad_sch")
		(attr smd)
		(fp_rect
			(start -0.925 -0.47)
			(end 0.925 0.47)
			(stroke
				(width 0.05)
				(type default)
			)
			(fill no)
			(layer "F.CrtYd")
		)
		(fp_rect
			(start -0.5 -0.25)
			(end 0.5 0.25)
			(stroke
				(width 0.15)
				(type solid)
			)
			(fill no)
			(layer "F.Fab")
		)
		(fp_text user "Author: Antmicro"
			(at -0.95 4.169 0)
			(layer "F.Fab")
			(effects
				(font
					(size 0.7 0.7)
					(thickness 0.15)
				)
				(justify left bottom)
			)
		)
		(fp_text user "License: Apache-2.0"
			(at -0.95 5.169 0)
			(layer "F.Fab")
			(effects
				(font
					(size 0.7 0.7)
					(thickness 0.15)
				)
				(justify left bottom)
			)
		)
		(fp_text user "${REFERENCE}"
			(at -0.95 3.168 0)
			(layer "F.Fab")
			(effects
				(font
					(size 0.7 0.7)
					(thickness 0.15)
				)
				(justify left bottom)
			)
		)
		(pad "1" smd roundrect
			(at -0.48 0)
			(size 0.59 0.64)
			(layers "F.Cu" "F.Mask" "F.Paste")
			(roundrect_rratio 0.25)
			(net 146 "/X710-AT2 10GbE/~{PHY_RESET_3V3}")
			(pintype "passive")
		)
		(pad "2" smd roundrect
			(at 0.48 0)
			(size 0.59 0.64)
			(layers "F.Cu" "F.Mask" "F.Paste")
			(roundrect_rratio 0.25)
			(net 7 "+3V3")
			(pintype "passive")
		)
	)
	(footprint "antmicro-footprints:R_0402_1005Metric"
		(layer "F.Cu")
		(at 156.205 67.124999 90)
		(descr "Resistor SMD 0402")
		(tags "resistor SMD 0402")
		(property "Reference" "R152"
			(at 12.324999 20.295 90)
			(layer "F.SilkS")
			(effects
				(font
					(size 0.7 0.7)
					(thickness 0.15)
				)
			)
		)
		(property "Value" "R_100k_0402"
			(at -1.011843 1.772047 90)
			(layer "F.Fab")
			(effects
				(font
					(size 0.7 0.7)
					(thickness 0.15)
				)
				(justify left bottom)
			)
		)
		(property "Datasheet" "https://www.bourns.com/docs/product-datasheets/cr.pdf"
			(at 0 0 90)
			(layer "F.Fab")
			(hide yes)
			(effects
				(font
					(size 1.27 1.27)
					(thickness 0.15)
				)
			)
		)
		(property "Description" "SMD Chip Resistor, 100 kohm, ± 1%, 62.5 mW, 0402 [1005 Metric], Thick Film, General Purpose"
			(at 0 0 90)
			(layer "F.Fab")
			(hide yes)
			(effects
				(font
					(size 1.27 1.27)
					(thickness 0.15)
				)
			)
		)
		(property "MPN" "CR0402-FX-1003GLF"
			(at 0 0 90)
			(unlocked yes)
			(layer "F.Fab")
			(hide yes)
			(effects
				(font
					(size 1 1)
					(thickness 0.15)
				)
			)
		)
		(property "Manufacturer" "Bourns"
			(at 0 0 90)
			(unlocked yes)
			(layer "F.Fab")
			(hide yes)
			(effects
				(font
					(size 1 1)
					(thickness 0.15)
				)
			)
		)
		(property "License" "Apache-2.0"
			(at 0 0 90)
			(unlocked yes)
			(layer "F.Fab")
			(hide yes)
			(effects
				(font
					(size 1 1)
					(thickness 0.15)
				)
			)
		)
		(property "Author" "Antmicro"
			(at 0 0 90)
			(unlocked yes)
			(layer "F.Fab")
			(hide yes)
			(effects
				(font
					(size 1 1)
					(thickness 0.15)
				)
			)
		)
		(property "Val" "100k"
			(at 0 0 90)
			(unlocked yes)
			(layer "F.Fab")
			(hide yes)
			(effects
				(font
					(size 1 1)
					(thickness 0.15)
				)
			)
		)
		(property "Tolerance" "1%"
			(at 0 0 90)
			(unlocked yes)
			(layer "F.Fab")
			(hide yes)
			(effects
				(font
					(size 1 1)
					(thickness 0.15)
				)
			)
		)
		(sheetname "/X710-AT2 Misc/")
		(sheetfile "x710-at2-mics.kicad_sch")
		(attr smd)
		(fp_rect
			(start -0.925 -0.47)
			(end 0.925 0.47)
			(stroke
				(width 0.05)
				(type default)
			)
			(fill no)
			(layer "F.CrtYd")
		)
		(fp_rect
			(start -0.5 -0.25)
			(end 0.5 0.25)
			(stroke
				(width 0.15)
				(type solid)
			)
			(fill no)
			(layer "F.Fab")
		)
		(fp_text user "${REFERENCE}"
			(at -0.95 3.168 90)
			(layer "F.Fab")
			(effects
				(font
					(size 0.7 0.7)
					(thickness 0.15)
				)
				(justify left bottom)
			)
		)
		(fp_text user "Author: Antmicro"
			(at -0.95 4.169 90)
			(layer "F.Fab")
			(effects
				(font
					(size 0.7 0.7)
					(thickness 0.15)
				)
				(justify left bottom)
			)
		)
		(fp_text user "License: Apache-2.0"
			(at -0.95 5.169 90)
			(layer "F.Fab")
			(effects
				(font
					(size 0.7 0.7)
					(thickness 0.15)
				)
				(justify left bottom)
			)
		)
		(pad "1" smd roundrect
			(at -0.48 0 90)
			(size 0.59 0.64)
			(layers "F.Cu" "F.Mask" "F.Paste")
			(roundrect_rratio 0.25)
			(net 23 "GND")
			(pintype "passive")
		)
		(pad "2" smd roundrect
			(at 0.48 0 90)
			(size 0.59 0.64)
			(layers "F.Cu" "F.Mask" "F.Paste")
			(roundrect_rratio 0.25)
			(net 142 "/X710-AT2 Misc/NCSI.CRS_DV")
			(pintype "passive")
		)
	)
	(footprint "antmicro-footprints:R_0402_1005Metric"
		(layer "F.Cu")
		(at 116.4 105.1 180)
		(descr "Resistor SMD 0402")
		(tags "resistor SMD 0402")
		(property "Reference" "R21"
			(at 0 8.1 180)
			(layer "F.SilkS")
			(effects
				(font
					(size 0.7 0.7)
					(thickness 0.15)
				)
			)
		)
		(property "Value" "R_40k2_0402"
			(at -1.011843 1.772047 180)
			(layer "F.Fab")
			(effects
				(font
					(size 0.7 0.7)
					(thickness 0.15)
				)
				(justify left bottom)
			)
		)
		(property "Datasheet" "https://www.bourns.com/docs/product-datasheets/cr.pdf"
			(at 0 0 180)
			(layer "F.Fab")
			(hide yes)
			(effects
				(font
					(size 1.27 1.27)
					(thickness 0.15)
				)
			)
		)
		(property "Description" "SMD Chip Resistor, 40.2 kohm, ± 1%, 63 mW, 0402 [1005 Metric], Thick Film, General Purpose"
			(at 0 0 180)
			(layer "F.Fab")
			(hide yes)
			(effects
				(font
					(size 1.27 1.27)
					(thickness 0.15)
				)
			)
		)
		(property "MPN" "CR0402-FX-4022GLF"
			(at 0 0 180)
			(unlocked yes)
			(layer "F.Fab")
			(hide yes)
			(effects
				(font
					(size 1 1)
					(thickness 0.15)
				)
			)
		)
		(property "Manufacturer" "Bourns"
			(at 0 0 180)
			(unlocked yes)
			(layer "F.Fab")
			(hide yes)
			(effects
				(font
					(size 1 1)
					(thickness 0.15)
				)
			)
		)
		(property "License" "Apache-2.0"
			(at 0 0 180)
			(unlocked yes)
			(layer "F.Fab")
			(hide yes)
			(effects
				(font
					(size 1 1)
					(thickness 0.15)
				)
			)
		)
		(property "Val" "40k2"
			(at 0 0 180)
			(unlocked yes)
			(layer "F.Fab")
			(hide yes)
			(effects
				(font
					(size 1 1)
					(thickness 0.15)
				)
			)
		)
		(property "Tolerance" "1%"
			(at 0 0 180)
			(unlocked yes)
			(layer "F.Fab")
			(hide yes)
			(effects
				(font
					(size 1 1)
					(thickness 0.15)
				)
			)
		)
		(property "Author" "Antmicro"
			(at 0 0 180)
			(unlocked yes)
			(layer "F.Fab")
			(hide yes)
			(effects
				(font
					(size 1 1)
					(thickness 0.15)
				)
			)
		)
		(sheetname "/PD and TB DC-DC/")
		(sheetfile "PD_and_TB_DC_DC.kicad_sch")
		(attr smd)
		(fp_rect
			(start -0.925 -0.47)
			(end 0.925 0.47)
			(stroke
				(width 0.05)
				(type default)
			)
			(fill no)
			(layer "F.CrtYd")
		)
		(fp_rect
			(start -0.5 -0.25)
			(end 0.5 0.25)
			(stroke
				(width 0.15)
				(type solid)
			)
			(fill no)
			(layer "F.Fab")
		)
		(fp_text user "${REFERENCE}"
			(at -0.95 3.168 180)
			(layer "F.Fab")
			(effects
				(font
					(size 0.7 0.7)
					(thickness 0.15)
				)
				(justify left bottom)
			)
		)
		(fp_text user "License: Apache-2.0"
			(at -0.95 5.169 180)
			(layer "F.Fab")
			(effects
				(font
					(size 0.7 0.7)
					(thickness 0.15)
				)
				(justify left bottom)
			)
		)
		(fp_text user "Author: Antmicro"
			(at -0.95 4.169 180)
			(layer "F.Fab")
			(effects
				(font
					(size 0.7 0.7)
					(thickness 0.15)
				)
				(justify left bottom)
			)
		)
		(pad "1" smd roundrect
			(at -0.48 0 180)
			(size 0.59 0.64)
			(layers "F.Cu" "F.Mask" "F.Paste")
			(roundrect_rratio 0.25)
			(net 166 "Net-(U2-FB)")
			(pintype "passive")
		)
		(pad "2" smd roundrect
			(at 0.48 0 180)
			(size 0.59 0.64)
			(layers "F.Cu" "F.Mask" "F.Paste")
			(roundrect_rratio 0.25)
			(net 399 "Net-(D4-A)")
			(pintype "passive")
		)
	)
	(footprint "antmicro-footprints:C_0603_1608Metric_EIA"
		(layer "F.Cu")
		(at 137.305 99.774998 -90)
		(descr "Capacitor SMD 0603, IPC-7351 Density Level A")
		(tags "Capacitor 0603")
		(property "Reference" "C265"
			(at -9.274999 -36.945 270)
			(layer "F.SilkS")
			(effects
				(font
					(size 0.7 0.7)
					(thickness 0.15)
				)
			)
		)
		(property "Value" "C_22u_16V_0603"
			(at -1.42757 1.770288 270)
			(layer "F.Fab")
			(effects
				(font
					(size 0.7 0.7)
					(thickness 0.15)
				)
				(justify left bottom)
			)
		)
		(property "Datasheet" "https://product.samsungsem.com/mlcc/CL10A226MO7JZN.do"
			(at 0 0 270)
			(layer "F.Fab")
			(hide yes)
			(effects
				(font
					(size 1.27 1.27)
					(thickness 0.15)
				)
			)
		)
		(property "Description" "SMD Multilayer Ceramic Capacitor"
			(at 0 0 270)
			(layer "F.Fab")
			(hide yes)
			(effects
				(font
					(size 1.27 1.27)
					(thickness 0.15)
				)
			)
		)
		(property "MPN" "CL10A226MO7JZNC"
			(at 0 0 270)
			(unlocked yes)
			(layer "F.Fab")
			(hide yes)
			(effects
				(font
					(size 1 1)
					(thickness 0.15)
				)
			)
		)
		(property "Manufacturer" "Samsung Electro-Mechanics"
			(at 0 0 270)
			(unlocked yes)
			(layer "F.Fab")
			(hide yes)
			(effects
				(font
					(size 1 1)
					(thickness 0.15)
				)
			)
		)
		(property "License" "Apache-2.0"
			(at 0 0 270)
			(unlocked yes)
			(layer "F.Fab")
			(hide yes)
			(effects
				(font
					(size 1 1)
					(thickness 0.15)
				)
			)
		)
		(property "Author" "Antmicro"
			(at 0 0 270)
			(unlocked yes)
			(layer "F.Fab")
			(hide yes)
			(effects
				(font
					(size 1 1)
					(thickness 0.15)
				)
			)
		)
		(property "Val" "22u"
			(at 0 0 270)
			(unlocked yes)
			(layer "F.Fab")
			(hide yes)
			(effects
				(font
					(size 1 1)
					(thickness 0.15)
				)
			)
		)
		(property "Voltage" "16V"
			(at 0 0 270)
			(unlocked yes)
			(layer "F.Fab")
			(hide yes)
			(effects
				(font
					(size 1 1)
					(thickness 0.15)
				)
			)
		)
		(property "Dielectric" ""
			(at 0 0 270)
			(unlocked yes)
			(layer "F.Fab")
			(hide yes)
			(effects
				(font
					(size 1 1)
					(thickness 0.15)
				)
			)
		)
		(sheetname "/X710-AT2 power/")
		(sheetfile "x710-at2-power.kicad_sch")
		(attr smd)
		(fp_line
			(start -0.15 0.55)
			(end 0.15 0.55)
			(stroke
				(width 0.15)
				(type solid)
			)
			(layer "F.SilkS")
		)
		(fp_line
			(start -0.15 -0.55)
			(end 0.15 -0.55)
			(stroke
				(width 0.15)
				(type solid)
			)
			(layer "F.SilkS")
		)
		(fp_rect
			(start -1.25 -0.65)
			(end 1.25 0.65)
			(stroke
				(width 0.05)
				(type solid)
			)
			(fill no)
			(layer "F.CrtYd")
		)
		(fp_rect
			(start -0.8 -0.45)
			(end 0.8 0.45)
			(stroke
				(width 0.15)
				(type solid)
			)
			(fill no)
			(layer "F.Fab")
		)
		(fp_text user "License: Apache-2.0"
			(at -1.682 5.895 270)
			(layer "F.Fab")
			(effects
				(font
					(size 0.7 0.7)
					(thickness 0.15)
				)
				(justify left bottom)
			)
		)
		(fp_text user "${REFERENCE}"
			(at -1.682 3.895 270)
			(layer "F.Fab")
			(effects
				(font
					(size 0.7 0.7)
					(thickness 0.15)
				)
				(justify left bottom)
			)
		)
		(fp_text user "Author: Antmicro"
			(at -1.682 4.894 270)
			(layer "F.Fab")
			(effects
				(font
					(size 0.7 0.7)
					(thickness 0.15)
				)
				(justify left bottom)
			)
		)
		(pad "1" smd roundrect
			(at -0.7 0 270)
			(size 0.8 1.1)
			(layers "F.Cu" "F.Mask" "F.Paste")
			(roundrect_rratio 0.2)
			(net 23 "GND")
			(pintype "passive")
		)
		(pad "2" smd roundrect
			(at 0.7 0 270)
			(size 0.8 1.1)
			(layers "F.Cu" "F.Mask" "F.Paste")
			(roundrect_rratio 0.2)
			(net 9 "VCCD")
			(pintype "passive")
		)
	)
	(footprint "antmicro-footprints:R_0402_1005Metric"
		(layer "F.Cu")
		(at 116.99 72.9)
		(descr "Resistor SMD 0402")
		(tags "resistor SMD 0402")
		(property "Reference" "R217"
			(at 3.6 -10.5 0)
			(layer "F.SilkS")
			(effects
				(font
					(size 0.7 0.7)
					(thickness 0.15)
				)
				(justify left bottom)
			)
		)
		(property "Value" "R_10k_0402"
			(at -1.011843 1.772047 0)
			(layer "F.Fab")
			(effects
				(font
					(size 0.7 0.7)
					(thickness 0.15)
				)
				(justify left bottom)
			)
		)
		(property "Datasheet" "https://www.bourns.com/docs/product-datasheets/cr.pdf"
			(at 0 0 0)
			(layer "F.Fab")
			(hide yes)
			(effects
				(font
					(size 1.27 1.27)
					(thickness 0.15)
				)
			)
		)
		(property "Description" "SMD Chip Resistor, 10 kohm, ± 1%, 62.5 mW, 0402 [1005 Metric], Thick Film, General Purpose"
			(at 0 0 0)
			(layer "F.Fab")
			(hide yes)
			(effects
				(font
					(size 1.27 1.27)
					(thickness 0.15)
				)
			)
		)
		(property "MPN" "CR0402-FX-1002GLF"
			(at 0 0 0)
			(unlocked yes)
			(layer "F.Fab")
			(hide yes)
			(effects
				(font
					(size 1 1)
					(thickness 0.15)
				)
			)
		)
		(property "Manufacturer" "Bourns"
			(at 0 0 0)
			(unlocked yes)
			(layer "F.Fab")
			(hide yes)
			(effects
				(font
					(size 1 1)
					(thickness 0.15)
				)
			)
		)
		(property "License" "Apache-2.0"
			(at 0 0 0)
			(unlocked yes)
			(layer "F.Fab")
			(hide yes)
			(effects
				(font
					(size 1 1)
					(thickness 0.15)
				)
			)
		)
		(property "Author" "Antmicro"
			(at 0 0 0)
			(unlocked yes)
			(layer "F.Fab")
			(hide yes)
			(effects
				(font
					(size 1 1)
					(thickness 0.15)
				)
			)
		)
		(property "Val" "10k"
			(at 0 0 0)
			(unlocked yes)
			(layer "F.Fab")
			(hide yes)
			(effects
				(font
					(size 1 1)
					(thickness 0.15)
				)
			)
		)
		(property "Tolerance" "1%"
			(at 0 0 0)
			(unlocked yes)
			(layer "F.Fab")
			(hide yes)
			(effects
				(font
					(size 1 1)
					(thickness 0.15)
				)
			)
		)
		(sheetname "/Fan controller/")
		(sheetfile "fan-controller.kicad_sch")
		(attr smd)
		(fp_rect
			(start -0.925 -0.47)
			(end 0.925 0.47)
			(stroke
				(width 0.05)
				(type default)
			)
			(fill no)
			(layer "F.CrtYd")
		)
		(fp_rect
			(start -0.5 -0.25)
			(end 0.5 0.25)
			(stroke
				(width 0.15)
				(type solid)
			)
			(fill no)
			(layer "F.Fab")
		)
		(fp_text user "License: Apache-2.0"
			(at -0.95 5.169 0)
			(layer "F.Fab")
			(effects
				(font
					(size 0.7 0.7)
					(thickness 0.15)
				)
				(justify left bottom)
			)
		)
		(fp_text user "Author: Antmicro"
			(at -0.95 4.169 0)
			(layer "F.Fab")
			(effects
				(font
					(size 0.7 0.7)
					(thickness 0.15)
				)
				(justify left bottom)
			)
		)
		(fp_text user "${REFERENCE}"
			(at -0.95 3.168 0)
			(layer "F.Fab")
			(effects
				(font
					(size 0.7 0.7)
					(thickness 0.15)
				)
				(justify left bottom)
			)
		)
		(pad "1" smd roundrect
			(at -0.48 0)
			(size 0.59 0.64)
			(layers "F.Cu" "F.Mask" "F.Paste")
			(roundrect_rratio 0.25)
			(net 446 "Net-(R216-Pad1)")
			(pintype "passive")
		)
		(pad "2" smd roundrect
			(at 0.48 0)
			(size 0.59 0.64)
			(layers "F.Cu" "F.Mask" "F.Paste")
			(roundrect_rratio 0.25)
			(net 151 "/Fan controller/SENSE")
			(pintype "passive")
		)
	)
	(footprint "antmicro-footprints:C_0402_1005Metric"
		(layer "F.Cu")
		(at 156.915 95.530499)
		(descr "Capacitor SMD 0402")
		(tags "capacitor SMD 0402")
		(property "Reference" "C281"
			(at 23.294999 19.625001 0)
			(layer "F.SilkS")
			(effects
				(font
					(size 0.7 0.7)
					(thickness 0.15)
				)
			)
		)
		(property "Value" "C_5p6_0402"
			(at -1.022927 2.155213 0)
			(layer "F.Fab")
			(effects
				(font
					(size 0.7 0.7)
					(thickness 0.15)
				)
				(justify left bottom)
			)
		)
		(property "Datasheet" "https://www.mouser.com/datasheet/3/76/2/GCM1555C1H5R6BA16_01A.pdf"
			(at 0 0 0)
			(layer "F.Fab")
			(hide yes)
			(effects
				(font
					(size 1.27 1.27)
					(thickness 0.15)
				)
			)
		)
		(property "Description" "Multilayer Ceramic Capacitors MLCC - SMD/SMT 5.6 pF 50 VDC 0.1 pF 0402 C0G (NP0) AEC-Q200"
			(at 0 0 0)
			(layer "F.Fab")
			(hide yes)
			(effects
				(font
					(size 1.27 1.27)
					(thickness 0.15)
				)
			)
		)
		(property "MPN" "GCM1555C1H5R6BA16D"
			(at 0 0 0)
			(unlocked yes)
			(layer "F.Fab")
			(hide yes)
			(effects
				(font
					(size 1 1)
					(thickness 0.15)
				)
			)
		)
		(property "Manufacturer" "Murata"
			(at 0 0 0)
			(unlocked yes)
			(layer "F.Fab")
			(hide yes)
			(effects
				(font
					(size 1 1)
					(thickness 0.15)
				)
			)
		)
		(property "License" "Apache-2.0"
			(at 0 0 0)
			(unlocked yes)
			(layer "F.Fab")
			(hide yes)
			(effects
				(font
					(size 1 1)
					(thickness 0.15)
				)
			)
		)
		(property "Author" "Antmicro"
			(at 0 0 0)
			(unlocked yes)
			(layer "F.Fab")
			(hide yes)
			(effects
				(font
					(size 1 1)
					(thickness 0.15)
				)
			)
		)
		(property "Val" "5p6"
			(at 0 0 0)
			(unlocked yes)
			(layer "F.Fab")
			(hide yes)
			(effects
				(font
					(size 1 1)
					(thickness 0.15)
				)
			)
		)
		(property "Voltage" "50V"
			(at 0 0 0)
			(unlocked yes)
			(layer "F.Fab")
			(hide yes)
			(effects
				(font
					(size 1 1)
					(thickness 0.15)
				)
			)
		)
		(property "Dielectric" "C0G"
			(at 0 0 0)
			(unlocked yes)
			(layer "F.Fab")
			(hide yes)
			(effects
				(font
					(size 1 1)
					(thickness 0.15)
				)
			)
		)
		(sheetname "/X710-AT2 Misc/")
		(sheetfile "x710-at2-mics.kicad_sch")
		(attr smd)
		(fp_rect
			(start -0.925 -0.47)
			(end 0.925 0.47)
			(stroke
				(width 0.05)
				(type default)
			)
			(fill no)
			(layer "F.CrtYd")
		)
		(fp_line
			(start -0.494 -0.25)
			(end 0.504 -0.25)
			(stroke
				(width 0.15)
				(type solid)
			)
			(layer "F.Fab")
		)
		(fp_line
			(start -0.494 0.248)
			(end -0.494 -0.25)
			(stroke
				(width 0.15)
				(type solid)
			)
			(layer "F.Fab")
		)
		(fp_line
			(start 0.504 -0.25)
			(end 0.504 0.248)
			(stroke
				(width 0.15)
				(type solid)
			)
			(layer "F.Fab")
		)
		(fp_line
			(start 0.504 0.248)
			(end -0.494 0.248)
			(stroke
				(width 0.15)
				(type solid)
			)
			(layer "F.Fab")
		)
		(fp_text user "${REFERENCE}"
			(at -0.939 4.599 0)
			(layer "F.Fab")
			(effects
				(font
					(size 0.7 0.7)
					(thickness 0.15)
				)
				(justify left bottom)
			)
		)
		(fp_text user "Author: Antmicro"
			(at -0.939 3.399 0)
			(layer "F.Fab")
			(effects
				(font
					(size 0.7 0.7)
					(thickness 0.15)
				)
				(justify left bottom)
			)
		)
		(fp_text user "License: Apache-2.0"
			(at -0.939 5.799 0)
			(layer "F.Fab")
			(effects
				(font
					(size 0.7 0.7)
					(thickness 0.15)
				)
				(justify left bottom)
			)
		)
		(pad "1" smd roundrect
			(at -0.48 0)
			(size 0.59 0.64)
			(layers "F.Cu" "F.Mask" "F.Paste")
			(roundrect_rratio 0.25)
			(net 23 "GND")
			(pintype "passive")
		)
		(pad "2" smd roundrect
			(at 0.48 0)
			(size 0.59 0.64)
			(layers "F.Cu" "F.Mask" "F.Paste")
			(roundrect_rratio 0.25)
			(net 59 "/X710-AT2 Misc/50MHZ_XTAL_R.-")
			(pintype "passive")
		)
	)
	(footprint "antmicro-footprints:C_0603_1608Metric_EIA"
		(layer "F.Cu")
		(at 151.850002 103.050001 -90)
		(descr "Capacitor SMD 0603, IPC-7351 Density Level A")
		(tags "Capacitor 0603")
		(property "Reference" "C141"
			(at 17.649996 -14.449998 270)
			(layer "F.SilkS")
			(effects
				(font
					(size 0.7 0.7)
					(thickness 0.15)
				)
			)
		)
		(property "Value" "C_22u_16V_0603"
			(at -1.42757 1.770288 270)
			(layer "F.Fab")
			(effects
				(font
					(size 0.7 0.7)
					(thickness 0.15)
				)
				(justify left bottom)
			)
		)
		(property "Datasheet" "https://product.samsungsem.com/mlcc/CL10A226MO7JZN.do"
			(at 0 0 270)
			(layer "F.Fab")
			(hide yes)
			(effects
				(font
					(size 1.27 1.27)
					(thickness 0.15)
				)
			)
		)
		(property "Description" "SMD Multilayer Ceramic Capacitor"
			(at 0 0 270)
			(layer "F.Fab")
			(hide yes)
			(effects
				(font
					(size 1.27 1.27)
					(thickness 0.15)
				)
			)
		)
		(property "MPN" "CL10A226MO7JZNC"
			(at 0 0 270)
			(unlocked yes)
			(layer "F.Fab")
			(hide yes)
			(effects
				(font
					(size 1 1)
					(thickness 0.15)
				)
			)
		)
		(property "Manufacturer" "Samsung Electro-Mechanics"
			(at 0 0 270)
			(unlocked yes)
			(layer "F.Fab")
			(hide yes)
			(effects
				(font
					(size 1 1)
					(thickness 0.15)
				)
			)
		)
		(property "License" "Apache-2.0"
			(at 0 0 270)
			(unlocked yes)
			(layer "F.Fab")
			(hide yes)
			(effects
				(font
					(size 1 1)
					(thickness 0.15)
				)
			)
		)
		(property "Author" "Antmicro"
			(at 0 0 270)
			(unlocked yes)
			(layer "F.Fab")
			(hide yes)
			(effects
				(font
					(size 1 1)
					(thickness 0.15)
				)
			)
		)
		(property "Val" "22u"
			(at 0 0 270)
			(unlocked yes)
			(layer "F.Fab")
			(hide yes)
			(effects
				(font
					(size 1 1)
					(thickness 0.15)
				)
			)
		)
		(property "Voltage" "16V"
			(at 0 0 270)
			(unlocked yes)
			(layer "F.Fab")
			(hide yes)
			(effects
				(font
					(size 1 1)
					(thickness 0.15)
				)
			)
		)
		(property "Dielectric" ""
			(at 0 0 270)
			(unlocked yes)
			(layer "F.Fab")
			(hide yes)
			(effects
				(font
					(size 1 1)
					(thickness 0.15)
				)
			)
		)
		(sheetname "/X710 DCDC converters/")
		(sheetfile "DCDC_converters_X710.kicad_sch")
		(attr smd)
		(fp_line
			(start -0.15 0.55)
			(end 0.15 0.55)
			(stroke
				(width 0.15)
				(type solid)
			)
			(layer "F.SilkS")
		)
		(fp_line
			(start -0.15 -0.55)
			(end 0.15 -0.55)
			(stroke
				(width 0.15)
				(type solid)
			)
			(layer "F.SilkS")
		)
		(fp_rect
			(start -1.25 -0.65)
			(end 1.25 0.65)
			(stroke
				(width 0.05)
				(type solid)
			)
			(fill no)
			(layer "F.CrtYd")
		)
		(fp_rect
			(start -0.8 -0.45)
			(end 0.8 0.45)
			(stroke
				(width 0.15)
				(type solid)
			)
			(fill no)
			(layer "F.Fab")
		)
		(fp_text user "License: Apache-2.0"
			(at -1.682 5.895 270)
			(layer "F.Fab")
			(effects
				(font
					(size 0.7 0.7)
					(thickness 0.15)
				)
				(justify left bottom)
			)
		)
		(fp_text user "Author: Antmicro"
			(at -1.682 4.894 270)
			(layer "F.Fab")
			(effects
				(font
					(size 0.7 0.7)
					(thickness 0.15)
				)
				(justify left bottom)
			)
		)
		(fp_text user "${REFERENCE}"
			(at -1.682 3.895 270)
			(layer "F.Fab")
			(effects
				(font
					(size 0.7 0.7)
					(thickness 0.15)
				)
				(justify left bottom)
			)
		)
		(pad "1" smd roundrect
			(at -0.7 0 270)
			(size 0.8 1.1)
			(layers "F.Cu" "F.Mask" "F.Paste")
			(roundrect_rratio 0.2)
			(net 23 "GND")
			(pintype "passive")
		)
		(pad "2" smd roundrect
			(at 0.7 0 270)
			(size 0.8 1.1)
			(layers "F.Cu" "F.Mask" "F.Paste")
			(roundrect_rratio 0.2)
			(net 338 "/X710 DCDC converters/+1V88_OUT")
			(pintype "passive")
		)
	)
	(footprint "antmicro-footprints:R_0402_1005Metric"
		(layer "F.Cu")
		(at 137 60.4)
		(descr "Resistor SMD 0402")
		(tags "resistor SMD 0402")
		(property "Reference" "R236"
			(at 0.6 5.8 0)
			(layer "F.SilkS")
			(effects
				(font
					(size 0.7 0.7)
					(thickness 0.15)
				)
				(justify left bottom)
			)
		)
		(property "Value" "R_0R_0402"
			(at -1.011843 1.772047 0)
			(layer "F.Fab")
			(effects
				(font
					(size 0.7 0.7)
					(thickness 0.15)
				)
				(justify left bottom)
			)
		)
		(property "Datasheet" "https://industrial.panasonic.com/cdbs/www-data/pdf/RDA0000/AOA0000C301.pdf"
			(at 0 0 0)
			(layer "F.Fab")
			(hide yes)
			(effects
				(font
					(size 1.27 1.27)
					(thickness 0.15)
				)
			)
		)
		(property "Description" "SMD Chip Resistor, Jumper, 0 ohm, 100 mW, 0402 [1005 Metric], Thick Film, General Purpose"
			(at 0 0 0)
			(layer "F.Fab")
			(hide yes)
			(effects
				(font
					(size 1.27 1.27)
					(thickness 0.15)
				)
			)
		)
		(property "MPN" "ERJ2GE0R00X"
			(at 0 0 0)
			(unlocked yes)
			(layer "F.Fab")
			(hide yes)
			(effects
				(font
					(size 1 1)
					(thickness 0.15)
				)
			)
		)
		(property "Manufacturer" "Panasonic"
			(at 0 0 0)
			(unlocked yes)
			(layer "F.Fab")
			(hide yes)
			(effects
				(font
					(size 1 1)
					(thickness 0.15)
				)
			)
		)
		(property "License" "Apache-2.0"
			(at 0 0 0)
			(unlocked yes)
			(layer "F.Fab")
			(hide yes)
			(effects
				(font
					(size 1 1)
					(thickness 0.15)
				)
			)
		)
		(property "Author" "Antmicro"
			(at 0 0 0)
			(unlocked yes)
			(layer "F.Fab")
			(hide yes)
			(effects
				(font
					(size 1 1)
					(thickness 0.15)
				)
			)
		)
		(property "Val" "0R"
			(at 0 0 0)
			(unlocked yes)
			(layer "F.Fab")
			(hide yes)
			(effects
				(font
					(size 1 1)
					(thickness 0.15)
				)
			)
		)
		(property "Tolerance" "~"
			(at 0 0 0)
			(unlocked yes)
			(layer "F.Fab")
			(hide yes)
			(effects
				(font
					(size 1 1)
					(thickness 0.15)
				)
			)
		)
		(property "Current" "1A"
			(at 0 0 0)
			(unlocked yes)
			(layer "F.Fab")
			(hide yes)
			(effects
				(font
					(size 1 1)
					(thickness 0.15)
				)
			)
		)
		(sheetname "/Power input/")
		(sheetfile "power_input.kicad_sch")
		(attr smd)
		(fp_rect
			(start -0.925 -0.47)
			(end 0.925 0.47)
			(stroke
				(width 0.05)
				(type default)
			)
			(fill no)
			(layer "F.CrtYd")
		)
		(fp_rect
			(start -0.5 -0.25)
			(end 0.5 0.25)
			(stroke
				(width 0.15)
				(type solid)
			)
			(fill no)
			(layer "F.Fab")
		)
		(fp_text user "Author: Antmicro"
			(at -0.95 4.169 0)
			(layer "F.Fab")
			(effects
				(font
					(size 0.7 0.7)
					(thickness 0.15)
				)
				(justify left bottom)
			)
		)
		(fp_text user "License: Apache-2.0"
			(at -0.95 5.169 0)
			(layer "F.Fab")
			(effects
				(font
					(size 0.7 0.7)
					(thickness 0.15)
				)
				(justify left bottom)
			)
		)
		(fp_text user "${REFERENCE}"
			(at -0.95 3.168 0)
			(layer "F.Fab")
			(effects
				(font
					(size 0.7 0.7)
					(thickness 0.15)
				)
				(justify left bottom)
			)
		)
		(pad "1" smd roundrect
			(at -0.48 0)
			(size 0.59 0.64)
			(layers "F.Cu" "F.Mask" "F.Paste")
			(roundrect_rratio 0.25)
			(net 13 "/Power input/5V_JACK")
			(pintype "passive")
		)
		(pad "2" smd roundrect
			(at 0.48 0)
			(size 0.59 0.64)
			(layers "F.Cu" "F.Mask" "F.Paste")
			(roundrect_rratio 0.25)
			(net 433 "Net-(Q8-G)")
			(pintype "passive")
		)
	)
	(footprint "antmicro-footprints:C_2220_5650Metric"
		(layer "F.Cu")
		(at 143 51 90)
		(descr "Capacitor SMD 2220")
		(tags "capacitor SMD 2220")
		(property "Reference" "C311"
			(at 3.6 0.25 180)
			(layer "F.SilkS")
			(effects
				(font
					(size 0.7 0.7)
					(thickness 0.15)
				)
				(justify left bottom)
			)
		)
		(property "Value" "C_22u_100V_2220"
			(at 0 3.9 90)
			(layer "F.Fab")
			(effects
				(font
					(size 0.7 0.7)
					(thickness 0.15)
				)
				(justify left bottom)
			)
		)
		(property "Datasheet" "https://product.tdk.com/en/search/capacitor/ceramic/mlcc/info?part_no=C5750X7S2A226M280KB"
			(at 0 0 90)
			(layer "F.Fab")
			(hide yes)
			(effects
				(font
					(size 1.27 1.27)
					(thickness 0.15)
				)
			)
		)
		(property "Description" "SMT Multilayer Ceramic Capacitor, 22 µF, 100 V, 2220 [5750 Metric], ± 20%, X7S, C"
			(at 0 0 90)
			(layer "F.Fab")
			(hide yes)
			(effects
				(font
					(size 1.27 1.27)
					(thickness 0.15)
				)
			)
		)
		(property "MPN" "C5750X7S2A226M280KB"
			(at 0 0 90)
			(unlocked yes)
			(layer "F.Fab")
			(hide yes)
			(effects
				(font
					(size 1 1)
					(thickness 0.15)
				)
			)
		)
		(property "Manufacturer" "TDK"
			(at 0 0 90)
			(unlocked yes)
			(layer "F.Fab")
			(hide yes)
			(effects
				(font
					(size 1 1)
					(thickness 0.15)
				)
			)
		)
		(property "License" "Apache-2.0"
			(at 0 0 90)
			(unlocked yes)
			(layer "F.Fab")
			(hide yes)
			(effects
				(font
					(size 1 1)
					(thickness 0.15)
				)
			)
		)
		(property "Author" "Antmicro"
			(at 0 0 90)
			(unlocked yes)
			(layer "F.Fab")
			(hide yes)
			(effects
				(font
					(size 1 1)
					(thickness 0.15)
				)
			)
		)
		(property "Val" "22u"
			(at 0 0 90)
			(unlocked yes)
			(layer "F.Fab")
			(hide yes)
			(effects
				(font
					(size 1 1)
					(thickness 0.15)
				)
			)
		)
		(property "Voltage" "100V"
			(at 0 0 90)
			(unlocked yes)
			(layer "F.Fab")
			(hide yes)
			(effects
				(font
					(size 1 1)
					(thickness 0.15)
				)
			)
		)
		(property "Dielectric" "X7S"
			(at 0 0 90)
			(unlocked yes)
			(layer "F.Fab")
			(hide yes)
			(effects
				(font
					(size 1 1)
					(thickness 0.15)
				)
			)
		)
		(property "Public" "False"
			(at 0 0 90)
			(unlocked yes)
			(layer "F.Fab")
			(hide yes)
			(effects
				(font
					(size 1 1)
					(thickness 0.15)
				)
			)
		)
		(sheetname "/Power input/")
		(sheetfile "power_input.kicad_sch")
		(attr smd)
		(fp_line
			(start -1.415 -2.61)
			(end 1.415 -2.61)
			(stroke
				(width 0.15)
				(type solid)
			)
			(layer "F.SilkS")
		)
		(fp_line
			(start -1.415 2.61)
			(end 1.415 2.61)
			(stroke
				(width 0.15)
				(type solid)
			)
			(layer "F.SilkS")
		)
		(fp_rect
			(start -3.7 -2.95)
			(end 3.7 2.95)
			(stroke
				(width 0.05)
				(type solid)
			)
			(fill no)
			(layer "F.CrtYd")
		)
		(fp_rect
			(start -2.85 -2.5)
			(end 2.85 2.5)
			(stroke
				(width 0.15)
				(type solid)
			)
			(fill no)
			(layer "F.Fab")
		)
		(fp_text user "License: Apache-2.0"
			(at -3.7 6.9 90)
			(layer "F.Fab")
			(effects
				(font
					(size 0.7 0.7)
					(thickness 0.15)
				)
				(justify left bottom)
			)
		)
		(fp_text user "${REFERENCE}"
			(at -3.7 5.9 90)
			(layer "F.Fab")
			(effects
				(font
					(size 0.7 0.7)
					(thickness 0.15)
				)
				(justify left bottom)
			)
		)
		(fp_text user "Author: Antmicro"
			(at -3.7 7.9 90)
			(layer "F.Fab")
			(effects
				(font
					(size 0.7 0.7)
					(thickness 0.15)
				)
				(justify left bottom)
			)
		)
		(pad "1" smd roundrect
			(at -2.55 0 90)
			(size 1.8 5.4)
			(layers "F.Cu" "F.Mask" "F.Paste")
			(roundrect_rratio 0.138889)
			(net 23 "GND")
			(pintype "passive")
		)
		(pad "2" smd roundrect
			(at 2.55 0 90)
			(size 1.8 5.4)
			(layers "F.Cu" "F.Mask" "F.Paste")
			(roundrect_rratio 0.138889)
			(net 412 "Net-(D15-C)")
			(pintype "passive")
		)
	)
	(footprint "antmicro-footprints:C_0603_1608Metric_EIA"
		(layer "F.Cu")
		(at 154.900001 114.35)
		(descr "Capacitor SMD 0603, IPC-7351 Density Level A")
		(tags "Capacitor 0603")
		(property "Reference" "C106"
			(at 13.650003 16.600001 0)
			(layer "F.SilkS")
			(effects
				(font
					(size 0.7 0.7)
					(thickness 0.15)
				)
			)
		)
		(property "Value" "C_22u_16V_0603"
			(at -1.42757 1.770288 0)
			(layer "F.Fab")
			(effects
				(font
					(size 0.7 0.7)
					(thickness 0.15)
				)
				(justify left bottom)
			)
		)
		(property "Datasheet" "https://product.samsungsem.com/mlcc/CL10A226MO7JZN.do"
			(at 0 0 0)
			(layer "F.Fab")
			(hide yes)
			(effects
				(font
					(size 1.27 1.27)
					(thickness 0.15)
				)
			)
		)
		(property "Description" "SMD Multilayer Ceramic Capacitor"
			(at 0 0 0)
			(layer "F.Fab")
			(hide yes)
			(effects
				(font
					(size 1.27 1.27)
					(thickness 0.15)
				)
			)
		)
		(property "MPN" "CL10A226MO7JZNC"
			(at 0 0 0)
			(unlocked yes)
			(layer "F.Fab")
			(hide yes)
			(effects
				(font
					(size 1 1)
					(thickness 0.15)
				)
			)
		)
		(property "Manufacturer" "Samsung Electro-Mechanics"
			(at 0 0 0)
			(unlocked yes)
			(layer "F.Fab")
			(hide yes)
			(effects
				(font
					(size 1 1)
					(thickness 0.15)
				)
			)
		)
		(property "License" "Apache-2.0"
			(at 0 0 0)
			(unlocked yes)
			(layer "F.Fab")
			(hide yes)
			(effects
				(font
					(size 1 1)
					(thickness 0.15)
				)
			)
		)
		(property "Author" "Antmicro"
			(at 0 0 0)
			(unlocked yes)
			(layer "F.Fab")
			(hide yes)
			(effects
				(font
					(size 1 1)
					(thickness 0.15)
				)
			)
		)
		(property "Val" "22u"
			(at 0 0 0)
			(unlocked yes)
			(layer "F.Fab")
			(hide yes)
			(effects
				(font
					(size 1 1)
					(thickness 0.15)
				)
			)
		)
		(property "Voltage" "16V"
			(at 0 0 0)
			(unlocked yes)
			(layer "F.Fab")
			(hide yes)
			(effects
				(font
					(size 1 1)
					(thickness 0.15)
				)
			)
		)
		(property "Dielectric" ""
			(at 0 0 0)
			(unlocked yes)
			(layer "F.Fab")
			(hide yes)
			(effects
				(font
					(size 1 1)
					(thickness 0.15)
				)
			)
		)
		(sheetname "/X710 DCDC converters/")
		(sheetfile "DCDC_converters_X710.kicad_sch")
		(attr smd)
		(fp_line
			(start -0.15 -0.55)
			(end 0.15 -0.55)
			(stroke
				(width 0.15)
				(type solid)
			)
			(layer "F.SilkS")
		)
		(fp_line
			(start -0.15 0.55)
			(end 0.15 0.55)
			(stroke
				(width 0.15)
				(type solid)
			)
			(layer "F.SilkS")
		)
		(fp_rect
			(start -1.25 -0.65)
			(end 1.25 0.65)
			(stroke
				(width 0.05)
				(type solid)
			)
			(fill no)
			(layer "F.CrtYd")
		)
		(fp_rect
			(start -0.8 -0.45)
			(end 0.8 0.45)
			(stroke
				(width 0.15)
				(type solid)
			)
			(fill no)
			(layer "F.Fab")
		)
		(fp_text user "Author: Antmicro"
			(at -1.682 4.894 0)
			(layer "F.Fab")
			(effects
				(font
					(size 0.7 0.7)
					(thickness 0.15)
				)
				(justify left bottom)
			)
		)
		(fp_text user "License: Apache-2.0"
			(at -1.682 5.895 0)
			(layer "F.Fab")
			(effects
				(font
					(size 0.7 0.7)
					(thickness 0.15)
				)
				(justify left bottom)
			)
		)
		(fp_text user "${REFERENCE}"
			(at -1.682 3.895 0)
			(layer "F.Fab")
			(effects
				(font
					(size 0.7 0.7)
					(thickness 0.15)
				)
				(justify left bottom)
			)
		)
		(pad "1" smd roundrect
			(at -0.7 0)
			(size 0.8 1.1)
			(layers "F.Cu" "F.Mask" "F.Paste")
			(roundrect_rratio 0.2)
			(net 23 "GND")
			(pintype "passive")
		)
		(pad "2" smd roundrect
			(at 0.7 0)
			(size 0.8 1.1)
			(layers "F.Cu" "F.Mask" "F.Paste")
			(roundrect_rratio 0.2)
			(net 40 "+5V")
			(pintype "passive")
		)
	)
	(footprint "antmicro-footprints:C_0402_1005Metric"
		(layer "F.Cu")
		(at 138 78.75)
		(descr "Capacitor SMD 0402")
		(tags "capacitor SMD 0402")
		(property "Reference" "C268"
			(at -3.8 0.45 0)
			(layer "F.SilkS")
			(effects
				(font
					(size 0.7 0.7)
					(thickness 0.15)
				)
				(justify left bottom)
			)
		)
		(property "Value" "C_220n_16V_0402"
			(at -1.022927 2.155213 0)
			(layer "F.Fab")
			(effects
				(font
					(size 0.7 0.7)
					(thickness 0.15)
				)
				(justify left bottom)
			)
		)
		(property "Datasheet" "https://www.murata.com/products/productdetail?partno=GRM155R71C224KA12%23"
			(at 0 0 0)
			(layer "F.Fab")
			(hide yes)
			(effects
				(font
					(size 1.27 1.27)
					(thickness 0.15)
				)
			)
		)
		(property "Description" "SMD Multilayer Ceramic Capacitor, 0.22 µF, 16 V, 0402 [1005 Metric], ± 10%, X7R, GRM Series"
			(at 0 0 0)
			(layer "F.Fab")
			(hide yes)
			(effects
				(font
					(size 1.27 1.27)
					(thickness 0.15)
				)
			)
		)
		(property "MPN" "GRM155R71C224KA12D"
			(at 0 0 0)
			(unlocked yes)
			(layer "F.Fab")
			(hide yes)
			(effects
				(font
					(size 1 1)
					(thickness 0.15)
				)
			)
		)
		(property "Manufacturer" "Murata"
			(at 0 0 0)
			(unlocked yes)
			(layer "F.Fab")
			(hide yes)
			(effects
				(font
					(size 1 1)
					(thickness 0.15)
				)
			)
		)
		(property "License" "Apache-2.0"
			(at 0 0 0)
			(unlocked yes)
			(layer "F.Fab")
			(hide yes)
			(effects
				(font
					(size 1 1)
					(thickness 0.15)
				)
			)
		)
		(property "Author" "Antmicro"
			(at 0 0 0)
			(unlocked yes)
			(layer "F.Fab")
			(hide yes)
			(effects
				(font
					(size 1 1)
					(thickness 0.15)
				)
			)
		)
		(property "Val" "220n"
			(at 0 0 0)
			(unlocked yes)
			(layer "F.Fab")
			(hide yes)
			(effects
				(font
					(size 1 1)
					(thickness 0.15)
				)
			)
		)
		(property "Voltage" "16V"
			(at 0 0 0)
			(unlocked yes)
			(layer "F.Fab")
			(hide yes)
			(effects
				(font
					(size 1 1)
					(thickness 0.15)
				)
			)
		)
		(property "Dielectric" "X7R"
			(at 0 0 0)
			(unlocked yes)
			(layer "F.Fab")
			(hide yes)
			(effects
				(font
					(size 1 1)
					(thickness 0.15)
				)
			)
		)
		(sheetname "/X710-AT2 PCIe/")
		(sheetfile "x710-at2-pcie.kicad_sch")
		(attr smd)
		(fp_rect
			(start -0.925 -0.47)
			(end 0.925 0.47)
			(stroke
				(width 0.05)
				(type default)
			)
			(fill no)
			(layer "F.CrtYd")
		)
		(fp_line
			(start -0.494 -0.25)
			(end 0.504 -0.25)
			(stroke
				(width 0.15)
				(type solid)
			)
			(layer "F.Fab")
		)
		(fp_line
			(start -0.494 0.248)
			(end -0.494 -0.25)
			(stroke
				(width 0.15)
				(type solid)
			)
			(layer "F.Fab")
		)
		(fp_line
			(start 0.504 -0.25)
			(end 0.504 0.248)
			(stroke
				(width 0.15)
				(type solid)
			)
			(layer "F.Fab")
		)
		(fp_line
			(start 0.504 0.248)
			(end -0.494 0.248)
			(stroke
				(width 0.15)
				(type solid)
			)
			(layer "F.Fab")
		)
		(fp_text user "License: Apache-2.0"
			(at -0.939 5.799 0)
			(layer "F.Fab")
			(effects
				(font
					(size 0.7 0.7)
					(thickness 0.15)
				)
				(justify left bottom)
			)
		)
		(fp_text user "Author: Antmicro"
			(at -0.939 3.399 0)
			(layer "F.Fab")
			(effects
				(font
					(size 0.7 0.7)
					(thickness 0.15)
				)
				(justify left bottom)
			)
		)
		(fp_text user "${REFERENCE}"
			(at -0.939 4.599 0)
			(layer "F.Fab")
			(effects
				(font
					(size 0.7 0.7)
					(thickness 0.15)
				)
				(justify left bottom)
			)
		)
		(pad "1" smd roundrect
			(at -0.48 0)
			(size 0.59 0.64)
			(layers "F.Cu" "F.Mask" "F.Paste")
			(roundrect_rratio 0.25)
			(net 598 "/TB Controller/PCIex4.TX2-")
			(pintype "passive")
		)
		(pad "2" smd roundrect
			(at 0.48 0)
			(size 0.59 0.64)
			(layers "F.Cu" "F.Mask" "F.Paste")
			(roundrect_rratio 0.25)
			(net 32 "/X710-AT2 PCIe/PCIe_{x4}_AC.TX2-")
			(pintype "passive")
		)
	)
	(footprint "antmicro-footprints:C_0402_1005Metric"
		(layer "F.Cu")
		(at 117.8 122 180)
		(descr "Capacitor SMD 0402")
		(tags "capacitor SMD 0402")
		(property "Reference" "C49"
			(at -0.8 -0.2 180)
			(layer "F.SilkS")
			(effects
				(font
					(size 0.7 0.7)
					(thickness 0.15)
				)
				(justify left bottom)
			)
		)
		(property "Value" "C_220n_0402"
			(at -1.022927 2.155213 180)
			(layer "F.Fab")
			(effects
				(font
					(size 0.7 0.7)
					(thickness 0.15)
				)
				(justify left bottom)
			)
		)
		(property "Datasheet" "https://www.yageo.com/en/Chart/Download/pdf/CC0402KRX5R6BB224"
			(at 0 0 180)
			(layer "F.Fab")
			(hide yes)
			(effects
				(font
					(size 1.27 1.27)
					(thickness 0.15)
				)
			)
		)
		(property "Description" "SMD Multilayer Ceramic Capacitor, 0.22 µF, 10 V, 0402 [1005 Metric], ± 10%, X5R, CC Series"
			(at 0 0 180)
			(layer "F.Fab")
			(hide yes)
			(effects
				(font
					(size 1.27 1.27)
					(thickness 0.15)
				)
			)
		)
		(property "MPN" "CC0402KRX5R6BB224"
			(at 0 0 180)
			(unlocked yes)
			(layer "F.Fab")
			(hide yes)
			(effects
				(font
					(size 1 1)
					(thickness 0.15)
				)
			)
		)
		(property "Manufacturer" "YAGEO"
			(at 0 0 180)
			(unlocked yes)
			(layer "F.Fab")
			(hide yes)
			(effects
				(font
					(size 1 1)
					(thickness 0.15)
				)
			)
		)
		(property "License" "Apache-2.0"
			(at 0 0 180)
			(unlocked yes)
			(layer "F.Fab")
			(hide yes)
			(effects
				(font
					(size 1 1)
					(thickness 0.15)
				)
			)
		)
		(property "Val" "220n"
			(at 0 0 180)
			(unlocked yes)
			(layer "F.Fab")
			(hide yes)
			(effects
				(font
					(size 1 1)
					(thickness 0.15)
				)
			)
		)
		(property "Voltage" ""
			(at 0 0 180)
			(unlocked yes)
			(layer "F.Fab")
			(hide yes)
			(effects
				(font
					(size 1 1)
					(thickness 0.15)
				)
			)
		)
		(property "Dielectric" ""
			(at 0 0 180)
			(unlocked yes)
			(layer "F.Fab")
			(hide yes)
			(effects
				(font
					(size 1 1)
					(thickness 0.15)
				)
			)
		)
		(property "Author" "Antmicro"
			(at 0 0 180)
			(unlocked yes)
			(layer "F.Fab")
			(hide yes)
			(effects
				(font
					(size 1 1)
					(thickness 0.15)
				)
			)
		)
		(sheetname "/TB Controller/")
		(sheetfile "tb.kicad_sch")
		(attr smd)
		(fp_rect
			(start -0.925 -0.47)
			(end 0.925 0.47)
			(stroke
				(width 0.05)
				(type default)
			)
			(fill no)
			(layer "F.CrtYd")
		)
		(fp_line
			(start 0.504 0.248)
			(end -0.494 0.248)
			(stroke
				(width 0.15)
				(type solid)
			)
			(layer "F.Fab")
		)
		(fp_line
			(start 0.504 -0.25)
			(end 0.504 0.248)
			(stroke
				(width 0.15)
				(type solid)
			)
			(layer "F.Fab")
		)
		(fp_line
			(start -0.494 0.248)
			(end -0.494 -0.25)
			(stroke
				(width 0.15)
				(type solid)
			)
			(layer "F.Fab")
		)
		(fp_line
			(start -0.494 -0.25)
			(end 0.504 -0.25)
			(stroke
				(width 0.15)
				(type solid)
			)
			(layer "F.Fab")
		)
		(fp_text user "Author: Antmicro"
			(at -0.939 3.399 180)
			(layer "F.Fab")
			(effects
				(font
					(size 0.7 0.7)
					(thickness 0.15)
				)
				(justify left bottom)
			)
		)
		(fp_text user "License: Apache-2.0"
			(at -0.939 5.799 180)
			(layer "F.Fab")
			(effects
				(font
					(size 0.7 0.7)
					(thickness 0.15)
				)
				(justify left bottom)
			)
		)
		(fp_text user "${REFERENCE}"
			(at -0.939 4.599 180)
			(layer "F.Fab")
			(effects
				(font
					(size 0.7 0.7)
					(thickness 0.15)
				)
				(justify left bottom)
			)
		)
		(pad "1" smd roundrect
			(at -0.48 0 180)
			(size 0.59 0.64)
			(layers "F.Cu" "F.Mask" "F.Paste")
			(roundrect_rratio 0.25)
			(net 316 "/TB Controller/TB_PCIE_TX1_N")
			(pintype "passive")
		)
		(pad "2" smd roundrect
			(at 0.48 0 180)
			(size 0.59 0.64)
			(layers "F.Cu" "F.Mask" "F.Paste")
			(roundrect_rratio 0.25)
			(net 324 "/TB Controller/PCIex4.RX1-")
			(pintype "passive")
		)
	)
	(footprint "antmicro-footprints:R_0402_1005Metric"
		(layer "F.Cu")
		(at 117 67.5 180)
		(descr "Resistor SMD 0402")
		(tags "resistor SMD 0402")
		(property "Reference" "R135"
			(at -3 -1.4 180)
			(layer "F.SilkS")
			(effects
				(font
					(size 0.7 0.7)
					(thickness 0.15)
				)
				(justify left bottom)
			)
		)
		(property "Value" "R_1k_0402"
			(at -1.011843 1.772047 180)
			(layer "F.Fab")
			(effects
				(font
					(size 0.7 0.7)
					(thickness 0.15)
				)
				(justify left bottom)
			)
		)
		(property "Datasheet" "https://www.bourns.com/docs/product-datasheets/cr.pdf"
			(at 0 0 180)
			(layer "F.Fab")
			(hide yes)
			(effects
				(font
					(size 1.27 1.27)
					(thickness 0.15)
				)
			)
		)
		(property "Description" "SMD Chip Resistor, 1 kohm, ± 1%, 63 mW, 0402 [1005 Metric], Thick Film, General Purpose"
			(at 0 0 180)
			(layer "F.Fab")
			(hide yes)
			(effects
				(font
					(size 1.27 1.27)
					(thickness 0.15)
				)
			)
		)
		(property "MPN" "CR0402-FX-1001GLF"
			(at 0 0 180)
			(unlocked yes)
			(layer "F.Fab")
			(hide yes)
			(effects
				(font
					(size 1 1)
					(thickness 0.15)
				)
			)
		)
		(property "Manufacturer" "Bourns"
			(at 0 0 180)
			(unlocked yes)
			(layer "F.Fab")
			(hide yes)
			(effects
				(font
					(size 1 1)
					(thickness 0.15)
				)
			)
		)
		(property "License" "Apache-2.0"
			(at 0 0 180)
			(unlocked yes)
			(layer "F.Fab")
			(hide yes)
			(effects
				(font
					(size 1 1)
					(thickness 0.15)
				)
			)
		)
		(property "Author" "Antmicro"
			(at 0 0 180)
			(unlocked yes)
			(layer "F.Fab")
			(hide yes)
			(effects
				(font
					(size 1 1)
					(thickness 0.15)
				)
			)
		)
		(property "Val" "1k"
			(at 0 0 180)
			(unlocked yes)
			(layer "F.Fab")
			(hide yes)
			(effects
				(font
					(size 1 1)
					(thickness 0.15)
				)
			)
		)
		(property "Tolerance" "1%"
			(at 0 0 180)
			(unlocked yes)
			(layer "F.Fab")
			(hide yes)
			(effects
				(font
					(size 1 1)
					(thickness 0.15)
				)
			)
		)
		(sheetname "/X710-AT2 RSVD/")
		(sheetfile "x710-at2-rsvd.kicad_sch")
		(attr smd)
		(fp_rect
			(start -0.925 -0.47)
			(end 0.925 0.47)
			(stroke
				(width 0.05)
				(type default)
			)
			(fill no)
			(layer "F.CrtYd")
		)
		(fp_rect
			(start -0.5 -0.25)
			(end 0.5 0.25)
			(stroke
				(width 0.15)
				(type solid)
			)
			(fill no)
			(layer "F.Fab")
		)
		(fp_text user "Author: Antmicro"
			(at -0.95 4.169 180)
			(layer "F.Fab")
			(effects
				(font
					(size 0.7 0.7)
					(thickness 0.15)
				)
				(justify left bottom)
			)
		)
		(fp_text user "${REFERENCE}"
			(at -0.95 3.168 180)
			(layer "F.Fab")
			(effects
				(font
					(size 0.7 0.7)
					(thickness 0.15)
				)
				(justify left bottom)
			)
		)
		(fp_text user "License: Apache-2.0"
			(at -0.95 5.169 180)
			(layer "F.Fab")
			(effects
				(font
					(size 0.7 0.7)
					(thickness 0.15)
				)
				(justify left bottom)
			)
		)
		(pad "1" smd roundrect
			(at -0.48 0 180)
			(size 0.59 0.64)
			(layers "F.Cu" "F.Mask" "F.Paste")
			(roundrect_rratio 0.25)
			(net 91 "/X710-AT2 RSVD/DEBUG_Y16")
			(pintype "passive")
		)
		(pad "2" smd roundrect
			(at 0.48 0 180)
			(size 0.59 0.64)
			(layers "F.Cu" "F.Mask" "F.Paste")
			(roundrect_rratio 0.25)
			(net 86 "/X710-AT2 RSVD/DEBUG_EN")
			(pintype "passive")
		)
	)
	(footprint "antmicro-footprints:SOD-523"
		(layer "F.Cu")
		(at 130.2 70.2)
		(property "Reference" "D14"
			(at -1 -1.8 0)
			(layer "F.SilkS")
			(effects
				(font
					(size 0.7 0.7)
					(thickness 0.15)
				)
				(justify left bottom)
			)
		)
		(property "Value" "RB521S30T1G"
			(at 0 1.499 0)
			(layer "F.Fab")
			(effects
				(font
					(size 0.7 0.7)
					(thickness 0.15)
				)
				(justify left bottom)
			)
		)
		(property "Datasheet" "https://www.onsemi.com/pdf/datasheet/rb521s30t1-d.pdf"
			(at 0 0 0)
			(layer "F.Fab")
			(hide yes)
			(effects
				(font
					(size 1.27 1.27)
					(thickness 0.15)
				)
			)
		)
		(property "Description" "Small Signal Schottky Diode, Single, 30 V, 200 mA, 500 mV, 1 A, 125 °C"
			(at 0 0 0)
			(layer "F.Fab")
			(hide yes)
			(effects
				(font
					(size 1.27 1.27)
					(thickness 0.15)
				)
			)
		)
		(property "MPN" "RB521S30T1G"
			(at 0 0 0)
			(unlocked yes)
			(layer "F.Fab")
			(hide yes)
			(effects
				(font
					(size 1 1)
					(thickness 0.15)
				)
			)
		)
		(property "Manufacturer" "ON Semiconductor"
			(at 0 0 0)
			(unlocked yes)
			(layer "F.Fab")
			(hide yes)
			(effects
				(font
					(size 1 1)
					(thickness 0.15)
				)
			)
		)
		(property "Author" "Antmicro"
			(at 0 0 0)
			(unlocked yes)
			(layer "F.Fab")
			(hide yes)
			(effects
				(font
					(size 1 1)
					(thickness 0.15)
				)
			)
		)
		(property "License" "Apache-2.0"
			(at 0 0 0)
			(unlocked yes)
			(layer "F.Fab")
			(hide yes)
			(effects
				(font
					(size 1 1)
					(thickness 0.15)
				)
			)
		)
		(sheetname "/X710 flash memory/")
		(sheetfile "flash_x710.kicad_sch")
		(attr smd)
		(fp_line
			(start -0.35 -0.5)
			(end -0.35 0.5)
			(stroke
				(width 0.15)
				(type solid)
			)
			(layer "F.SilkS")
		)
		(fp_rect
			(start -1 -0.6)
			(end 1 0.6)
			(stroke
				(width 0.05)
				(type solid)
			)
			(fill no)
			(layer "F.CrtYd")
		)
		(fp_line
			(start -0.652 -0.425)
			(end 0.65 -0.425)
			(stroke
				(width 0.15)
				(type solid)
			)
			(layer "F.Fab")
		)
		(fp_line
			(start -0.652 0.423)
			(end -0.652 -0.425)
			(stroke
				(width 0.15)
				(type solid)
			)
			(layer "F.Fab")
		)
		(fp_line
			(start -0.652 0.423)
			(end 0.65 0.423)
			(stroke
				(width 0.15)
				(type solid)
			)
			(layer "F.Fab")
		)
		(fp_line
			(start -0.35 -0.4)
			(end -0.35 0.4)
			(stroke
				(width 0.15)
				(type solid)
			)
			(layer "F.Fab")
		)
		(fp_line
			(start 0.65 -0.425)
			(end 0.65 0.423)
			(stroke
				(width 0.15)
				(type solid)
			)
			(layer "F.Fab")
		)
		(fp_text user "${REFERENCE}"
			(at -1.276 3.499 0)
			(layer "F.Fab")
			(effects
				(font
					(size 0.7 0.7)
					(thickness 0.15)
				)
				(justify left bottom)
			)
		)
		(fp_text user "License: Apache-2.0"
			(at -1.276 5.9 0)
			(layer "F.Fab")
			(effects
				(font
					(size 0.7 0.7)
					(thickness 0.15)
				)
				(justify left bottom)
			)
		)
		(fp_text user "Author: Antmicro"
			(at -1.276 4.7 0)
			(layer "F.Fab")
			(effects
				(font
					(size 0.7 0.7)
					(thickness 0.15)
				)
				(justify left bottom)
			)
		)
		(pad "1" smd roundrect
			(at -0.701 0)
			(size 0.5 0.6)
			(layers "F.Cu" "F.Mask" "F.Paste")
			(roundrect_rratio 0.25)
			(net 343 "/X710 flash memory/+3V3_FLASH")
			(pinfunction "C")
			(pintype "passive")
		)
		(pad "2" smd roundrect
			(at 0.699 0)
			(size 0.5 0.6)
			(layers "F.Cu" "F.Mask" "F.Paste")
			(roundrect_rratio 0.25)
			(net 7 "+3V3")
			(pinfunction "A")
			(pintype "passive")
		)
	)
	(footprint "antmicro-footprints:C_0402_1005Metric"
		(layer "F.Cu")
		(at 144.6 61.75 -90)
		(descr "Capacitor SMD 0402")
		(tags "capacitor SMD 0402")
		(property "Reference" "C322"
			(at 2.25 -1.4 270)
			(layer "F.SilkS")
			(effects
				(font
					(size 0.7 0.7)
					(thickness 0.15)
				)
				(justify left bottom)
			)
		)
		(property "Value" "C_100n_0402"
			(at -1.022927 2.155213 270)
			(layer "F.Fab")
			(effects
				(font
					(size 0.7 0.7)
					(thickness 0.15)
				)
				(justify left bottom)
			)
		)
		(property "Datasheet" "https://www.murata.com/products/productdetail?partno=GRM155R61H104KE14%23"
			(at 0 0 270)
			(layer "F.Fab")
			(hide yes)
			(effects
				(font
					(size 1.27 1.27)
					(thickness 0.15)
				)
			)
		)
		(property "Description" "SMD Multilayer Ceramic Capacitor, 0.1 µF, 50 V, 0402 [1005 Metric], ± 10%, X5R, GRM Series"
			(at 0 0 270)
			(layer "F.Fab")
			(hide yes)
			(effects
				(font
					(size 1.27 1.27)
					(thickness 0.15)
				)
			)
		)
		(property "MPN" "GRM155R61H104KE14D"
			(at 0 0 270)
			(unlocked yes)
			(layer "F.Fab")
			(hide yes)
			(effects
				(font
					(size 1 1)
					(thickness 0.15)
				)
			)
		)
		(property "Manufacturer" "Murata"
			(at 0 0 270)
			(unlocked yes)
			(layer "F.Fab")
			(hide yes)
			(effects
				(font
					(size 1 1)
					(thickness 0.15)
				)
			)
		)
		(property "License" "Apache-2.0"
			(at 0 0 270)
			(unlocked yes)
			(layer "F.Fab")
			(hide yes)
			(effects
				(font
					(size 1 1)
					(thickness 0.15)
				)
			)
		)
		(property "Author" "Antmicro"
			(at 0 0 270)
			(unlocked yes)
			(layer "F.Fab")
			(hide yes)
			(effects
				(font
					(size 1 1)
					(thickness 0.15)
				)
			)
		)
		(property "Val" "100n"
			(at 0 0 270)
			(unlocked yes)
			(layer "F.Fab")
			(hide yes)
			(effects
				(font
					(size 1 1)
					(thickness 0.15)
				)
			)
		)
		(property "Voltage" "50V"
			(at 0 0 270)
			(unlocked yes)
			(layer "F.Fab")
			(hide yes)
			(effects
				(font
					(size 1 1)
					(thickness 0.15)
				)
			)
		)
		(property "Dielectric" "X5R"
			(at 0 0 270)
			(unlocked yes)
			(layer "F.Fab")
			(hide yes)
			(effects
				(font
					(size 1 1)
					(thickness 0.15)
				)
			)
		)
		(sheetname "/Power input/")
		(sheetfile "power_input.kicad_sch")
		(attr smd)
		(fp_rect
			(start -0.925 -0.47)
			(end 0.925 0.47)
			(stroke
				(width 0.05)
				(type default)
			)
			(fill no)
			(layer "F.CrtYd")
		)
		(fp_line
			(start -0.494 0.248)
			(end -0.494 -0.25)
			(stroke
				(width 0.15)
				(type solid)
			)
			(layer "F.Fab")
		)
		(fp_line
			(start 0.504 0.248)
			(end -0.494 0.248)
			(stroke
				(width 0.15)
				(type solid)
			)
			(layer "F.Fab")
		)
		(fp_line
			(start -0.494 -0.25)
			(end 0.504 -0.25)
			(stroke
				(width 0.15)
				(type solid)
			)
			(layer "F.Fab")
		)
		(fp_line
			(start 0.504 -0.25)
			(end 0.504 0.248)
			(stroke
				(width 0.15)
				(type solid)
			)
			(layer "F.Fab")
		)
		(fp_text user "Author: Antmicro"
			(at -0.939 3.399 270)
			(layer "F.Fab")
			(effects
				(font
					(size 0.7 0.7)
					(thickness 0.15)
				)
				(justify left bottom)
			)
		)
		(fp_text user "${REFERENCE}"
			(at -0.939 4.599 270)
			(layer "F.Fab")
			(effects
				(font
					(size 0.7 0.7)
					(thickness 0.15)
				)
				(justify left bottom)
			)
		)
		(fp_text user "License: Apache-2.0"
			(at -0.939 5.799 270)
			(layer "F.Fab")
			(effects
				(font
					(size 0.7 0.7)
					(thickness 0.15)
				)
				(justify left bottom)
			)
		)
		(pad "1" smd roundrect
			(at -0.48 0 270)
			(size 0.59 0.64)
			(layers "F.Cu" "F.Mask" "F.Paste")
			(roundrect_rratio 0.25)
			(net 23 "GND")
			(pintype "passive")
		)
		(pad "2" smd roundrect
			(at 0.48 0 270)
			(size 0.59 0.64)
			(layers "F.Cu" "F.Mask" "F.Paste")
			(roundrect_rratio 0.25)
			(net 13 "/Power input/5V_JACK")
			(pintype "passive")
		)
	)
	(footprint "antmicro-footprints:C_0603_1608Metric"
		(layer "F.Cu")
		(at 161.355 93.574999 180)
		(descr "Capacitor SMD 0603")
		(tags "capacitor 0603")
		(property "Reference" "C180"
			(at -7.695 0 180)
			(layer "F.SilkS")
			(effects
				(font
					(size 0.7 0.7)
					(thickness 0.15)
				)
			)
		)
		(property "Value" "C_10u_10V_X7R_0603"
			(at -1.42757 1.770288 180)
			(layer "F.Fab")
			(effects
				(font
					(size 0.7 0.7)
					(thickness 0.15)
				)
				(justify left bottom)
			)
		)
		(property "Datasheet" "https://www.murata.com/products/productdetail?partno=GRM188Z71A106KA73%23"
			(at 0 0 180)
			(layer "F.Fab")
			(hide yes)
			(effects
				(font
					(size 1.27 1.27)
					(thickness 0.15)
				)
			)
		)
		(property "Description" "SMD Multilayer Ceramic Capacitor,  10µF, 10V, 0603, ±10%, X7R"
			(at 0 0 180)
			(layer "F.Fab")
			(hide yes)
			(effects
				(font
					(size 1.27 1.27)
					(thickness 0.15)
				)
			)
		)
		(property "MPN" "GRM188Z71A106KA73D"
			(at 0 0 180)
			(unlocked yes)
			(layer "F.Fab")
			(hide yes)
			(effects
				(font
					(size 1 1)
					(thickness 0.15)
				)
			)
		)
		(property "Val" "10u"
			(at 0 0 180)
			(unlocked yes)
			(layer "F.Fab")
			(hide yes)
			(effects
				(font
					(size 1 1)
					(thickness 0.15)
				)
			)
		)
		(property "Voltage" "10V"
			(at 0 0 180)
			(unlocked yes)
			(layer "F.Fab")
			(hide yes)
			(effects
				(font
					(size 1 1)
					(thickness 0.15)
				)
			)
		)
		(property "Dielectric" "X7R"
			(at 0 0 180)
			(unlocked yes)
			(layer "F.Fab")
			(hide yes)
			(effects
				(font
					(size 1 1)
					(thickness 0.15)
				)
			)
		)
		(property "Manufacturer" "Murata"
			(at 0 0 180)
			(unlocked yes)
			(layer "F.Fab")
			(hide yes)
			(effects
				(font
					(size 1 1)
					(thickness 0.15)
				)
			)
		)
		(property "License" "Apache-2.0"
			(at 0 0 180)
			(unlocked yes)
			(layer "F.Fab")
			(hide yes)
			(effects
				(font
					(size 1 1)
					(thickness 0.15)
				)
			)
		)
		(property "Author" "Antmicro"
			(at 0 0 180)
			(unlocked yes)
			(layer "F.Fab")
			(hide yes)
			(effects
				(font
					(size 1 1)
					(thickness 0.15)
				)
			)
		)
		(sheetname "/X710-AT2 power/")
		(sheetfile "x710-at2-power.kicad_sch")
		(attr smd)
		(fp_line
			(start -0.15 0.4)
			(end 0.15 0.4)
			(stroke
				(width 0.15)
				(type solid)
			)
			(layer "F.SilkS")
		)
		(fp_line
			(start -0.15 -0.4)
			(end 0.15 -0.4)
			(stroke
				(width 0.15)
				(type solid)
			)
			(layer "F.SilkS")
		)
		(fp_rect
			(start -1.25 -0.65)
			(end 1.25 0.65)
			(stroke
				(width 0.05)
				(type solid)
			)
			(fill no)
			(layer "F.CrtYd")
		)
		(fp_rect
			(start -0.8 -0.4)
			(end 0.8 0.4)
			(stroke
				(width 0.15)
				(type solid)
			)
			(fill no)
			(layer "F.Fab")
		)
		(fp_text user "License: Apache-2.0"
			(at -1.682 5.895 180)
			(layer "F.Fab")
			(effects
				(font
					(size 0.7 0.7)
					(thickness 0.15)
				)
				(justify left bottom)
			)
		)
		(fp_text user "${REFERENCE}"
			(at -1.682 3.895 180)
			(layer "F.Fab")
			(effects
				(font
					(size 0.7 0.7)
					(thickness 0.15)
				)
				(justify left bottom)
			)
		)
		(fp_text user "Author: Antmicro"
			(at -1.682 4.894 180)
			(layer "F.Fab")
			(effects
				(font
					(size 0.7 0.7)
					(thickness 0.15)
				)
				(justify left bottom)
			)
		)
		(pad "1" smd roundrect
			(at -0.7 0 180)
			(size 0.8 1)
			(layers "F.Cu" "F.Mask" "F.Paste")
			(roundrect_rratio 0.2)
			(net 23 "GND")
			(pintype "passive")
		)
		(pad "2" smd roundrect
			(at 0.7 0 180)
			(size 0.8 1)
			(layers "F.Cu" "F.Mask" "F.Paste")
			(roundrect_rratio 0.2)
			(net 5 "P0_AVDDL")
			(pintype "passive")
		)
	)
	(footprint "antmicro-footprints:R_0402_1005Metric"
		(layer "F.Cu")
		(at 172.6 72.1 90)
		(descr "Resistor SMD 0402")
		(tags "resistor SMD 0402")
		(property "Reference" "R186"
			(at 0.9 0.4 90)
			(layer "F.SilkS")
			(effects
				(font
					(size 0.7 0.7)
					(thickness 0.15)
				)
				(justify left bottom)
			)
		)
		(property "Value" "R_10R_0402"
			(at -1.011843 1.772047 90)
			(layer "F.Fab")
			(effects
				(font
					(size 0.7 0.7)
					(thickness 0.15)
				)
				(justify left bottom)
			)
		)
		(property "Datasheet" "https://www.bourns.com/docs/product-datasheets/cr.pdf"
			(at 0 0 90)
			(layer "F.Fab")
			(hide yes)
			(effects
				(font
					(size 1.27 1.27)
					(thickness 0.15)
				)
			)
		)
		(property "Description" "SMD Chip Resistor, 10 ohm, ± 1%, 62.5 mW, 0402 [1005 Metric], Thick Film, General Purpose"
			(at 0 0 90)
			(layer "F.Fab")
			(hide yes)
			(effects
				(font
					(size 1.27 1.27)
					(thickness 0.15)
				)
			)
		)
		(property "MPN" "CR0402-FX-10R0GLF"
			(at 0 0 90)
			(unlocked yes)
			(layer "F.Fab")
			(hide yes)
			(effects
				(font
					(size 1 1)
					(thickness 0.15)
				)
			)
		)
		(property "Manufacturer" "Bourns"
			(at 0 0 90)
			(unlocked yes)
			(layer "F.Fab")
			(hide yes)
			(effects
				(font
					(size 1 1)
					(thickness 0.15)
				)
			)
		)
		(property "License" "Apache-2.0"
			(at 0 0 90)
			(unlocked yes)
			(layer "F.Fab")
			(hide yes)
			(effects
				(font
					(size 1 1)
					(thickness 0.15)
				)
			)
		)
		(property "Author" "Antmicro"
			(at 0 0 90)
			(unlocked yes)
			(layer "F.Fab")
			(hide yes)
			(effects
				(font
					(size 1 1)
					(thickness 0.15)
				)
			)
		)
		(property "Val" "10R"
			(at 0 0 90)
			(unlocked yes)
			(layer "F.Fab")
			(hide yes)
			(effects
				(font
					(size 1 1)
					(thickness 0.15)
				)
			)
		)
		(property "Tolerance" "1%"
			(at 0 0 90)
			(unlocked yes)
			(layer "F.Fab")
			(hide yes)
			(effects
				(font
					(size 1 1)
					(thickness 0.15)
				)
			)
		)
		(sheetname "/X710-AT2 10GbE/")
		(sheetfile "x710-at2-10gbe.kicad_sch")
		(attr smd)
		(fp_rect
			(start -0.925 -0.47)
			(end 0.925 0.47)
			(stroke
				(width 0.05)
				(type default)
			)
			(fill no)
			(layer "F.CrtYd")
		)
		(fp_rect
			(start -0.5 -0.25)
			(end 0.5 0.25)
			(stroke
				(width 0.15)
				(type solid)
			)
			(fill no)
			(layer "F.Fab")
		)
		(fp_text user "Author: Antmicro"
			(at -0.95 4.169 90)
			(layer "F.Fab")
			(effects
				(font
					(size 0.7 0.7)
					(thickness 0.15)
				)
				(justify left bottom)
			)
		)
		(fp_text user "${REFERENCE}"
			(at -0.95 3.168 90)
			(layer "F.Fab")
			(effects
				(font
					(size 0.7 0.7)
					(thickness 0.15)
				)
				(justify left bottom)
			)
		)
		(fp_text user "License: Apache-2.0"
			(at -0.95 5.169 90)
			(layer "F.Fab")
			(effects
				(font
					(size 0.7 0.7)
					(thickness 0.15)
				)
				(justify left bottom)
			)
		)
		(pad "1" smd roundrect
			(at -0.48 0 90)
			(size 0.59 0.64)
			(layers "F.Cu" "F.Mask" "F.Paste")
			(roundrect_rratio 0.25)
			(net 125 "/X710-AT2 10GbE/MDIO0_I2C0.MDC")
			(pintype "passive")
		)
		(pad "2" smd roundrect
			(at 0.48 0 90)
			(size 0.59 0.64)
			(layers "F.Cu" "F.Mask" "F.Paste")
			(roundrect_rratio 0.25)
			(net 100 "/X710-AT2 10GbE/MDC0_SCL0")
			(pintype "passive")
		)
	)
	(footprint "antmicro-footprints:C_0603_1608Metric_EIA"
		(layer "F.Cu")
		(at 134.505 99.774998 -90)
		(descr "Capacitor SMD 0603, IPC-7351 Density Level A")
		(tags "Capacitor 0603")
		(property "Reference" "C247"
			(at -9.274999 -37.745 270)
			(layer "F.SilkS")
			(effects
				(font
					(size 0.7 0.7)
					(thickness 0.15)
				)
			)
		)
		(property "Value" "C_22u_16V_0603"
			(at -1.42757 1.770288 270)
			(layer "F.Fab")
			(effects
				(font
					(size 0.7 0.7)
					(thickness 0.15)
				)
				(justify left bottom)
			)
		)
		(property "Datasheet" "https://product.samsungsem.com/mlcc/CL10A226MO7JZN.do"
			(at 0 0 270)
			(layer "F.Fab")
			(hide yes)
			(effects
				(font
					(size 1.27 1.27)
					(thickness 0.15)
				)
			)
		)
		(property "Description" "SMD Multilayer Ceramic Capacitor"
			(at 0 0 270)
			(layer "F.Fab")
			(hide yes)
			(effects
				(font
					(size 1.27 1.27)
					(thickness 0.15)
				)
			)
		)
		(property "MPN" "CL10A226MO7JZNC"
			(at 0 0 270)
			(unlocked yes)
			(layer "F.Fab")
			(hide yes)
			(effects
				(font
					(size 1 1)
					(thickness 0.15)
				)
			)
		)
		(property "Manufacturer" "Samsung Electro-Mechanics"
			(at 0 0 270)
			(unlocked yes)
			(layer "F.Fab")
			(hide yes)
			(effects
				(font
					(size 1 1)
					(thickness 0.15)
				)
			)
		)
		(property "License" "Apache-2.0"
			(at 0 0 270)
			(unlocked yes)
			(layer "F.Fab")
			(hide yes)
			(effects
				(font
					(size 1 1)
					(thickness 0.15)
				)
			)
		)
		(property "Author" "Antmicro"
			(at 0 0 270)
			(unlocked yes)
			(layer "F.Fab")
			(hide yes)
			(effects
				(font
					(size 1 1)
					(thickness 0.15)
				)
			)
		)
		(property "Val" "22u"
			(at 0 0 270)
			(unlocked yes)
			(layer "F.Fab")
			(hide yes)
			(effects
				(font
					(size 1 1)
					(thickness 0.15)
				)
			)
		)
		(property "Voltage" "16V"
			(at 0 0 270)
			(unlocked yes)
			(layer "F.Fab")
			(hide yes)
			(effects
				(font
					(size 1 1)
					(thickness 0.15)
				)
			)
		)
		(property "Dielectric" ""
			(at 0 0 270)
			(unlocked yes)
			(layer "F.Fab")
			(hide yes)
			(effects
				(font
					(size 1 1)
					(thickness 0.15)
				)
			)
		)
		(sheetname "/X710-AT2 power/")
		(sheetfile "x710-at2-power.kicad_sch")
		(attr smd)
		(fp_line
			(start -0.15 0.55)
			(end 0.15 0.55)
			(stroke
				(width 0.15)
				(type solid)
			)
			(layer "F.SilkS")
		)
		(fp_line
			(start -0.15 -0.55)
			(end 0.15 -0.55)
			(stroke
				(width 0.15)
				(type solid)
			)
			(layer "F.SilkS")
		)
		(fp_rect
			(start -1.25 -0.65)
			(end 1.25 0.65)
			(stroke
				(width 0.05)
				(type solid)
			)
			(fill no)
			(layer "F.CrtYd")
		)
		(fp_rect
			(start -0.8 -0.45)
			(end 0.8 0.45)
			(stroke
				(width 0.15)
				(type solid)
			)
			(fill no)
			(layer "F.Fab")
		)
		(fp_text user "License: Apache-2.0"
			(at -1.682 5.895 270)
			(layer "F.Fab")
			(effects
				(font
					(size 0.7 0.7)
					(thickness 0.15)
				)
				(justify left bottom)
			)
		)
		(fp_text user "Author: Antmicro"
			(at -1.682 4.894 270)
			(layer "F.Fab")
			(effects
				(font
					(size 0.7 0.7)
					(thickness 0.15)
				)
				(justify left bottom)
			)
		)
		(fp_text user "${REFERENCE}"
			(at -1.682 3.895 270)
			(layer "F.Fab")
			(effects
				(font
					(size 0.7 0.7)
					(thickness 0.15)
				)
				(justify left bottom)
			)
		)
		(pad "1" smd roundrect
			(at -0.7 0 270)
			(size 0.8 1.1)
			(layers "F.Cu" "F.Mask" "F.Paste")
			(roundrect_rratio 0.2)
			(net 23 "GND")
			(pintype "passive")
		)
		(pad "2" smd roundrect
			(at 0.7 0 270)
			(size 0.8 1.1)
			(layers "F.Cu" "F.Mask" "F.Paste")
			(roundrect_rratio 0.2)
			(net 9 "VCCD")
			(pintype "passive")
		)
	)
	(footprint "antmicro-footprints:R_0402_1005Metric"
		(layer "F.Cu")
		(at 158 46.3 90)
		(descr "Resistor SMD 0402")
		(tags "resistor SMD 0402")
		(property "Reference" "R228"
			(at -1.9 6.3 90)
			(layer "F.SilkS")
			(effects
				(font
					(size 0.7 0.7)
					(thickness 0.15)
				)
				(justify left bottom)
			)
		)
		(property "Value" "R_499k_0402"
			(at -1.011843 1.772047 90)
			(layer "F.Fab")
			(effects
				(font
					(size 0.7 0.7)
					(thickness 0.15)
				)
				(justify left bottom)
			)
		)
		(property "Datasheet" "https://www.mouser.com/datasheet/2/54/cr-1858361.pdf"
			(at 0 0 90)
			(layer "F.Fab")
			(hide yes)
			(effects
				(font
					(size 1.27 1.27)
					(thickness 0.15)
				)
			)
		)
		(property "Description" "SMD Chip Resistor, 499 kohm, ± 1%, 63 mW, 0402 [1005 Metric], Thick Film, General Purpose"
			(at 0 0 90)
			(layer "F.Fab")
			(hide yes)
			(effects
				(font
					(size 1.27 1.27)
					(thickness 0.15)
				)
			)
		)
		(property "MPN" "CR0402-FX-4993GLF"
			(at 0 0 90)
			(unlocked yes)
			(layer "F.Fab")
			(hide yes)
			(effects
				(font
					(size 1 1)
					(thickness 0.15)
				)
			)
		)
		(property "Manufacturer" "Bourns"
			(at 0 0 90)
			(unlocked yes)
			(layer "F.Fab")
			(hide yes)
			(effects
				(font
					(size 1 1)
					(thickness 0.15)
				)
			)
		)
		(property "License" "Apache-2.0"
			(at 0 0 90)
			(unlocked yes)
			(layer "F.Fab")
			(hide yes)
			(effects
				(font
					(size 1 1)
					(thickness 0.15)
				)
			)
		)
		(property "Author" "Antmicro"
			(at 0 0 90)
			(unlocked yes)
			(layer "F.Fab")
			(hide yes)
			(effects
				(font
					(size 1 1)
					(thickness 0.15)
				)
			)
		)
		(property "Val" "499k"
			(at 0 0 90)
			(unlocked yes)
			(layer "F.Fab")
			(hide yes)
			(effects
				(font
					(size 1 1)
					(thickness 0.15)
				)
			)
		)
		(property "Tolerance" "1%"
			(at 0 0 90)
			(unlocked yes)
			(layer "F.Fab")
			(hide yes)
			(effects
				(font
					(size 1 1)
					(thickness 0.15)
				)
			)
		)
		(sheetname "/Power input/")
		(sheetfile "power_input.kicad_sch")
		(attr smd dnp)
		(fp_rect
			(start -0.925 -0.47)
			(end 0.925 0.47)
			(stroke
				(width 0.05)
				(type default)
			)
			(fill no)
			(layer "F.CrtYd")
		)
		(fp_rect
			(start -0.5 -0.25)
			(end 0.5 0.25)
			(stroke
				(width 0.15)
				(type solid)
			)
			(fill no)
			(layer "F.Fab")
		)
		(fp_text user "${REFERENCE}"
			(at -0.95 3.168 90)
			(layer "F.Fab")
			(effects
				(font
					(size 0.7 0.7)
					(thickness 0.15)
				)
				(justify left bottom)
			)
		)
		(fp_text user "License: Apache-2.0"
			(at -0.95 5.169 90)
			(layer "F.Fab")
			(effects
				(font
					(size 0.7 0.7)
					(thickness 0.15)
				)
				(justify left bottom)
			)
		)
		(fp_text user "Author: Antmicro"
			(at -0.95 4.169 90)
			(layer "F.Fab")
			(effects
				(font
					(size 0.7 0.7)
					(thickness 0.15)
				)
				(justify left bottom)
			)
		)
		(pad "1" smd roundrect
			(at -0.48 0 90)
			(size 0.59 0.64)
			(layers "F.Cu" "F.Mask" "F.Paste")
			(roundrect_rratio 0.25)
			(net 389 "/Power input/5V_MODE1")
			(pintype "passive")
		)
		(pad "2" smd roundrect
			(at 0.48 0 90)
			(size 0.59 0.64)
			(layers "F.Cu" "F.Mask" "F.Paste")
			(roundrect_rratio 0.25)
			(net 345 "/Power input/5V_VDD")
			(pintype "passive")
		)
	)
	(footprint "antmicro-footprints:R_0402_1005Metric"
		(layer "F.Cu")
		(at 170.855 79.361 180)
		(descr "Resistor SMD 0402")
		(tags "resistor SMD 0402")
		(property "Reference" "R172"
			(at 1.655 -1.639 180)
			(layer "F.SilkS")
			(effects
				(font
					(size 0.7 0.7)
					(thickness 0.15)
				)
				(justify left bottom)
			)
		)
		(property "Value" "R_2k_0402"
			(at -1.011843 1.772047 180)
			(layer "F.Fab")
			(effects
				(font
					(size 0.7 0.7)
					(thickness 0.15)
				)
				(justify left bottom)
			)
		)
		(property "Datasheet" "https://www.bourns.com/docs/product-datasheets/cr.pdf"
			(at 0 0 180)
			(layer "F.Fab")
			(hide yes)
			(effects
				(font
					(size 1.27 1.27)
					(thickness 0.15)
				)
			)
		)
		(property "Description" "SMD Chip Resistor, 2 kohm, ± 1%, 62.5 mW, 0402 [1005 Metric], Thick Film, General Purpose"
			(at 0 0 180)
			(layer "F.Fab")
			(hide yes)
			(effects
				(font
					(size 1.27 1.27)
					(thickness 0.15)
				)
			)
		)
		(property "MPN" "CR0402-FX-2001GLF"
			(at 0 0 180)
			(unlocked yes)
			(layer "F.Fab")
			(hide yes)
			(effects
				(font
					(size 1 1)
					(thickness 0.15)
				)
			)
		)
		(property "Manufacturer" "Bourns"
			(at 0 0 180)
			(unlocked yes)
			(layer "F.Fab")
			(hide yes)
			(effects
				(font
					(size 1 1)
					(thickness 0.15)
				)
			)
		)
		(property "License" "Apache-2.0"
			(at 0 0 180)
			(unlocked yes)
			(layer "F.Fab")
			(hide yes)
			(effects
				(font
					(size 1 1)
					(thickness 0.15)
				)
			)
		)
		(property "Author" "Antmicro"
			(at 0 0 180)
			(unlocked yes)
			(layer "F.Fab")
			(hide yes)
			(effects
				(font
					(size 1 1)
					(thickness 0.15)
				)
			)
		)
		(property "Val" "2k"
			(at 0 0 180)
			(unlocked yes)
			(layer "F.Fab")
			(hide yes)
			(effects
				(font
					(size 1 1)
					(thickness 0.15)
				)
			)
		)
		(property "Tolerance" "1%"
			(at 0 0 180)
			(unlocked yes)
			(layer "F.Fab")
			(hide yes)
			(effects
				(font
					(size 1 1)
					(thickness 0.15)
				)
			)
		)
		(sheetname "/X710-AT2 Misc/")
		(sheetfile "x710-at2-mics.kicad_sch")
		(attr smd)
		(fp_rect
			(start -0.925 -0.47)
			(end 0.925 0.47)
			(stroke
				(width 0.05)
				(type default)
			)
			(fill no)
			(layer "F.CrtYd")
		)
		(fp_rect
			(start -0.5 -0.25)
			(end 0.5 0.25)
			(stroke
				(width 0.15)
				(type solid)
			)
			(fill no)
			(layer "F.Fab")
		)
		(fp_text user "License: Apache-2.0"
			(at -0.95 5.169 180)
			(layer "F.Fab")
			(effects
				(font
					(size 0.7 0.7)
					(thickness 0.15)
				)
				(justify left bottom)
			)
		)
		(fp_text user "Author: Antmicro"
			(at -0.95 4.169 180)
			(layer "F.Fab")
			(effects
				(font
					(size 0.7 0.7)
					(thickness 0.15)
				)
				(justify left bottom)
			)
		)
		(fp_text user "${REFERENCE}"
			(at -0.95 3.168 180)
			(layer "F.Fab")
			(effects
				(font
					(size 0.7 0.7)
					(thickness 0.15)
				)
				(justify left bottom)
			)
		)
		(pad "1" smd roundrect
			(at -0.48 0 180)
			(size 0.59 0.64)
			(layers "F.Cu" "F.Mask" "F.Paste")
			(roundrect_rratio 0.25)
			(net 147 "/X710-AT2 Misc/MDIO.MDIO")
			(pintype "passive")
		)
		(pad "2" smd roundrect
			(at 0.48 0 180)
			(size 0.59 0.64)
			(layers "F.Cu" "F.Mask" "F.Paste")
			(roundrect_rratio 0.25)
			(net 18 "+1V88")
			(pintype "passive")
		)
	)
	(footprint "antmicro-footprints:C_0603_1608Metric_EIA"
		(layer "F.Cu")
		(at 162.6 113)
		(descr "Capacitor SMD 0603, IPC-7351 Density Level A")
		(tags "Capacitor 0603")
		(property "Reference" "C112"
			(at 12.450003 16.799998 0)
			(layer "F.SilkS")
			(effects
				(font
					(size 0.7 0.7)
					(thickness 0.15)
				)
			)
		)
		(property "Value" "C_22u_16V_0603"
			(at -1.42757 1.770288 0)
			(layer "F.Fab")
			(effects
				(font
					(size 0.7 0.7)
					(thickness 0.15)
				)
				(justify left bottom)
			)
		)
		(property "Datasheet" "https://product.samsungsem.com/mlcc/CL10A226MO7JZN.do"
			(at 0 0 0)
			(layer "F.Fab")
			(hide yes)
			(effects
				(font
					(size 1.27 1.27)
					(thickness 0.15)
				)
			)
		)
		(property "Description" "SMD Multilayer Ceramic Capacitor"
			(at 0 0 0)
			(layer "F.Fab")
			(hide yes)
			(effects
				(font
					(size 1.27 1.27)
					(thickness 0.15)
				)
			)
		)
		(property "MPN" "CL10A226MO7JZNC"
			(at 0 0 0)
			(unlocked yes)
			(layer "F.Fab")
			(hide yes)
			(effects
				(font
					(size 1 1)
					(thickness 0.15)
				)
			)
		)
		(property "Manufacturer" "Samsung Electro-Mechanics"
			(at 0 0 0)
			(unlocked yes)
			(layer "F.Fab")
			(hide yes)
			(effects
				(font
					(size 1 1)
					(thickness 0.15)
				)
			)
		)
		(property "License" "Apache-2.0"
			(at 0 0 0)
			(unlocked yes)
			(layer "F.Fab")
			(hide yes)
			(effects
				(font
					(size 1 1)
					(thickness 0.15)
				)
			)
		)
		(property "Author" "Antmicro"
			(at 0 0 0)
			(unlocked yes)
			(layer "F.Fab")
			(hide yes)
			(effects
				(font
					(size 1 1)
					(thickness 0.15)
				)
			)
		)
		(property "Val" "22u"
			(at 0 0 0)
			(unlocked yes)
			(layer "F.Fab")
			(hide yes)
			(effects
				(font
					(size 1 1)
					(thickness 0.15)
				)
			)
		)
		(property "Voltage" "16V"
			(at 0 0 0)
			(unlocked yes)
			(layer "F.Fab")
			(hide yes)
			(effects
				(font
					(size 1 1)
					(thickness 0.15)
				)
			)
		)
		(property "Dielectric" ""
			(at 0 0 0)
			(unlocked yes)
			(layer "F.Fab")
			(hide yes)
			(effects
				(font
					(size 1 1)
					(thickness 0.15)
				)
			)
		)
		(sheetname "/X710 DCDC converters/")
		(sheetfile "DCDC_converters_X710.kicad_sch")
		(attr smd)
		(fp_line
			(start -0.15 -0.55)
			(end 0.15 -0.55)
			(stroke
				(width 0.15)
				(type solid)
			)
			(layer "F.SilkS")
		)
		(fp_line
			(start -0.15 0.55)
			(end 0.15 0.55)
			(stroke
				(width 0.15)
				(type solid)
			)
			(layer "F.SilkS")
		)
		(fp_rect
			(start -1.25 -0.65)
			(end 1.25 0.65)
			(stroke
				(width 0.05)
				(type solid)
			)
			(fill no)
			(layer "F.CrtYd")
		)
		(fp_rect
			(start -0.8 -0.45)
			(end 0.8 0.45)
			(stroke
				(width 0.15)
				(type solid)
			)
			(fill no)
			(layer "F.Fab")
		)
		(fp_text user "License: Apache-2.0"
			(at -1.682 5.895 0)
			(layer "F.Fab")
			(effects
				(font
					(size 0.7 0.7)
					(thickness 0.15)
				)
				(justify left bottom)
			)
		)
		(fp_text user "${REFERENCE}"
			(at -1.682 3.895 0)
			(layer "F.Fab")
			(effects
				(font
					(size 0.7 0.7)
					(thickness 0.15)
				)
				(justify left bottom)
			)
		)
		(fp_text user "Author: Antmicro"
			(at -1.682 4.894 0)
			(layer "F.Fab")
			(effects
				(font
					(size 0.7 0.7)
					(thickness 0.15)
				)
				(justify left bottom)
			)
		)
		(pad "1" smd roundrect
			(at -0.7 0)
			(size 0.8 1.1)
			(layers "F.Cu" "F.Mask" "F.Paste")
			(roundrect_rratio 0.2)
			(net 23 "GND")
			(pintype "passive")
		)
		(pad "2" smd roundrect
			(at 0.7 0)
			(size 0.8 1.1)
			(layers "F.Cu" "F.Mask" "F.Paste")
			(roundrect_rratio 0.2)
			(net 40 "+5V")
			(pintype "passive")
		)
	)
	(footprint "antmicro-footprints:LED_0603_1608Metric_G"
		(layer "F.Cu")
		(at 116.2 114.4 90)
		(descr "LED SMD 0603 Green")
		(tags "LED SMD 0603 Green")
		(property "Reference" "D4"
			(at -1.6 1.05 90)
			(layer "F.SilkS")
			(effects
				(font
					(size 0.7 0.7)
					(thickness 0.15)
				)
			)
		)
		(property "Value" "LED_G_0603_KP-1608CGCK"
			(at -0.001 1.599 90)
			(layer "F.Fab")
			(effects
				(font
					(size 0.7 0.7)
					(thickness 0.15)
				)
				(justify left bottom)
			)
		)
		(property "Datasheet" "http://www.kingbright.com/attachments/file/psearch//000/00/00/KP-1608CGCK(Ver.23B).pdf"
			(at 0 0 90)
			(layer "F.Fab")
			(hide yes)
			(effects
				(font
					(size 1.27 1.27)
					(thickness 0.15)
				)
			)
		)
		(property "Description" "LED, Green, SMD, 0603, 20 mA, 2.1 V, 570 nm"
			(at 0 0 90)
			(layer "F.Fab")
			(hide yes)
			(effects
				(font
					(size 1.27 1.27)
					(thickness 0.15)
				)
			)
		)
		(property "MPN" "KP-1608CGCK"
			(at 0 0 90)
			(unlocked yes)
			(layer "F.Fab")
			(hide yes)
			(effects
				(font
					(size 1 1)
					(thickness 0.15)
				)
			)
		)
		(property "Manufacturer" "Kingbright"
			(at 0 0 90)
			(unlocked yes)
			(layer "F.Fab")
			(hide yes)
			(effects
				(font
					(size 1 1)
					(thickness 0.15)
				)
			)
		)
		(property "License" "Apache-2.0"
			(at 0 0 90)
			(unlocked yes)
			(layer "F.Fab")
			(hide yes)
			(effects
				(font
					(size 1 1)
					(thickness 0.15)
				)
			)
		)
		(property "Author" "Antmicro"
			(at 0 0 90)
			(unlocked yes)
			(layer "F.Fab")
			(hide yes)
			(effects
				(font
					(size 1 1)
					(thickness 0.15)
				)
			)
		)
		(property "Color" "Green"
			(at 0 0 90)
			(unlocked yes)
			(layer "F.Fab")
			(hide yes)
			(effects
				(font
					(size 1 1)
					(thickness 0.15)
				)
			)
		)
		(sheetname "/PD and TB DC-DC/")
		(sheetfile "PD_and_TB_DC_DC.kicad_sch")
		(attr smd)
		(fp_line
			(start 0.22 -0.35)
			(end -0.22 -0.35)
			(stroke
				(width 0.15)
				(type solid)
			)
			(layer "F.SilkS")
		)
		(fp_line
			(start -1.18 -0.319)
			(end -1.18 0.321)
			(stroke
				(width 0.15)
				(type solid)
			)
			(layer "F.SilkS")
		)
		(fp_line
			(start 0.105328 0.001008)
			(end 0.24 0.001)
			(stroke
				(width 0.1)
				(type solid)
			)
			(layer "F.SilkS")
		)
		(fp_line
			(start -0.094672 0.001008)
			(end 0.105328 -0.198992)
			(stroke
				(width 0.1)
				(type solid)
			)
			(layer "F.SilkS")
		)
		(fp_line
			(start -0.094672 0.001008)
			(end -0.24 0.001008)
			(stroke
				(width 0.1)
				(type solid)
			)
			(layer "F.SilkS")
		)
		(fp_line
			(start 0.105328 0.201008)
			(end 0.105328 -0.198992)
			(stroke
				(width 0.1)
				(type solid)
			)
			(layer "F.SilkS")
		)
		(fp_line
			(start 0.105328 0.201008)
			(end -0.094672 0.001008)
			(stroke
				(width 0.1)
				(type solid)
			)
			(layer "F.SilkS")
		)
		(fp_line
			(start -0.094672 0.201008)
			(end -0.094672 -0.198992)
			(stroke
				(width 0.1)
				(type solid)
			)
			(layer "F.SilkS")
		)
		(fp_line
			(start 0.22 0.35)
			(end -0.22 0.35)
			(stroke
				(width 0.15)
				(type solid)
			)
			(layer "F.SilkS")
		)
		(fp_rect
			(start 1.25 0.65)
			(end -1.25 -0.65)
			(stroke
				(width 0.05)
				(type solid)
			)
			(fill no)
			(layer "F.CrtYd")
		)
		(fp_line
			(start 0.201 -0.202)
			(end -0.101 0)
			(stroke
				(width 0.15)
				(type solid)
			)
			(layer "F.Fab")
		)
		(fp_line
			(start -0.199 -0.202)
			(end -0.199 0.1)
			(stroke
				(width 0.15)
				(type solid)
			)
			(layer "F.Fab")
		)
		(fp_line
			(start 0.599 0)
			(end 0.201 0)
			(stroke
				(width 0.15)
				(type solid)
			)
			(layer "F.Fab")
		)
		(fp_line
			(start 0.201 0)
			(end 0.201 -0.202)
			(stroke
				(width 0.15)
				(type solid)
			)
			(layer "F.Fab")
		)
		(fp_line
			(start -0.101 0)
			(end 0.201 0.2)
			(stroke
				(width 0.15)
				(type solid)
			)
			(layer "F.Fab")
		)
		(fp_line
			(start -0.199 0)
			(end -0.597 0)
			(stroke
				(width 0.15)
				(type solid)
			)
			(layer "F.Fab")
		)
		(fp_line
			(start 0.201 0.2)
			(end 0.201 0)
			(stroke
				(width 0.15)
				(type solid)
			)
			(layer "F.Fab")
		)
		(fp_line
			(start -0.199 0.2)
			(end -0.199 0.1)
			(stroke
				(width 0.15)
				(type solid)
			)
			(layer "F.Fab")
		)
		(fp_rect
			(start 0.848 0.4)
			(end -0.85 -0.402)
			(stroke
				(width 0.15)
				(type solid)
			)
			(fill no)
			(layer "F.Fab")
		)
		(fp_text user "License: Apache-2.0"
			(at -1.4224 3.599 90)
			(layer "F.Fab")
			(effects
				(font
					(size 0.7 0.7)
					(thickness 0.15)
				)
				(justify left bottom)
			)
		)
		(fp_text user "Author: Antmicro"
			(at -1.4224 4.799 90)
			(layer "F.Fab")
			(effects
				(font
					(size 0.7 0.7)
					(thickness 0.15)
				)
				(justify left bottom)
			)
		)
		(fp_text user "${REFERENCE}"
			(at -1.4224 5.999 90)
			(layer "F.Fab")
			(effects
				(font
					(size 0.7 0.7)
					(thickness 0.15)
				)
				(justify left bottom)
			)
		)
		(pad "1" smd roundrect
			(at -0.7 0 270)
			(size 0.8 1)
			(layers "F.Cu" "F.Mask" "F.Paste")
			(roundrect_rratio 0.2)
			(net 195 "Net-(D4-C)")
			(pinfunction "C")
			(pintype "passive")
		)
		(pad "2" smd roundrect
			(at 0.7 0 270)
			(size 0.8 1)
			(layers "F.Cu" "F.Mask" "F.Paste")
			(roundrect_rratio 0.2)
			(net 399 "Net-(D4-A)")
			(pinfunction "A")
			(pintype "passive")
		)
	)
	(footprint "antmicro-footprints:C_0603_1608Metric"
		(layer "F.Cu")
		(at 153.005001 68.574999 -90)
		(descr "Capacitor SMD 0603")
		(tags "capacitor 0603")
		(property "Reference" "C231"
			(at -12.274999 -20.045 270)
			(layer "F.SilkS")
			(effects
				(font
					(size 0.7 0.7)
					(thickness 0.15)
				)
			)
		)
		(property "Value" "C_10u_10V_X7R_0603"
			(at -1.42757 1.770288 270)
			(layer "F.Fab")
			(effects
				(font
					(size 0.7 0.7)
					(thickness 0.15)
				)
				(justify left bottom)
			)
		)
		(property "Datasheet" "https://www.murata.com/products/productdetail?partno=GRM188Z71A106KA73%23"
			(at 0 0 270)
			(layer "F.Fab")
			(hide yes)
			(effects
				(font
					(size 1.27 1.27)
					(thickness 0.15)
				)
			)
		)
		(property "Description" "SMD Multilayer Ceramic Capacitor,  10µF, 10V, 0603, ±10%, X7R"
			(at 0 0 270)
			(layer "F.Fab")
			(hide yes)
			(effects
				(font
					(size 1.27 1.27)
					(thickness 0.15)
				)
			)
		)
		(property "MPN" "GRM188Z71A106KA73D"
			(at 0 0 270)
			(unlocked yes)
			(layer "F.Fab")
			(hide yes)
			(effects
				(font
					(size 1 1)
					(thickness 0.15)
				)
			)
		)
		(property "Val" "10u"
			(at 0 0 270)
			(unlocked yes)
			(layer "F.Fab")
			(hide yes)
			(effects
				(font
					(size 1 1)
					(thickness 0.15)
				)
			)
		)
		(property "Voltage" "10V"
			(at 0 0 270)
			(unlocked yes)
			(layer "F.Fab")
			(hide yes)
			(effects
				(font
					(size 1 1)
					(thickness 0.15)
				)
			)
		)
		(property "Dielectric" "X7R"
			(at 0 0 270)
			(unlocked yes)
			(layer "F.Fab")
			(hide yes)
			(effects
				(font
					(size 1 1)
					(thickness 0.15)
				)
			)
		)
		(property "Manufacturer" "Murata"
			(at 0 0 270)
			(unlocked yes)
			(layer "F.Fab")
			(hide yes)
			(effects
				(font
					(size 1 1)
					(thickness 0.15)
				)
			)
		)
		(property "License" "Apache-2.0"
			(at 0 0 270)
			(unlocked yes)
			(layer "F.Fab")
			(hide yes)
			(effects
				(font
					(size 1 1)
					(thickness 0.15)
				)
			)
		)
		(property "Author" "Antmicro"
			(at 0 0 270)
			(unlocked yes)
			(layer "F.Fab")
			(hide yes)
			(effects
				(font
					(size 1 1)
					(thickness 0.15)
				)
			)
		)
		(sheetname "/X710-AT2 power/")
		(sheetfile "x710-at2-power.kicad_sch")
		(attr smd)
		(fp_line
			(start -0.15 0.4)
			(end 0.15 0.4)
			(stroke
				(width 0.15)
				(type solid)
			)
			(layer "F.SilkS")
		)
		(fp_line
			(start -0.15 -0.4)
			(end 0.15 -0.4)
			(stroke
				(width 0.15)
				(type solid)
			)
			(layer "F.SilkS")
		)
		(fp_rect
			(start -1.25 -0.65)
			(end 1.25 0.65)
			(stroke
				(width 0.05)
				(type solid)
			)
			(fill no)
			(layer "F.CrtYd")
		)
		(fp_rect
			(start -0.8 -0.4)
			(end 0.8 0.4)
			(stroke
				(width 0.15)
				(type solid)
			)
			(fill no)
			(layer "F.Fab")
		)
		(fp_text user "License: Apache-2.0"
			(at -1.682 5.895 270)
			(layer "F.Fab")
			(effects
				(font
					(size 0.7 0.7)
					(thickness 0.15)
				)
				(justify left bottom)
			)
		)
		(fp_text user "Author: Antmicro"
			(at -1.682 4.894 270)
			(layer "F.Fab")
			(effects
				(font
					(size 0.7 0.7)
					(thickness 0.15)
				)
				(justify left bottom)
			)
		)
		(fp_text user "${REFERENCE}"
			(at -1.682 3.895 270)
			(layer "F.Fab")
			(effects
				(font
					(size 0.7 0.7)
					(thickness 0.15)
				)
				(justify left bottom)
			)
		)
		(pad "1" smd roundrect
			(at -0.7 0 270)
			(size 0.8 1)
			(layers "F.Cu" "F.Mask" "F.Paste")
			(roundrect_rratio 0.2)
			(net 23 "GND")
			(pintype "passive")
		)
		(pad "2" smd roundrect
			(at 0.7 0 270)
			(size 0.8 1)
			(layers "F.Cu" "F.Mask" "F.Paste")
			(roundrect_rratio 0.2)
			(net 7 "+3V3")
			(pintype "passive")
		)
	)
	(footprint "antmicro-footprints:C_0402_1005Metric"
		(layer "F.Cu")
		(at 166 75.4 180)
		(descr "Capacitor SMD 0402")
		(tags "capacitor SMD 0402")
		(property "Reference" "C276"
			(at 1.2 -1.4 180)
			(layer "F.SilkS")
			(effects
				(font
					(size 0.7 0.7)
					(thickness 0.15)
				)
				(justify left bottom)
			)
		)
		(property "Value" "C_100n_0402"
			(at -1.022927 2.155213 180)
			(layer "F.Fab")
			(effects
				(font
					(size 0.7 0.7)
					(thickness 0.15)
				)
				(justify left bottom)
			)
		)
		(property "Datasheet" "https://www.murata.com/products/productdetail?partno=GRM155R61H104KE14%23"
			(at 0 0 180)
			(layer "F.Fab")
			(hide yes)
			(effects
				(font
					(size 1.27 1.27)
					(thickness 0.15)
				)
			)
		)
		(property "Description" "SMD Multilayer Ceramic Capacitor, 0.1 µF, 50 V, 0402 [1005 Metric], ± 10%, X5R, GRM Series"
			(at 0 0 180)
			(layer "F.Fab")
			(hide yes)
			(effects
				(font
					(size 1.27 1.27)
					(thickness 0.15)
				)
			)
		)
		(property "MPN" "GRM155R61H104KE14D"
			(at 0 0 180)
			(unlocked yes)
			(layer "F.Fab")
			(hide yes)
			(effects
				(font
					(size 1 1)
					(thickness 0.15)
				)
			)
		)
		(property "Val" "100n"
			(at 0 0 180)
			(unlocked yes)
			(layer "F.Fab")
			(hide yes)
			(effects
				(font
					(size 1 1)
					(thickness 0.15)
				)
			)
		)
		(property "Voltage" "50V"
			(at 0 0 180)
			(unlocked yes)
			(layer "F.Fab")
			(hide yes)
			(effects
				(font
					(size 1 1)
					(thickness 0.15)
				)
			)
		)
		(property "Dielectric" "X5R"
			(at 0 0 180)
			(unlocked yes)
			(layer "F.Fab")
			(hide yes)
			(effects
				(font
					(size 1 1)
					(thickness 0.15)
				)
			)
		)
		(property "Manufacturer" "Murata"
			(at 0 0 180)
			(unlocked yes)
			(layer "F.Fab")
			(hide yes)
			(effects
				(font
					(size 1 1)
					(thickness 0.15)
				)
			)
		)
		(property "License" "Apache-2.0"
			(at 0 0 180)
			(unlocked yes)
			(layer "F.Fab")
			(hide yes)
			(effects
				(font
					(size 1 1)
					(thickness 0.15)
				)
			)
		)
		(property "Author" "Antmicro"
			(at 0 0 180)
			(unlocked yes)
			(layer "F.Fab")
			(hide yes)
			(effects
				(font
					(size 1 1)
					(thickness 0.15)
				)
			)
		)
		(sheetname "/X710-AT2 Misc/")
		(sheetfile "x710-at2-mics.kicad_sch")
		(attr smd)
		(fp_rect
			(start -0.925 -0.47)
			(end 0.925 0.47)
			(stroke
				(width 0.05)
				(type default)
			)
			(fill no)
			(layer "F.CrtYd")
		)
		(fp_line
			(start 0.504 0.248)
			(end -0.494 0.248)
			(stroke
				(width 0.15)
				(type solid)
			)
			(layer "F.Fab")
		)
		(fp_line
			(start 0.504 -0.25)
			(end 0.504 0.248)
			(stroke
				(width 0.15)
				(type solid)
			)
			(layer "F.Fab")
		)
		(fp_line
			(start -0.494 0.248)
			(end -0.494 -0.25)
			(stroke
				(width 0.15)
				(type solid)
			)
			(layer "F.Fab")
		)
		(fp_line
			(start -0.494 -0.25)
			(end 0.504 -0.25)
			(stroke
				(width 0.15)
				(type solid)
			)
			(layer "F.Fab")
		)
		(fp_text user "${REFERENCE}"
			(at -0.939 4.599 180)
			(layer "F.Fab")
			(effects
				(font
					(size 0.7 0.7)
					(thickness 0.15)
				)
				(justify left bottom)
			)
		)
		(fp_text user "License: Apache-2.0"
			(at -0.939 5.799 180)
			(layer "F.Fab")
			(effects
				(font
					(size 0.7 0.7)
					(thickness 0.15)
				)
				(justify left bottom)
			)
		)
		(fp_text user "Author: Antmicro"
			(at -0.939 3.399 180)
			(layer "F.Fab")
			(effects
				(font
					(size 0.7 0.7)
					(thickness 0.15)
				)
				(justify left bottom)
			)
		)
		(pad "1" smd roundrect
			(at -0.48 0 180)
			(size 0.59 0.64)
			(layers "F.Cu" "F.Mask" "F.Paste")
			(roundrect_rratio 0.25)
			(net 23 "GND")
			(pintype "passive")
		)
		(pad "2" smd roundrect
			(at 0.48 0 180)
			(size 0.59 0.64)
			(layers "F.Cu" "F.Mask" "F.Paste")
			(roundrect_rratio 0.25)
			(net 7 "+3V3")
			(pintype "passive")
		)
	)
	(footprint "antmicro-footprints:R_0402_1005Metric"
		(layer "F.Cu")
		(at 142.309999 93.674999 180)
		(descr "Resistor SMD 0402")
		(tags "resistor SMD 0402")
		(property "Reference" "R146"
			(at -2.190001 -0.025001 180)
			(layer "F.SilkS")
			(effects
				(font
					(size 0.7 0.7)
					(thickness 0.15)
				)
			)
		)
		(property "Value" "R_10k_0402"
			(at -1.011843 1.772047 180)
			(layer "F.Fab")
			(effects
				(font
					(size 0.7 0.7)
					(thickness 0.15)
				)
				(justify left bottom)
			)
		)
		(property "Datasheet" "https://www.bourns.com/docs/product-datasheets/cr.pdf"
			(at 0 0 180)
			(layer "F.Fab")
			(hide yes)
			(effects
				(font
					(size 1.27 1.27)
					(thickness 0.15)
				)
			)
		)
		(property "Description" "SMD Chip Resistor, 10 kohm, ± 1%, 62.5 mW, 0402 [1005 Metric], Thick Film, General Purpose"
			(at 0 0 180)
			(layer "F.Fab")
			(hide yes)
			(effects
				(font
					(size 1.27 1.27)
					(thickness 0.15)
				)
			)
		)
		(property "MPN" "CR0402-FX-1002GLF"
			(at 0 0 180)
			(unlocked yes)
			(layer "F.Fab")
			(hide yes)
			(effects
				(font
					(size 1 1)
					(thickness 0.15)
				)
			)
		)
		(property "Manufacturer" "Bourns"
			(at 0 0 180)
			(unlocked yes)
			(layer "F.Fab")
			(hide yes)
			(effects
				(font
					(size 1 1)
					(thickness 0.15)
				)
			)
		)
		(property "License" "Apache-2.0"
			(at 0 0 180)
			(unlocked yes)
			(layer "F.Fab")
			(hide yes)
			(effects
				(font
					(size 1 1)
					(thickness 0.15)
				)
			)
		)
		(property "Author" "Antmicro"
			(at 0 0 180)
			(unlocked yes)
			(layer "F.Fab")
			(hide yes)
			(effects
				(font
					(size 1 1)
					(thickness 0.15)
				)
			)
		)
		(property "Val" "10k"
			(at 0 0 180)
			(unlocked yes)
			(layer "F.Fab")
			(hide yes)
			(effects
				(font
					(size 1 1)
					(thickness 0.15)
				)
			)
		)
		(property "Tolerance" "1%"
			(at 0 0 180)
			(unlocked yes)
			(layer "F.Fab")
			(hide yes)
			(effects
				(font
					(size 1 1)
					(thickness 0.15)
				)
			)
		)
		(sheetname "/X710-AT2 Misc/")
		(sheetfile "x710-at2-mics.kicad_sch")
		(attr smd)
		(fp_rect
			(start -0.925 -0.47)
			(end 0.925 0.47)
			(stroke
				(width 0.05)
				(type default)
			)
			(fill no)
			(layer "F.CrtYd")
		)
		(fp_rect
			(start -0.5 -0.25)
			(end 0.5 0.25)
			(stroke
				(width 0.15)
				(type solid)
			)
			(fill no)
			(layer "F.Fab")
		)
		(fp_text user "${REFERENCE}"
			(at -0.95 3.168 180)
			(layer "F.Fab")
			(effects
				(font
					(size 0.7 0.7)
					(thickness 0.15)
				)
				(justify left bottom)
			)
		)
		(fp_text user "Author: Antmicro"
			(at -0.95 4.169 180)
			(layer "F.Fab")
			(effects
				(font
					(size 0.7 0.7)
					(thickness 0.15)
				)
				(justify left bottom)
			)
		)
		(fp_text user "License: Apache-2.0"
			(at -0.95 5.169 180)
			(layer "F.Fab")
			(effects
				(font
					(size 0.7 0.7)
					(thickness 0.15)
				)
				(justify left bottom)
			)
		)
		(pad "1" smd roundrect
			(at -0.48 0 180)
			(size 0.59 0.64)
			(layers "F.Cu" "F.Mask" "F.Paste")
			(roundrect_rratio 0.25)
			(net 74 "/X710-AT2 Misc/LAN_PWR_GOOD")
			(pintype "passive")
		)
		(pad "2" smd roundrect
			(at 0.48 0 180)
			(size 0.59 0.64)
			(layers "F.Cu" "F.Mask" "F.Paste")
			(roundrect_rratio 0.25)
			(net 7 "+3V3")
			(pintype "passive")
		)
	)
	(footprint "antmicro-footprints:R_0402_1005Metric"
		(layer "F.Cu")
		(at 157.155 69.074999 90)
		(descr "Resistor SMD 0402")
		(tags "resistor SMD 0402")
		(property "Reference" "R170"
			(at 11.574999 20.295 90)
			(layer "F.SilkS")
			(effects
				(font
					(size 0.7 0.7)
					(thickness 0.15)
				)
			)
		)
		(property "Value" "R_10k_0402"
			(at -1.011843 1.772047 90)
			(layer "F.Fab")
			(effects
				(font
					(size 0.7 0.7)
					(thickness 0.15)
				)
				(justify left bottom)
			)
		)
		(property "Datasheet" "https://www.bourns.com/docs/product-datasheets/cr.pdf"
			(at 0 0 90)
			(layer "F.Fab")
			(hide yes)
			(effects
				(font
					(size 1.27 1.27)
					(thickness 0.15)
				)
			)
		)
		(property "Description" "SMD Chip Resistor, 10 kohm, ± 1%, 62.5 mW, 0402 [1005 Metric], Thick Film, General Purpose"
			(at 0 0 90)
			(layer "F.Fab")
			(hide yes)
			(effects
				(font
					(size 1.27 1.27)
					(thickness 0.15)
				)
			)
		)
		(property "MPN" "CR0402-FX-1002GLF"
			(at 0 0 90)
			(unlocked yes)
			(layer "F.Fab")
			(hide yes)
			(effects
				(font
					(size 1 1)
					(thickness 0.15)
				)
			)
		)
		(property "Manufacturer" "Bourns"
			(at 0 0 90)
			(unlocked yes)
			(layer "F.Fab")
			(hide yes)
			(effects
				(font
					(size 1 1)
					(thickness 0.15)
				)
			)
		)
		(property "License" "Apache-2.0"
			(at 0 0 90)
			(unlocked yes)
			(layer "F.Fab")
			(hide yes)
			(effects
				(font
					(size 1 1)
					(thickness 0.15)
				)
			)
		)
		(property "Author" "Antmicro"
			(at 0 0 90)
			(unlocked yes)
			(layer "F.Fab")
			(hide yes)
			(effects
				(font
					(size 1 1)
					(thickness 0.15)
				)
			)
		)
		(property "Val" "10k"
			(at 0 0 90)
			(unlocked yes)
			(layer "F.Fab")
			(hide yes)
			(effects
				(font
					(size 1 1)
					(thickness 0.15)
				)
			)
		)
		(property "Tolerance" "1%"
			(at 0 0 90)
			(unlocked yes)
			(layer "F.Fab")
			(hide yes)
			(effects
				(font
					(size 1 1)
					(thickness 0.15)
				)
			)
		)
		(sheetname "/X710-AT2 Misc/")
		(sheetfile "x710-at2-mics.kicad_sch")
		(attr smd)
		(fp_rect
			(start -0.925 -0.47)
			(end 0.925 0.47)
			(stroke
				(width 0.05)
				(type default)
			)
			(fill no)
			(layer "F.CrtYd")
		)
		(fp_rect
			(start -0.5 -0.25)
			(end 0.5 0.25)
			(stroke
				(width 0.15)
				(type solid)
			)
			(fill no)
			(layer "F.Fab")
		)
		(fp_text user "Author: Antmicro"
			(at -0.95 4.169 90)
			(layer "F.Fab")
			(effects
				(font
					(size 0.7 0.7)
					(thickness 0.15)
				)
				(justify left bottom)
			)
		)
		(fp_text user "${REFERENCE}"
			(at -0.95 3.168 90)
			(layer "F.Fab")
			(effects
				(font
					(size 0.7 0.7)
					(thickness 0.15)
				)
				(justify left bottom)
			)
		)
		(fp_text user "License: Apache-2.0"
			(at -0.95 5.169 90)
			(layer "F.Fab")
			(effects
				(font
					(size 0.7 0.7)
					(thickness 0.15)
				)
				(justify left bottom)
			)
		)
		(pad "1" smd roundrect
			(at -0.48 0 90)
			(size 0.59 0.64)
			(layers "F.Cu" "F.Mask" "F.Paste")
			(roundrect_rratio 0.25)
			(net 127 "/X710-AT2 Misc/~{DEV_DIS}")
			(pintype "passive")
		)
		(pad "2" smd roundrect
			(at 0.48 0 90)
			(size 0.59 0.64)
			(layers "F.Cu" "F.Mask" "F.Paste")
			(roundrect_rratio 0.25)
			(net 7 "+3V3")
			(pintype "passive")
		)
	)
	(footprint "antmicro-footprints:C_0402_1005Metric"
		(layer "F.Cu")
		(at 149.955 97.374999 -90)
		(descr "Capacitor SMD 0402")
		(tags "capacitor SMD 0402")
		(property "Reference" "C162"
			(at 19.625001 -23.294999 270)
			(layer "F.SilkS")
			(effects
				(font
					(size 0.7 0.7)
					(thickness 0.15)
				)
			)
		)
		(property "Value" "C_100n_0402"
			(at -1.022927 2.155213 270)
			(layer "F.Fab")
			(effects
				(font
					(size 0.7 0.7)
					(thickness 0.15)
				)
				(justify left bottom)
			)
		)
		(property "Datasheet" "https://www.murata.com/products/productdetail?partno=GRM155R61H104KE14%23"
			(at 0 0 270)
			(layer "F.Fab")
			(hide yes)
			(effects
				(font
					(size 1.27 1.27)
					(thickness 0.15)
				)
			)
		)
		(property "Description" "SMD Multilayer Ceramic Capacitor, 0.1 µF, 50 V, 0402 [1005 Metric], ± 10%, X5R, GRM Series"
			(at 0 0 270)
			(layer "F.Fab")
			(hide yes)
			(effects
				(font
					(size 1.27 1.27)
					(thickness 0.15)
				)
			)
		)
		(property "MPN" "GRM155R61H104KE14D"
			(at 0 0 270)
			(unlocked yes)
			(layer "F.Fab")
			(hide yes)
			(effects
				(font
					(size 1 1)
					(thickness 0.15)
				)
			)
		)
		(property "Val" "100n"
			(at 0 0 270)
			(unlocked yes)
			(layer "F.Fab")
			(hide yes)
			(effects
				(font
					(size 1 1)
					(thickness 0.15)
				)
			)
		)
		(property "Voltage" "50V"
			(at 0 0 270)
			(unlocked yes)
			(layer "F.Fab")
			(hide yes)
			(effects
				(font
					(size 1 1)
					(thickness 0.15)
				)
			)
		)
		(property "Dielectric" "X5R"
			(at 0 0 270)
			(unlocked yes)
			(layer "F.Fab")
			(hide yes)
			(effects
				(font
					(size 1 1)
					(thickness 0.15)
				)
			)
		)
		(property "Manufacturer" "Murata"
			(at 0 0 270)
			(unlocked yes)
			(layer "F.Fab")
			(hide yes)
			(effects
				(font
					(size 1 1)
					(thickness 0.15)
				)
			)
		)
		(property "License" "Apache-2.0"
			(at 0 0 270)
			(unlocked yes)
			(layer "F.Fab")
			(hide yes)
			(effects
				(font
					(size 1 1)
					(thickness 0.15)
				)
			)
		)
		(property "Author" "Antmicro"
			(at 0 0 270)
			(unlocked yes)
			(layer "F.Fab")
			(hide yes)
			(effects
				(font
					(size 1 1)
					(thickness 0.15)
				)
			)
		)
		(sheetname "/X710-AT2 power/")
		(sheetfile "x710-at2-power.kicad_sch")
		(attr smd)
		(fp_rect
			(start -0.925 -0.47)
			(end 0.925 0.47)
			(stroke
				(width 0.05)
				(type default)
			)
			(fill no)
			(layer "F.CrtYd")
		)
		(fp_line
			(start -0.494 0.248)
			(end -0.494 -0.25)
			(stroke
				(width 0.15)
				(type solid)
			)
			(layer "F.Fab")
		)
		(fp_line
			(start 0.504 0.248)
			(end -0.494 0.248)
			(stroke
				(width 0.15)
				(type solid)
			)
			(layer "F.Fab")
		)
		(fp_line
			(start -0.494 -0.25)
			(end 0.504 -0.25)
			(stroke
				(width 0.15)
				(type solid)
			)
			(layer "F.Fab")
		)
		(fp_line
			(start 0.504 -0.25)
			(end 0.504 0.248)
			(stroke
				(width 0.15)
				(type solid)
			)
			(layer "F.Fab")
		)
		(fp_text user "Author: Antmicro"
			(at -0.939 3.399 270)
			(layer "F.Fab")
			(effects
				(font
					(size 0.7 0.7)
					(thickness 0.15)
				)
				(justify left bottom)
			)
		)
		(fp_text user "License: Apache-2.0"
			(at -0.939 5.799 270)
			(layer "F.Fab")
			(effects
				(font
					(size 0.7 0.7)
					(thickness 0.15)
				)
				(justify left bottom)
			)
		)
		(fp_text user "${REFERENCE}"
			(at -0.939 4.599 270)
			(layer "F.Fab")
			(effects
				(font
					(size 0.7 0.7)
					(thickness 0.15)
				)
				(justify left bottom)
			)
		)
		(pad "1" smd roundrect
			(at -0.48 0 270)
			(size 0.59 0.64)
			(layers "F.Cu" "F.Mask" "F.Paste")
			(roundrect_rratio 0.25)
			(net 23 "GND")
			(pintype "passive")
		)
		(pad "2" smd roundrect
			(at 0.48 0 270)
			(size 0.59 0.64)
			(layers "F.Cu" "F.Mask" "F.Paste")
			(roundrect_rratio 0.25)
			(net 18 "+1V88")
			(pintype "passive")
		)
	)
	(footprint "antmicro-footprints:C_0402_1005Metric"
		(layer "F.Cu")
		(at 164.200001 109.850001 90)
		(descr "Capacitor SMD 0402")
		(tags "capacitor SMD 0402")
		(property "Reference" "C127"
			(at -16.799997 12 90)
			(layer "F.SilkS")
			(effects
				(font
					(size 0.7 0.7)
					(thickness 0.15)
				)
			)
		)
		(property "Value" "C_100n_0402"
			(at -1.022927 2.155213 90)
			(layer "F.Fab")
			(effects
				(font
					(size 0.7 0.7)
					(thickness 0.15)
				)
				(justify left bottom)
			)
		)
		(property "Datasheet" "https://www.murata.com/products/productdetail?partno=GRM155R61H104KE14%23"
			(at 0 0 90)
			(layer "F.Fab")
			(hide yes)
			(effects
				(font
					(size 1.27 1.27)
					(thickness 0.15)
				)
			)
		)
		(property "Description" "SMD Multilayer Ceramic Capacitor, 0.1 µF, 50 V, 0402 [1005 Metric], ± 10%, X5R, GRM Series"
			(at 0 0 90)
			(layer "F.Fab")
			(hide yes)
			(effects
				(font
					(size 1.27 1.27)
					(thickness 0.15)
				)
			)
		)
		(property "MPN" "GRM155R61H104KE14D"
			(at 0 0 90)
			(unlocked yes)
			(layer "F.Fab")
			(hide yes)
			(effects
				(font
					(size 1 1)
					(thickness 0.15)
				)
			)
		)
		(property "Manufacturer" "Murata"
			(at 0 0 90)
			(unlocked yes)
			(layer "F.Fab")
			(hide yes)
			(effects
				(font
					(size 1 1)
					(thickness 0.15)
				)
			)
		)
		(property "License" "Apache-2.0"
			(at 0 0 90)
			(unlocked yes)
			(layer "F.Fab")
			(hide yes)
			(effects
				(font
					(size 1 1)
					(thickness 0.15)
				)
			)
		)
		(property "Author" "Antmicro"
			(at 0 0 90)
			(unlocked yes)
			(layer "F.Fab")
			(hide yes)
			(effects
				(font
					(size 1 1)
					(thickness 0.15)
				)
			)
		)
		(property "Val" "100n"
			(at 0 0 90)
			(unlocked yes)
			(layer "F.Fab")
			(hide yes)
			(effects
				(font
					(size 1 1)
					(thickness 0.15)
				)
			)
		)
		(property "Voltage" "50V"
			(at 0 0 90)
			(unlocked yes)
			(layer "F.Fab")
			(hide yes)
			(effects
				(font
					(size 1 1)
					(thickness 0.15)
				)
			)
		)
		(property "Dielectric" "X5R"
			(at 0 0 90)
			(unlocked yes)
			(layer "F.Fab")
			(hide yes)
			(effects
				(font
					(size 1 1)
					(thickness 0.15)
				)
			)
		)
		(sheetname "/X710 DCDC converters/")
		(sheetfile "DCDC_converters_X710.kicad_sch")
		(attr smd)
		(fp_rect
			(start -0.925 -0.47)
			(end 0.925 0.47)
			(stroke
				(width 0.05)
				(type default)
			)
			(fill no)
			(layer "F.CrtYd")
		)
		(fp_line
			(start 0.504 -0.25)
			(end 0.504 0.248)
			(stroke
				(width 0.15)
				(type solid)
			)
			(layer "F.Fab")
		)
		(fp_line
			(start -0.494 -0.25)
			(end 0.504 -0.25)
			(stroke
				(width 0.15)
				(type solid)
			)
			(layer "F.Fab")
		)
		(fp_line
			(start 0.504 0.248)
			(end -0.494 0.248)
			(stroke
				(width 0.15)
				(type solid)
			)
			(layer "F.Fab")
		)
		(fp_line
			(start -0.494 0.248)
			(end -0.494 -0.25)
			(stroke
				(width 0.15)
				(type solid)
			)
			(layer "F.Fab")
		)
		(fp_text user "Author: Antmicro"
			(at -0.939 3.399 90)
			(layer "F.Fab")
			(effects
				(font
					(size 0.7 0.7)
					(thickness 0.15)
				)
				(justify left bottom)
			)
		)
		(fp_text user "${REFERENCE}"
			(at -0.939 4.599 90)
			(layer "F.Fab")
			(effects
				(font
					(size 0.7 0.7)
					(thickness 0.15)
				)
				(justify left bottom)
			)
		)
		(fp_text user "License: Apache-2.0"
			(at -0.939 5.799 90)
			(layer "F.Fab")
			(effects
				(font
					(size 0.7 0.7)
					(thickness 0.15)
				)
				(justify left bottom)
			)
		)
		(pad "1" smd roundrect
			(at -0.48 0 90)
			(size 0.59 0.64)
			(layers "F.Cu" "F.Mask" "F.Paste")
			(roundrect_rratio 0.25)
			(net 307 "/X710 DCDC converters/1V0_BST")
			(pintype "passive")
		)
		(pad "2" smd roundrect
			(at 0.48 0 90)
			(size 0.59 0.64)
			(layers "F.Cu" "F.Mask" "F.Paste")
			(roundrect_rratio 0.25)
			(net 310 "/X710 DCDC converters/1V0_SW")
			(pintype "passive")
		)
	)
	(footprint "antmicro-footprints:C_0603_1608Metric"
		(layer "F.Cu")
		(at 139.991421 120.15 -90)
		(descr "Capacitor SMD 0603")
		(tags "capacitor 0603")
		(property "Reference" "C80"
			(at -1.35 -0.55 270)
			(layer "F.SilkS")
			(effects
				(font
					(size 0.7 0.7)
					(thickness 0.15)
				)
				(justify left bottom)
			)
		)
		(property "Value" "C_22u_0603"
			(at -1.42757 1.770288 270)
			(layer "F.Fab")
			(effects
				(font
					(size 0.7 0.7)
					(thickness 0.15)
				)
				(justify left bottom)
			)
		)
		(property "Datasheet" "https://www.murata.com/products/productdetail?partno=GRM188R60J226MEA0%23"
			(at 0 0 270)
			(layer "F.Fab")
			(hide yes)
			(effects
				(font
					(size 1.27 1.27)
					(thickness 0.15)
				)
			)
		)
		(property "Description" "SMD Multilayer Ceramic Capacitor, 22 µF, 6.3 V, 0603 [1608 Metric], ± 20%, X5R, GRM Series"
			(at 0 0 270)
			(layer "F.Fab")
			(hide yes)
			(effects
				(font
					(size 1.27 1.27)
					(thickness 0.15)
				)
			)
		)
		(property "MPN" "GRM188R60J226MEA0D"
			(at 0 0 270)
			(unlocked yes)
			(layer "F.Fab")
			(hide yes)
			(effects
				(font
					(size 1 1)
					(thickness 0.15)
				)
			)
		)
		(property "Manufacturer" "Murata"
			(at 0 0 270)
			(unlocked yes)
			(layer "F.Fab")
			(hide yes)
			(effects
				(font
					(size 1 1)
					(thickness 0.15)
				)
			)
		)
		(property "License" "Apache-2.0"
			(at 0 0 270)
			(unlocked yes)
			(layer "F.Fab")
			(hide yes)
			(effects
				(font
					(size 1 1)
					(thickness 0.15)
				)
			)
		)
		(property "Val" "22u"
			(at 0 0 270)
			(unlocked yes)
			(layer "F.Fab")
			(hide yes)
			(effects
				(font
					(size 1 1)
					(thickness 0.15)
				)
			)
		)
		(property "Voltage" ""
			(at 0 0 270)
			(unlocked yes)
			(layer "F.Fab")
			(hide yes)
			(effects
				(font
					(size 1 1)
					(thickness 0.15)
				)
			)
		)
		(property "Dielectric" ""
			(at 0 0 270)
			(unlocked yes)
			(layer "F.Fab")
			(hide yes)
			(effects
				(font
					(size 1 1)
					(thickness 0.15)
				)
			)
		)
		(property "Author" "Antmicro"
			(at 0 0 270)
			(unlocked yes)
			(layer "F.Fab")
			(hide yes)
			(effects
				(font
					(size 1 1)
					(thickness 0.15)
				)
			)
		)
		(sheetname "/TB Controller - Power/")
		(sheetfile "tb-power.kicad_sch")
		(attr smd)
		(fp_line
			(start -0.15 0.4)
			(end 0.15 0.4)
			(stroke
				(width 0.15)
				(type solid)
			)
			(layer "F.SilkS")
		)
		(fp_line
			(start -0.15 -0.4)
			(end 0.15 -0.4)
			(stroke
				(width 0.15)
				(type solid)
			)
			(layer "F.SilkS")
		)
		(fp_rect
			(start -1.25 -0.65)
			(end 1.25 0.65)
			(stroke
				(width 0.05)
				(type solid)
			)
			(fill no)
			(layer "F.CrtYd")
		)
		(fp_rect
			(start -0.8 -0.4)
			(end 0.8 0.4)
			(stroke
				(width 0.15)
				(type solid)
			)
			(fill no)
			(layer "F.Fab")
		)
		(fp_text user "${REFERENCE}"
			(at -1.682 3.895 270)
			(layer "F.Fab")
			(effects
				(font
					(size 0.7 0.7)
					(thickness 0.15)
				)
				(justify left bottom)
			)
		)
		(fp_text user "License: Apache-2.0"
			(at -1.682 5.895 270)
			(layer "F.Fab")
			(effects
				(font
					(size 0.7 0.7)
					(thickness 0.15)
				)
				(justify left bottom)
			)
		)
		(fp_text user "Author: Antmicro"
			(at -1.682 4.894 270)
			(layer "F.Fab")
			(effects
				(font
					(size 0.7 0.7)
					(thickness 0.15)
				)
				(justify left bottom)
			)
		)
		(pad "1" smd roundrect
			(at -0.7 0 270)
			(size 0.8 1)
			(layers "F.Cu" "F.Mask" "F.Paste")
			(roundrect_rratio 0.2)
			(net 23 "GND")
			(pintype "passive")
		)
		(pad "2" smd roundrect
			(at 0.7 0 270)
			(size 0.8 1)
			(layers "F.Cu" "F.Mask" "F.Paste")
			(roundrect_rratio 0.2)
			(net 68 "/TB Controller - Power/VCC_0P9")
			(pintype "passive")
		)
	)
	(footprint "antmicro-footprints:R_0402_1005Metric"
		(layer "F.Cu")
		(at 159.249999 113.15)
		(descr "Resistor SMD 0402")
		(tags "resistor SMD 0402")
		(property "Reference" "R94"
			(at 12.950004 17.25 0)
			(layer "F.SilkS")
			(effects
				(font
					(size 0.7 0.7)
					(thickness 0.15)
				)
			)
		)
		(property "Value" "R_0R_0402"
			(at -1.011843 1.772047 0)
			(layer "F.Fab")
			(effects
				(font
					(size 0.7 0.7)
					(thickness 0.15)
				)
				(justify left bottom)
			)
		)
		(property "Datasheet" "https://industrial.panasonic.com/cdbs/www-data/pdf/RDA0000/AOA0000C301.pdf"
			(at 0 0 0)
			(layer "F.Fab")
			(hide yes)
			(effects
				(font
					(size 1.27 1.27)
					(thickness 0.15)
				)
			)
		)
		(property "Description" "SMD Chip Resistor, Jumper, 0 ohm, 100 mW, 0402 [1005 Metric], Thick Film, General Purpose"
			(at 0 0 0)
			(layer "F.Fab")
			(hide yes)
			(effects
				(font
					(size 1.27 1.27)
					(thickness 0.15)
				)
			)
		)
		(property "MPN" "ERJ2GE0R00X"
			(at 0 0 0)
			(unlocked yes)
			(layer "F.Fab")
			(hide yes)
			(effects
				(font
					(size 1 1)
					(thickness 0.15)
				)
			)
		)
		(property "Manufacturer" "Panasonic"
			(at 0 0 0)
			(unlocked yes)
			(layer "F.Fab")
			(hide yes)
			(effects
				(font
					(size 1 1)
					(thickness 0.15)
				)
			)
		)
		(property "License" "Apache-2.0"
			(at 0 0 0)
			(unlocked yes)
			(layer "F.Fab")
			(hide yes)
			(effects
				(font
					(size 1 1)
					(thickness 0.15)
				)
			)
		)
		(property "Author" "Antmicro"
			(at 0 0 0)
			(unlocked yes)
			(layer "F.Fab")
			(hide yes)
			(effects
				(font
					(size 1 1)
					(thickness 0.15)
				)
			)
		)
		(property "Val" "0R"
			(at 0 0 0)
			(unlocked yes)
			(layer "F.Fab")
			(hide yes)
			(effects
				(font
					(size 1 1)
					(thickness 0.15)
				)
			)
		)
		(property "Tolerance" "~"
			(at 0 0 0)
			(unlocked yes)
			(layer "F.Fab")
			(hide yes)
			(effects
				(font
					(size 1 1)
					(thickness 0.15)
				)
			)
		)
		(property "Current" "1A"
			(at 0 0 0)
			(unlocked yes)
			(layer "F.Fab")
			(hide yes)
			(effects
				(font
					(size 1 1)
					(thickness 0.15)
				)
			)
		)
		(sheetname "/X710 DCDC converters/")
		(sheetfile "DCDC_converters_X710.kicad_sch")
		(attr smd)
		(fp_rect
			(start -0.925 -0.47)
			(end 0.925 0.47)
			(stroke
				(width 0.05)
				(type default)
			)
			(fill no)
			(layer "F.CrtYd")
		)
		(fp_rect
			(start -0.5 -0.25)
			(end 0.5 0.25)
			(stroke
				(width 0.15)
				(type solid)
			)
			(fill no)
			(layer "F.Fab")
		)
		(fp_text user "License: Apache-2.0"
			(at -0.95 5.169 0)
			(layer "F.Fab")
			(effects
				(font
					(size 0.7 0.7)
					(thickness 0.15)
				)
				(justify left bottom)
			)
		)
		(fp_text user "${REFERENCE}"
			(at -0.95 3.168 0)
			(layer "F.Fab")
			(effects
				(font
					(size 0.7 0.7)
					(thickness 0.15)
				)
				(justify left bottom)
			)
		)
		(fp_text user "Author: Antmicro"
			(at -0.95 4.169 0)
			(layer "F.Fab")
			(effects
				(font
					(size 0.7 0.7)
					(thickness 0.15)
				)
				(justify left bottom)
			)
		)
		(pad "1" smd roundrect
			(at -0.48 0)
			(size 0.59 0.64)
			(layers "F.Cu" "F.Mask" "F.Paste")
			(roundrect_rratio 0.25)
			(net 380 "/X710 DCDC converters/1V88_PG")
			(pintype "passive")
		)
		(pad "2" smd roundrect
			(at 0.48 0)
			(size 0.59 0.64)
			(layers "F.Cu" "F.Mask" "F.Paste")
			(roundrect_rratio 0.25)
			(net 385 "/X710 DCDC converters/1V0_EN")
			(pintype "passive")
		)
	)
	(footprint "antmicro-footprints:C_0402_1005Metric"
		(layer "F.Cu")
		(at 151.549999 111.15 180)
		(descr "Capacitor SMD 0402")
		(tags "capacitor SMD 0402")
		(property "Reference" "C131"
			(at -14.149998 -17.25 180)
			(layer "F.SilkS")
			(effects
				(font
					(size 0.7 0.7)
					(thickness 0.15)
				)
			)
		)
		(property "Value" "C_33p_0402"
			(at -1.022927 2.155213 180)
			(layer "F.Fab")
			(effects
				(font
					(size 0.7 0.7)
					(thickness 0.15)
				)
				(justify left bottom)
			)
		)
		(property "Datasheet" "https://spicat.kyocera-avx.com/product/mlcc/chartview/04025A330FAT2A/"
			(at 0 0 180)
			(layer "F.Fab")
			(hide yes)
			(effects
				(font
					(size 1.27 1.27)
					(thickness 0.15)
				)
			)
		)
		(property "Description" "SMD Multilayer Ceramic Capacitor, 33 pF, 50 V, 0402 [1005 Metric], ± 5%, C0G / NP0, MC"
			(at 0 0 180)
			(layer "F.Fab")
			(hide yes)
			(effects
				(font
					(size 1.27 1.27)
					(thickness 0.15)
				)
			)
		)
		(property "MPN" "04025A330FAT2A"
			(at 0 0 180)
			(unlocked yes)
			(layer "F.Fab")
			(hide yes)
			(effects
				(font
					(size 1 1)
					(thickness 0.15)
				)
			)
		)
		(property "Manufacturer" "KYOCERA AVX"
			(at 0 0 180)
			(unlocked yes)
			(layer "F.Fab")
			(hide yes)
			(effects
				(font
					(size 1 1)
					(thickness 0.15)
				)
			)
		)
		(property "License" "Apache-2.0"
			(at 0 0 180)
			(unlocked yes)
			(layer "F.Fab")
			(hide yes)
			(effects
				(font
					(size 1 1)
					(thickness 0.15)
				)
			)
		)
		(property "Author" "Antmicro"
			(at 0 0 180)
			(unlocked yes)
			(layer "F.Fab")
			(hide yes)
			(effects
				(font
					(size 1 1)
					(thickness 0.15)
				)
			)
		)
		(property "Val" "33p"
			(at 0 0 180)
			(unlocked yes)
			(layer "F.Fab")
			(hide yes)
			(effects
				(font
					(size 1 1)
					(thickness 0.15)
				)
			)
		)
		(property "Voltage" ""
			(at 0 0 180)
			(unlocked yes)
			(layer "F.Fab")
			(hide yes)
			(effects
				(font
					(size 1 1)
					(thickness 0.15)
				)
			)
		)
		(property "Dielectric" ""
			(at 0 0 180)
			(unlocked yes)
			(layer "F.Fab")
			(hide yes)
			(effects
				(font
					(size 1 1)
					(thickness 0.15)
				)
			)
		)
		(sheetname "/X710 DCDC converters/")
		(sheetfile "DCDC_converters_X710.kicad_sch")
		(attr smd dnp)
		(fp_rect
			(start -0.925 -0.47)
			(end 0.925 0.47)
			(stroke
				(width 0.05)
				(type default)
			)
			(fill no)
			(layer "F.CrtYd")
		)
		(fp_line
			(start 0.504 0.248)
			(end -0.494 0.248)
			(stroke
				(width 0.15)
				(type solid)
			)
			(layer "F.Fab")
		)
		(fp_line
			(start 0.504 -0.25)
			(end 0.504 0.248)
			(stroke
				(width 0.15)
				(type solid)
			)
			(layer "F.Fab")
		)
		(fp_line
			(start -0.494 0.248)
			(end -0.494 -0.25)
			(stroke
				(width 0.15)
				(type solid)
			)
			(layer "F.Fab")
		)
		(fp_line
			(start -0.494 -0.25)
			(end 0.504 -0.25)
			(stroke
				(width 0.15)
				(type solid)
			)
			(layer "F.Fab")
		)
		(fp_text user "${REFERENCE}"
			(at -0.939 4.599 180)
			(layer "F.Fab")
			(effects
				(font
					(size 0.7 0.7)
					(thickness 0.15)
				)
				(justify left bottom)
			)
		)
		(fp_text user "License: Apache-2.0"
			(at -0.939 5.799 180)
			(layer "F.Fab")
			(effects
				(font
					(size 0.7 0.7)
					(thickness 0.15)
				)
				(justify left bottom)
			)
		)
		(fp_text user "Author: Antmicro"
			(at -0.939 3.399 180)
			(layer "F.Fab")
			(effects
				(font
					(size 0.7 0.7)
					(thickness 0.15)
				)
				(justify left bottom)
			)
		)
		(pad "1" smd roundrect
			(at -0.48 0 180)
			(size 0.59 0.64)
			(layers "F.Cu" "F.Mask" "F.Paste")
			(roundrect_rratio 0.25)
			(net 337 "/X710 DCDC converters/1V88_FB")
			(pintype "passive")
		)
		(pad "2" smd roundrect
			(at 0.48 0 180)
			(size 0.59 0.64)
			(layers "F.Cu" "F.Mask" "F.Paste")
			(roundrect_rratio 0.25)
			(net 338 "/X710 DCDC converters/+1V88_OUT")
			(pintype "passive")
		)
	)
	(footprint "antmicro-footprints:C_0402_1005Metric"
		(layer "F.Cu")
		(at 138 80.75)
		(descr "Capacitor SMD 0402")
		(tags "capacitor SMD 0402")
		(property "Reference" "C273"
			(at -3.8 0.45 0)
			(layer "F.SilkS")
			(effects
				(font
					(size 0.7 0.7)
					(thickness 0.15)
				)
				(justify left bottom)
			)
		)
		(property "Value" "C_220n_16V_0402"
			(at -1.022927 2.155213 0)
			(layer "F.Fab")
			(effects
				(font
					(size 0.7 0.7)
					(thickness 0.15)
				)
				(justify left bottom)
			)
		)
		(property "Datasheet" "https://www.murata.com/products/productdetail?partno=GRM155R71C224KA12%23"
			(at 0 0 0)
			(layer "F.Fab")
			(hide yes)
			(effects
				(font
					(size 1.27 1.27)
					(thickness 0.15)
				)
			)
		)
		(property "Description" "SMD Multilayer Ceramic Capacitor, 0.22 µF, 16 V, 0402 [1005 Metric], ± 10%, X7R, GRM Series"
			(at 0 0 0)
			(layer "F.Fab")
			(hide yes)
			(effects
				(font
					(size 1.27 1.27)
					(thickness 0.15)
				)
			)
		)
		(property "MPN" "GRM155R71C224KA12D"
			(at 0 0 0)
			(unlocked yes)
			(layer "F.Fab")
			(hide yes)
			(effects
				(font
					(size 1 1)
					(thickness 0.15)
				)
			)
		)
		(property "Manufacturer" "Murata"
			(at 0 0 0)
			(unlocked yes)
			(layer "F.Fab")
			(hide yes)
			(effects
				(font
					(size 1 1)
					(thickness 0.15)
				)
			)
		)
		(property "License" "Apache-2.0"
			(at 0 0 0)
			(unlocked yes)
			(layer "F.Fab")
			(hide yes)
			(effects
				(font
					(size 1 1)
					(thickness 0.15)
				)
			)
		)
		(property "Author" "Antmicro"
			(at 0 0 0)
			(unlocked yes)
			(layer "F.Fab")
			(hide yes)
			(effects
				(font
					(size 1 1)
					(thickness 0.15)
				)
			)
		)
		(property "Val" "220n"
			(at 0 0 0)
			(unlocked yes)
			(layer "F.Fab")
			(hide yes)
			(effects
				(font
					(size 1 1)
					(thickness 0.15)
				)
			)
		)
		(property "Voltage" "16V"
			(at 0 0 0)
			(unlocked yes)
			(layer "F.Fab")
			(hide yes)
			(effects
				(font
					(size 1 1)
					(thickness 0.15)
				)
			)
		)
		(property "Dielectric" "X7R"
			(at 0 0 0)
			(unlocked yes)
			(layer "F.Fab")
			(hide yes)
			(effects
				(font
					(size 1 1)
					(thickness 0.15)
				)
			)
		)
		(sheetname "/X710-AT2 PCIe/")
		(sheetfile "x710-at2-pcie.kicad_sch")
		(attr smd)
		(fp_rect
			(start -0.925 -0.47)
			(end 0.925 0.47)
			(stroke
				(width 0.05)
				(type default)
			)
			(fill no)
			(layer "F.CrtYd")
		)
		(fp_line
			(start -0.494 -0.25)
			(end 0.504 -0.25)
			(stroke
				(width 0.15)
				(type solid)
			)
			(layer "F.Fab")
		)
		(fp_line
			(start -0.494 0.248)
			(end -0.494 -0.25)
			(stroke
				(width 0.15)
				(type solid)
			)
			(layer "F.Fab")
		)
		(fp_line
			(start 0.504 -0.25)
			(end 0.504 0.248)
			(stroke
				(width 0.15)
				(type solid)
			)
			(layer "F.Fab")
		)
		(fp_line
			(start 0.504 0.248)
			(end -0.494 0.248)
			(stroke
				(width 0.15)
				(type solid)
			)
			(layer "F.Fab")
		)
		(fp_text user "License: Apache-2.0"
			(at -0.939 5.799 0)
			(layer "F.Fab")
			(effects
				(font
					(size 0.7 0.7)
					(thickness 0.15)
				)
				(justify left bottom)
			)
		)
		(fp_text user "${REFERENCE}"
			(at -0.939 4.599 0)
			(layer "F.Fab")
			(effects
				(font
					(size 0.7 0.7)
					(thickness 0.15)
				)
				(justify left bottom)
			)
		)
		(fp_text user "Author: Antmicro"
			(at -0.939 3.399 0)
			(layer "F.Fab")
			(effects
				(font
					(size 0.7 0.7)
					(thickness 0.15)
				)
				(justify left bottom)
			)
		)
		(pad "1" smd roundrect
			(at -0.48 0)
			(size 0.59 0.64)
			(layers "F.Cu" "F.Mask" "F.Paste")
			(roundrect_rratio 0.25)
			(net 601 "/TB Controller/PCIex4.TX3+")
			(pintype "passive")
		)
		(pad "2" smd roundrect
			(at 0.48 0)
			(size 0.59 0.64)
			(layers "F.Cu" "F.Mask" "F.Paste")
			(roundrect_rratio 0.25)
			(net 33 "/X710-AT2 PCIe/PCIe_{x4}_AC.TX3+")
			(pintype "passive")
		)
	)
	(footprint "antmicro-footprints:R_0402_1005Metric"
		(layer "F.Cu")
		(at 119.25 65.5 180)
		(descr "Resistor SMD 0402")
		(tags "resistor SMD 0402")
		(property "Reference" "R132"
			(at -3.45 -1.4 180)
			(layer "F.SilkS")
			(effects
				(font
					(size 0.7 0.7)
					(thickness 0.15)
				)
				(justify left bottom)
			)
		)
		(property "Value" "R_10k_0402"
			(at -1.011843 1.772047 180)
			(layer "F.Fab")
			(effects
				(font
					(size 0.7 0.7)
					(thickness 0.15)
				)
				(justify left bottom)
			)
		)
		(property "Datasheet" "https://www.bourns.com/docs/product-datasheets/cr.pdf"
			(at 0 0 180)
			(layer "F.Fab")
			(hide yes)
			(effects
				(font
					(size 1.27 1.27)
					(thickness 0.15)
				)
			)
		)
		(property "Description" "SMD Chip Resistor, 10 kohm, ± 1%, 62.5 mW, 0402 [1005 Metric], Thick Film, General Purpose"
			(at 0 0 180)
			(layer "F.Fab")
			(hide yes)
			(effects
				(font
					(size 1.27 1.27)
					(thickness 0.15)
				)
			)
		)
		(property "MPN" "CR0402-FX-1002GLF"
			(at 0 0 180)
			(unlocked yes)
			(layer "F.Fab")
			(hide yes)
			(effects
				(font
					(size 1 1)
					(thickness 0.15)
				)
			)
		)
		(property "Manufacturer" "Bourns"
			(at 0 0 180)
			(unlocked yes)
			(layer "F.Fab")
			(hide yes)
			(effects
				(font
					(size 1 1)
					(thickness 0.15)
				)
			)
		)
		(property "License" "Apache-2.0"
			(at 0 0 180)
			(unlocked yes)
			(layer "F.Fab")
			(hide yes)
			(effects
				(font
					(size 1 1)
					(thickness 0.15)
				)
			)
		)
		(property "Author" "Antmicro"
			(at 0 0 180)
			(unlocked yes)
			(layer "F.Fab")
			(hide yes)
			(effects
				(font
					(size 1 1)
					(thickness 0.15)
				)
			)
		)
		(property "Val" "10k"
			(at 0 0 180)
			(unlocked yes)
			(layer "F.Fab")
			(hide yes)
			(effects
				(font
					(size 1 1)
					(thickness 0.15)
				)
			)
		)
		(property "Tolerance" "1%"
			(at 0 0 180)
			(unlocked yes)
			(layer "F.Fab")
			(hide yes)
			(effects
				(font
					(size 1 1)
					(thickness 0.15)
				)
			)
		)
		(sheetname "/X710-AT2 RSVD/")
		(sheetfile "x710-at2-rsvd.kicad_sch")
		(attr smd)
		(fp_rect
			(start -0.925 -0.47)
			(end 0.925 0.47)
			(stroke
				(width 0.05)
				(type default)
			)
			(fill no)
			(layer "F.CrtYd")
		)
		(fp_rect
			(start -0.5 -0.25)
			(end 0.5 0.25)
			(stroke
				(width 0.15)
				(type solid)
			)
			(fill no)
			(layer "F.Fab")
		)
		(fp_text user "Author: Antmicro"
			(at -0.95 4.169 180)
			(layer "F.Fab")
			(effects
				(font
					(size 0.7 0.7)
					(thickness 0.15)
				)
				(justify left bottom)
			)
		)
		(fp_text user "${REFERENCE}"
			(at -0.95 3.168 180)
			(layer "F.Fab")
			(effects
				(font
					(size 0.7 0.7)
					(thickness 0.15)
				)
				(justify left bottom)
			)
		)
		(fp_text user "License: Apache-2.0"
			(at -0.95 5.169 180)
			(layer "F.Fab")
			(effects
				(font
					(size 0.7 0.7)
					(thickness 0.15)
				)
				(justify left bottom)
			)
		)
		(pad "1" smd roundrect
			(at -0.48 0 180)
			(size 0.59 0.64)
			(layers "F.Cu" "F.Mask" "F.Paste")
			(roundrect_rratio 0.25)
			(net 23 "GND")
			(pintype "passive")
		)
		(pad "2" smd roundrect
			(at 0.48 0 180)
			(size 0.59 0.64)
			(layers "F.Cu" "F.Mask" "F.Paste")
			(roundrect_rratio 0.25)
			(net 89 "/X710-AT2 RSVD/DEBUG_Y20")
			(pintype "passive")
		)
	)
	(footprint "antmicro-footprints:R_0402_1005Metric"
		(layer "F.Cu")
		(at 164 76.4 180)
		(descr "Resistor SMD 0402")
		(tags "resistor SMD 0402")
		(property "Reference" "R196"
			(at 1 -6.4 180)
			(layer "F.SilkS")
			(effects
				(font
					(size 0.7 0.7)
					(thickness 0.15)
				)
				(justify left bottom)
			)
		)
		(property "Value" "R_0R_0402"
			(at -1.011843 1.772047 180)
			(layer "F.Fab")
			(effects
				(font
					(size 0.7 0.7)
					(thickness 0.15)
				)
				(justify left bottom)
			)
		)
		(property "Datasheet" "https://industrial.panasonic.com/cdbs/www-data/pdf/RDA0000/AOA0000C301.pdf"
			(at 0 0 180)
			(layer "F.Fab")
			(hide yes)
			(effects
				(font
					(size 1.27 1.27)
					(thickness 0.15)
				)
			)
		)
		(property "Description" "SMD Chip Resistor, Jumper, 0 ohm, 100 mW, 0402 [1005 Metric], Thick Film, General Purpose"
			(at 0 0 180)
			(layer "F.Fab")
			(hide yes)
			(effects
				(font
					(size 1.27 1.27)
					(thickness 0.15)
				)
			)
		)
		(property "MPN" "ERJ2GE0R00X"
			(at 0 0 180)
			(unlocked yes)
			(layer "F.Fab")
			(hide yes)
			(effects
				(font
					(size 1 1)
					(thickness 0.15)
				)
			)
		)
		(property "Manufacturer" "Panasonic"
			(at 0 0 180)
			(unlocked yes)
			(layer "F.Fab")
			(hide yes)
			(effects
				(font
					(size 1 1)
					(thickness 0.15)
				)
			)
		)
		(property "License" "Apache-2.0"
			(at 0 0 180)
			(unlocked yes)
			(layer "F.Fab")
			(hide yes)
			(effects
				(font
					(size 1 1)
					(thickness 0.15)
				)
			)
		)
		(property "Author" "Antmicro"
			(at 0 0 180)
			(unlocked yes)
			(layer "F.Fab")
			(hide yes)
			(effects
				(font
					(size 1 1)
					(thickness 0.15)
				)
			)
		)
		(property "Val" "0R"
			(at 0 0 180)
			(unlocked yes)
			(layer "F.Fab")
			(hide yes)
			(effects
				(font
					(size 1 1)
					(thickness 0.15)
				)
			)
		)
		(property "Tolerance" "~"
			(at 0 0 180)
			(unlocked yes)
			(layer "F.Fab")
			(hide yes)
			(effects
				(font
					(size 1 1)
					(thickness 0.15)
				)
			)
		)
		(property "Current" "1A"
			(at 0 0 180)
			(unlocked yes)
			(layer "F.Fab")
			(hide yes)
			(effects
				(font
					(size 1 1)
					(thickness 0.15)
				)
			)
		)
		(sheetname "/X710-AT2 10GbE/")
		(sheetfile "x710-at2-10gbe.kicad_sch")
		(attr smd)
		(fp_rect
			(start -0.925 -0.47)
			(end 0.925 0.47)
			(stroke
				(width 0.05)
				(type default)
			)
			(fill no)
			(layer "F.CrtYd")
		)
		(fp_rect
			(start -0.5 -0.25)
			(end 0.5 0.25)
			(stroke
				(width 0.15)
				(type solid)
			)
			(fill no)
			(layer "F.Fab")
		)
		(fp_text user "License: Apache-2.0"
			(at -0.95 5.169 180)
			(layer "F.Fab")
			(effects
				(font
					(size 0.7 0.7)
					(thickness 0.15)
				)
				(justify left bottom)
			)
		)
		(fp_text user "Author: Antmicro"
			(at -0.95 4.169 180)
			(layer "F.Fab")
			(effects
				(font
					(size 0.7 0.7)
					(thickness 0.15)
				)
				(justify left bottom)
			)
		)
		(fp_text user "${REFERENCE}"
			(at -0.95 3.168 180)
			(layer "F.Fab")
			(effects
				(font
					(size 0.7 0.7)
					(thickness 0.15)
				)
				(justify left bottom)
			)
		)
		(pad "1" smd roundrect
			(at -0.48 0 180)
			(size 0.59 0.64)
			(layers "F.Cu" "F.Mask" "F.Paste")
			(roundrect_rratio 0.25)
			(net 146 "/X710-AT2 10GbE/~{PHY_RESET_3V3}")
			(pintype "passive")
		)
		(pad "2" smd roundrect
			(at 0.48 0 180)
			(size 0.59 0.64)
			(layers "F.Cu" "F.Mask" "F.Paste")
			(roundrect_rratio 0.25)
			(net 110 "/X710-AT2 10GbE/~{PHY_RESET_3V3_R}")
			(pintype "passive")
		)
	)
	(footprint "antmicro-footprints:R_0402_1005Metric"
		(layer "F.Cu")
		(at 159.249997 112.150001)
		(descr "Resistor SMD 0402")
		(tags "resistor SMD 0402")
		(property "Reference" "R105"
			(at 12.950004 17.25 0)
			(layer "F.SilkS")
			(effects
				(font
					(size 0.7 0.7)
					(thickness 0.15)
				)
			)
		)
		(property "Value" "R_30k_0402"
			(at -1.011843 1.772047 0)
			(layer "F.Fab")
			(effects
				(font
					(size 0.7 0.7)
					(thickness 0.15)
				)
				(justify left bottom)
			)
		)
		(property "Datasheet" "https://www.bourns.com/docs/product-datasheets/cr.pdf"
			(at 0 0 0)
			(layer "F.Fab")
			(hide yes)
			(effects
				(font
					(size 1.27 1.27)
					(thickness 0.15)
				)
			)
		)
		(property "Description" "SMD Chip Resistor, 30 kohm, ± 1%, 63 mW, 0402 [1005 Metric], Thick Film, General Purpose"
			(at 0 0 0)
			(layer "F.Fab")
			(hide yes)
			(effects
				(font
					(size 1.27 1.27)
					(thickness 0.15)
				)
			)
		)
		(property "MPN" "CR0402-FX-3002GLF"
			(at 0 0 0)
			(unlocked yes)
			(layer "F.Fab")
			(hide yes)
			(effects
				(font
					(size 1 1)
					(thickness 0.15)
				)
			)
		)
		(property "Manufacturer" "Bourns"
			(at 0 0 0)
			(unlocked yes)
			(layer "F.Fab")
			(hide yes)
			(effects
				(font
					(size 1 1)
					(thickness 0.15)
				)
			)
		)
		(property "License" "Apache-2.0"
			(at 0 0 0)
			(unlocked yes)
			(layer "F.Fab")
			(hide yes)
			(effects
				(font
					(size 1 1)
					(thickness 0.15)
				)
			)
		)
		(property "Author" "Antmicro"
			(at 0 0 0)
			(unlocked yes)
			(layer "F.Fab")
			(hide yes)
			(effects
				(font
					(size 1 1)
					(thickness 0.15)
				)
			)
		)
		(property "Val" "30k"
			(at 0 0 0)
			(unlocked yes)
			(layer "F.Fab")
			(hide yes)
			(effects
				(font
					(size 1 1)
					(thickness 0.15)
				)
			)
		)
		(property "Tolerance" "1%"
			(at 0 0 0)
			(unlocked yes)
			(layer "F.Fab")
			(hide yes)
			(effects
				(font
					(size 1 1)
					(thickness 0.15)
				)
			)
		)
		(sheetname "/X710 DCDC converters/")
		(sheetfile "DCDC_converters_X710.kicad_sch")
		(attr smd)
		(fp_rect
			(start -0.925 -0.47)
			(end 0.925 0.47)
			(stroke
				(width 0.05)
				(type default)
			)
			(fill no)
			(layer "F.CrtYd")
		)
		(fp_rect
			(start -0.5 -0.25)
			(end 0.5 0.25)
			(stroke
				(width 0.15)
				(type solid)
			)
			(fill no)
			(layer "F.Fab")
		)
		(fp_text user "Author: Antmicro"
			(at -0.95 4.169 0)
			(layer "F.Fab")
			(effects
				(font
					(size 0.7 0.7)
					(thickness 0.15)
				)
				(justify left bottom)
			)
		)
		(fp_text user "License: Apache-2.0"
			(at -0.95 5.169 0)
			(layer "F.Fab")
			(effects
				(font
					(size 0.7 0.7)
					(thickness 0.15)
				)
				(justify left bottom)
			)
		)
		(fp_text user "${REFERENCE}"
			(at -0.95 3.168 0)
			(layer "F.Fab")
			(effects
				(font
					(size 0.7 0.7)
					(thickness 0.15)
				)
				(justify left bottom)
			)
		)
		(pad "1" smd roundrect
			(at -0.48 0)
			(size 0.59 0.64)
			(layers "F.Cu" "F.Mask" "F.Paste")
			(roundrect_rratio 0.25)
			(net 23 "GND")
			(pintype "passive")
		)
		(pad "2" smd roundrect
			(at 0.48 0)
			(size 0.59 0.64)
			(layers "F.Cu" "F.Mask" "F.Paste")
			(roundrect_rratio 0.25)
			(net 340 "/X710 DCDC converters/1V0_FB")
			(pintype "passive")
		)
	)
	(footprint "antmicro-footprints:TSSOP-8_3x3mm_P0.65mm"
		(layer "F.Cu")
		(at 165.5 71.674999 -90)
		(property "Reference" "U17"
			(at -1.274999 1.9 270)
			(layer "F.SilkS")
			(effects
				(font
					(size 0.7 0.7)
					(thickness 0.15)
				)
				(justify left bottom)
			)
		)
		(property "Value" "NTS0102_TSSOP"
			(at 0 2.8 270)
			(layer "F.Fab")
			(effects
				(font
					(size 0.7 0.7)
					(thickness 0.15)
				)
				(justify left bottom)
			)
		)
		(property "Datasheet" "https://www.mouser.com/datasheet/2/302/NTS0102-1127324.pdf"
			(at 0 0 270)
			(layer "F.Fab")
			(hide yes)
			(effects
				(font
					(size 1.27 1.27)
					(thickness 0.15)
				)
			)
		)
		(property "Description" "Transceiver, 1.65 V to 3.6 V, TSSOP-8"
			(at 0 0 270)
			(layer "F.Fab")
			(hide yes)
			(effects
				(font
					(size 1.27 1.27)
					(thickness 0.15)
				)
			)
		)
		(property "MPN" "NTS0102DP"
			(at 0 0 270)
			(unlocked yes)
			(layer "F.Fab")
			(hide yes)
			(effects
				(font
					(size 1 1)
					(thickness 0.15)
				)
			)
		)
		(property "Manufacturer" "NXP"
			(at 0 0 270)
			(unlocked yes)
			(layer "F.Fab")
			(hide yes)
			(effects
				(font
					(size 1 1)
					(thickness 0.15)
				)
			)
		)
		(property "Author" "Antmicro"
			(at 0 0 270)
			(unlocked yes)
			(layer "F.Fab")
			(hide yes)
			(effects
				(font
					(size 1 1)
					(thickness 0.15)
				)
			)
		)
		(property "License" "Apache-2.0"
			(at 0 0 270)
			(unlocked yes)
			(layer "F.Fab")
			(hide yes)
			(effects
				(font
					(size 1 1)
					(thickness 0.15)
				)
			)
		)
		(sheetname "/X710-AT2 Misc/")
		(sheetfile "x710-at2-mics.kicad_sch")
		(attr smd)
		(fp_line
			(start -1.55 1.561)
			(end 1.552 1.561)
			(stroke
				(width 0.15)
				(type solid)
			)
			(layer "F.SilkS")
		)
		(fp_line
			(start -1.525 -1.537)
			(end 1.552 -1.539)
			(stroke
				(width 0.15)
				(type solid)
			)
			(layer "F.SilkS")
		)
		(fp_circle
			(center -1.87 -1.4)
			(end -1.82 -1.4)
			(stroke
				(width 0.15)
				(type solid)
			)
			(fill yes)
			(layer "F.SilkS")
		)
		(fp_rect
			(start -3.15 -1.789)
			(end 3.15 1.811)
			(stroke
				(width 0.05)
				(type solid)
			)
			(fill no)
			(layer "F.CrtYd")
		)
		(fp_line
			(start -1.55 1.561)
			(end 1.552 1.561)
			(stroke
				(width 0.15)
				(type solid)
			)
			(layer "F.Fab")
		)
		(fp_line
			(start -1.55 -0.937)
			(end -1.55 1.561)
			(stroke
				(width 0.15)
				(type solid)
			)
			(layer "F.Fab")
		)
		(fp_line
			(start -1.55 -0.937)
			(end -0.949 -1.539)
			(stroke
				(width 0.15)
				(type solid)
			)
			(layer "F.Fab")
		)
		(fp_line
			(start -0.949 -1.539)
			(end 1.552 -1.539)
			(stroke
				(width 0.15)
				(type solid)
			)
			(layer "F.Fab")
		)
		(fp_line
			(start 1.552 -1.539)
			(end 1.552 1.561)
			(stroke
				(width 0.15)
				(type solid)
			)
			(layer "F.Fab")
		)
		(fp_text user "Author: Antmicro"
			(at -1.789 7.78 270)
			(layer "F.Fab")
			(effects
				(font
					(size 0.7 0.7)
					(thickness 0.15)
				)
				(justify left bottom)
			)
		)
		(fp_text user "${REFERENCE}"
			(at -1.789 6.58 270)
			(layer "F.Fab")
			(effects
				(font
					(size 0.7 0.7)
					(thickness 0.15)
				)
				(justify left bottom)
			)
		)
		(fp_text user "License: Apache-2.0"
			(at -1.789 8.98 270)
			(layer "F.Fab")
			(effects
				(font
					(size 0.7 0.7)
					(thickness 0.15)
				)
				(justify left bottom)
			)
		)
		(pad "1" smd roundrect
			(at -2.148 -0.962 270)
			(size 1.47 0.4)
			(layers "F.Cu" "F.Mask" "F.Paste")
			(roundrect_rratio 0.25)
			(net 438 "Net-(U17-B_{2})")
			(pinfunction "B_{2}")
			(pintype "bidirectional")
		)
		(pad "2" smd roundrect
			(at -2.148 -0.313 270)
			(size 1.47 0.4)
			(layers "F.Cu" "F.Mask" "F.Paste")
			(roundrect_rratio 0.25)
			(net 23 "GND")
			(pinfunction "GND")
			(pintype "power_in")
		)
		(pad "3" smd roundrect
			(at -2.148 0.338 270)
			(size 1.47 0.4)
			(layers "F.Cu" "F.Mask" "F.Paste")
			(roundrect_rratio 0.25)
			(net 18 "+1V88")
			(pinfunction "VCC_{A}")
			(pintype "power_in")
		)
		(pad "4" smd roundrect
			(at -2.148 0.987 270)
			(size 1.47 0.4)
			(layers "F.Cu" "F.Mask" "F.Paste")
			(roundrect_rratio 0.25)
			(net 439 "Net-(U17-A_{2})")
			(pinfunction "A_{2}")
			(pintype "bidirectional")
		)
		(pad "5" smd roundrect
			(at 2.151 0.987 270)
			(size 1.47 0.4)
			(layers "F.Cu" "F.Mask" "F.Paste")
			(roundrect_rratio 0.25)
			(net 150 "/X710-AT2 Misc/~{PHY_RESET}")
			(pinfunction "A_{1}")
			(pintype "bidirectional")
		)
		(pad "6" smd roundrect
			(at 2.151 0.338 270)
			(size 1.47 0.4)
			(layers "F.Cu" "F.Mask" "F.Paste")
			(roundrect_rratio 0.25)
			(net 18 "+1V88")
			(pinfunction "OE")
			(pintype "input")
		)
		(pad "7" smd roundrect
			(at 2.151 -0.313 270)
			(size 1.47 0.4)
			(layers "F.Cu" "F.Mask" "F.Paste")
			(roundrect_rratio 0.25)
			(net 7 "+3V3")
			(pinfunction "VCC_{B}")
			(pintype "power_in")
		)
		(pad "8" smd roundrect
			(at 2.151 -0.962 270)
			(size 1.47 0.4)
			(layers "F.Cu" "F.Mask" "F.Paste")
			(roundrect_rratio 0.25)
			(net 146 "/X710-AT2 10GbE/~{PHY_RESET_3V3}")
			(pinfunction "B_{1}")
			(pintype "bidirectional")
		)
	)
	(footprint "antmicro-footprints:C_0402_1005Metric"
		(layer "F.Cu")
		(at 136.149999 111.149999 180)
		(descr "Capacitor SMD 0402")
		(tags "capacitor SMD 0402")
		(property "Reference" "C130"
			(at -16.549997 -17.25 180)
			(layer "F.SilkS")
			(effects
				(font
					(size 0.7 0.7)
					(thickness 0.15)
				)
			)
		)
		(property "Value" "C_33p_0402"
			(at -1.022927 2.155213 180)
			(layer "F.Fab")
			(effects
				(font
					(size 0.7 0.7)
					(thickness 0.15)
				)
				(justify left bottom)
			)
		)
		(property "Datasheet" "https://spicat.kyocera-avx.com/product/mlcc/chartview/04025A330FAT2A/"
			(at 0 0 180)
			(layer "F.Fab")
			(hide yes)
			(effects
				(font
					(size 1.27 1.27)
					(thickness 0.15)
				)
			)
		)
		(property "Description" "SMD Multilayer Ceramic Capacitor, 33 pF, 50 V, 0402 [1005 Metric], ± 5%, C0G / NP0, MC"
			(at 0 0 180)
			(layer "F.Fab")
			(hide yes)
			(effects
				(font
					(size 1.27 1.27)
					(thickness 0.15)
				)
			)
		)
		(property "MPN" "04025A330FAT2A"
			(at 0 0 180)
			(unlocked yes)
			(layer "F.Fab")
			(hide yes)
			(effects
				(font
					(size 1 1)
					(thickness 0.15)
				)
			)
		)
		(property "Manufacturer" "KYOCERA AVX"
			(at 0 0 180)
			(unlocked yes)
			(layer "F.Fab")
			(hide yes)
			(effects
				(font
					(size 1 1)
					(thickness 0.15)
				)
			)
		)
		(property "License" "Apache-2.0"
			(at 0 0 180)
			(unlocked yes)
			(layer "F.Fab")
			(hide yes)
			(effects
				(font
					(size 1 1)
					(thickness 0.15)
				)
			)
		)
		(property "Author" "Antmicro"
			(at 0 0 180)
			(unlocked yes)
			(layer "F.Fab")
			(hide yes)
			(effects
				(font
					(size 1 1)
					(thickness 0.15)
				)
			)
		)
		(property "Val" "33p"
			(at 0 0 180)
			(unlocked yes)
			(layer "F.Fab")
			(hide yes)
			(effects
				(font
					(size 1 1)
					(thickness 0.15)
				)
			)
		)
		(property "Voltage" ""
			(at 0 0 180)
			(unlocked yes)
			(layer "F.Fab")
			(hide yes)
			(effects
				(font
					(size 1 1)
					(thickness 0.15)
				)
			)
		)
		(property "Dielectric" ""
			(at 0 0 180)
			(unlocked yes)
			(layer "F.Fab")
			(hide yes)
			(effects
				(font
					(size 1 1)
					(thickness 0.15)
				)
			)
		)
		(sheetname "/X710 DCDC converters/")
		(sheetfile "DCDC_converters_X710.kicad_sch")
		(attr smd dnp)
		(fp_rect
			(start -0.925 -0.47)
			(end 0.925 0.47)
			(stroke
				(width 0.05)
				(type default)
			)
			(fill no)
			(layer "F.CrtYd")
		)
		(fp_line
			(start 0.504 0.248)
			(end -0.494 0.248)
			(stroke
				(width 0.15)
				(type solid)
			)
			(layer "F.Fab")
		)
		(fp_line
			(start 0.504 -0.25)
			(end 0.504 0.248)
			(stroke
				(width 0.15)
				(type solid)
			)
			(layer "F.Fab")
		)
		(fp_line
			(start -0.494 0.248)
			(end -0.494 -0.25)
			(stroke
				(width 0.15)
				(type solid)
			)
			(layer "F.Fab")
		)
		(fp_line
			(start -0.494 -0.25)
			(end 0.504 -0.25)
			(stroke
				(width 0.15)
				(type solid)
			)
			(layer "F.Fab")
		)
		(fp_text user "${REFERENCE}"
			(at -0.939 4.599 180)
			(layer "F.Fab")
			(effects
				(font
					(size 0.7 0.7)
					(thickness 0.15)
				)
				(justify left bottom)
			)
		)
		(fp_text user "License: Apache-2.0"
			(at -0.939 5.799 180)
			(layer "F.Fab")
			(effects
				(font
					(size 0.7 0.7)
					(thickness 0.15)
				)
				(justify left bottom)
			)
		)
		(fp_text user "Author: Antmicro"
			(at -0.939 3.399 180)
			(layer "F.Fab")
			(effects
				(font
					(size 0.7 0.7)
					(thickness 0.15)
				)
				(justify left bottom)
			)
		)
		(pad "1" smd roundrect
			(at -0.48 0 180)
			(size 0.59 0.64)
			(layers "F.Cu" "F.Mask" "F.Paste")
			(roundrect_rratio 0.25)
			(net 336 "/X710 DCDC converters/VCCD_FB")
			(pintype "passive")
		)
		(pad "2" smd roundrect
			(at 0.48 0 180)
			(size 0.59 0.64)
			(layers "F.Cu" "F.Mask" "F.Paste")
			(roundrect_rratio 0.25)
			(net 335 "/X710 DCDC converters/+VCCD_OUT")
			(pintype "passive")
		)
	)
	(footprint "antmicro-footprints:C_0603_1608Metric"
		(layer "F.Cu")
		(at 153.004998 66.024998 90)
		(descr "Capacitor SMD 0603")
		(tags "capacitor 0603")
		(property "Reference" "C216"
			(at 12.424999 20.045 90)
			(layer "F.SilkS")
			(effects
				(font
					(size 0.7 0.7)
					(thickness 0.15)
				)
			)
		)
		(property "Value" "C_10u_10V_X7R_0603"
			(at -1.42757 1.770288 90)
			(layer "F.Fab")
			(effects
				(font
					(size 0.7 0.7)
					(thickness 0.15)
				)
				(justify left bottom)
			)
		)
		(property "Datasheet" "https://www.murata.com/products/productdetail?partno=GRM188Z71A106KA73%23"
			(at 0 0 90)
			(layer "F.Fab")
			(hide yes)
			(effects
				(font
					(size 1.27 1.27)
					(thickness 0.15)
				)
			)
		)
		(property "Description" "SMD Multilayer Ceramic Capacitor,  10µF, 10V, 0603, ±10%, X7R"
			(at 0 0 90)
			(layer "F.Fab")
			(hide yes)
			(effects
				(font
					(size 1.27 1.27)
					(thickness 0.15)
				)
			)
		)
		(property "MPN" "GRM188Z71A106KA73D"
			(at 0 0 90)
			(unlocked yes)
			(layer "F.Fab")
			(hide yes)
			(effects
				(font
					(size 1 1)
					(thickness 0.15)
				)
			)
		)
		(property "Val" "10u"
			(at 0 0 90)
			(unlocked yes)
			(layer "F.Fab")
			(hide yes)
			(effects
				(font
					(size 1 1)
					(thickness 0.15)
				)
			)
		)
		(property "Voltage" "10V"
			(at 0 0 90)
			(unlocked yes)
			(layer "F.Fab")
			(hide yes)
			(effects
				(font
					(size 1 1)
					(thickness 0.15)
				)
			)
		)
		(property "Dielectric" "X7R"
			(at 0 0 90)
			(unlocked yes)
			(layer "F.Fab")
			(hide yes)
			(effects
				(font
					(size 1 1)
					(thickness 0.15)
				)
			)
		)
		(property "Manufacturer" "Murata"
			(at 0 0 90)
			(unlocked yes)
			(layer "F.Fab")
			(hide yes)
			(effects
				(font
					(size 1 1)
					(thickness 0.15)
				)
			)
		)
		(property "License" "Apache-2.0"
			(at 0 0 90)
			(unlocked yes)
			(layer "F.Fab")
			(hide yes)
			(effects
				(font
					(size 1 1)
					(thickness 0.15)
				)
			)
		)
		(property "Author" "Antmicro"
			(at 0 0 90)
			(unlocked yes)
			(layer "F.Fab")
			(hide yes)
			(effects
				(font
					(size 1 1)
					(thickness 0.15)
				)
			)
		)
		(sheetname "/X710-AT2 power/")
		(sheetfile "x710-at2-power.kicad_sch")
		(attr smd)
		(fp_line
			(start -0.15 -0.4)
			(end 0.15 -0.4)
			(stroke
				(width 0.15)
				(type solid)
			)
			(layer "F.SilkS")
		)
		(fp_line
			(start -0.15 0.4)
			(end 0.15 0.4)
			(stroke
				(width 0.15)
				(type solid)
			)
			(layer "F.SilkS")
		)
		(fp_rect
			(start -1.25 -0.65)
			(end 1.25 0.65)
			(stroke
				(width 0.05)
				(type solid)
			)
			(fill no)
			(layer "F.CrtYd")
		)
		(fp_rect
			(start -0.8 -0.4)
			(end 0.8 0.4)
			(stroke
				(width 0.15)
				(type solid)
			)
			(fill no)
			(layer "F.Fab")
		)
		(fp_text user "Author: Antmicro"
			(at -1.682 4.894 90)
			(layer "F.Fab")
			(effects
				(font
					(size 0.7 0.7)
					(thickness 0.15)
				)
				(justify left bottom)
			)
		)
		(fp_text user "${REFERENCE}"
			(at -1.682 3.895 90)
			(layer "F.Fab")
			(effects
				(font
					(size 0.7 0.7)
					(thickness 0.15)
				)
				(justify left bottom)
			)
		)
		(fp_text user "License: Apache-2.0"
			(at -1.682 5.895 90)
			(layer "F.Fab")
			(effects
				(font
					(size 0.7 0.7)
					(thickness 0.15)
				)
				(justify left bottom)
			)
		)
		(pad "1" smd roundrect
			(at -0.7 0 90)
			(size 0.8 1)
			(layers "F.Cu" "F.Mask" "F.Paste")
			(roundrect_rratio 0.2)
			(net 23 "GND")
			(pintype "passive")
		)
		(pad "2" smd roundrect
			(at 0.7 0 90)
			(size 0.8 1)
			(layers "F.Cu" "F.Mask" "F.Paste")
			(roundrect_rratio 0.2)
			(net 1 "VCCA")
			(pintype "passive")
		)
	)
	(footprint "antmicro-footprints:C_0603_1608Metric_EIA"
		(layer "F.Cu")
		(at 159.55 105.600001 90)
		(descr "Capacitor SMD 0603, IPC-7351 Density Level A")
		(tags "Capacitor 0603")
		(property "Reference" "C142"
			(at -17.849995 13.250002 90)
			(layer "F.SilkS")
			(effects
				(font
					(size 0.7 0.7)
					(thickness 0.15)
				)
			)
		)
		(property "Value" "C_22u_16V_0603"
			(at -1.42757 1.770288 90)
			(layer "F.Fab")
			(effects
				(font
					(size 0.7 0.7)
					(thickness 0.15)
				)
				(justify left bottom)
			)
		)
		(property "Datasheet" "https://product.samsungsem.com/mlcc/CL10A226MO7JZN.do"
			(at 0 0 90)
			(layer "F.Fab")
			(hide yes)
			(effects
				(font
					(size 1.27 1.27)
					(thickness 0.15)
				)
			)
		)
		(property "Description" "SMD Multilayer Ceramic Capacitor"
			(at 0 0 90)
			(layer "F.Fab")
			(hide yes)
			(effects
				(font
					(size 1.27 1.27)
					(thickness 0.15)
				)
			)
		)
		(property "MPN" "CL10A226MO7JZNC"
			(at 0 0 90)
			(unlocked yes)
			(layer "F.Fab")
			(hide yes)
			(effects
				(font
					(size 1 1)
					(thickness 0.15)
				)
			)
		)
		(property "Manufacturer" "Samsung Electro-Mechanics"
			(at 0 0 90)
			(unlocked yes)
			(layer "F.Fab")
			(hide yes)
			(effects
				(font
					(size 1 1)
					(thickness 0.15)
				)
			)
		)
		(property "License" "Apache-2.0"
			(at 0 0 90)
			(unlocked yes)
			(layer "F.Fab")
			(hide yes)
			(effects
				(font
					(size 1 1)
					(thickness 0.15)
				)
			)
		)
		(property "Author" "Antmicro"
			(at 0 0 90)
			(unlocked yes)
			(layer "F.Fab")
			(hide yes)
			(effects
				(font
					(size 1 1)
					(thickness 0.15)
				)
			)
		)
		(property "Val" "22u"
			(at 0 0 90)
			(unlocked yes)
			(layer "F.Fab")
			(hide yes)
			(effects
				(font
					(size 1 1)
					(thickness 0.15)
				)
			)
		)
		(property "Voltage" "16V"
			(at 0 0 90)
			(unlocked yes)
			(layer "F.Fab")
			(hide yes)
			(effects
				(font
					(size 1 1)
					(thickness 0.15)
				)
			)
		)
		(property "Dielectric" ""
			(at 0 0 90)
			(unlocked yes)
			(layer "F.Fab")
			(hide yes)
			(effects
				(font
					(size 1 1)
					(thickness 0.15)
				)
			)
		)
		(sheetname "/X710 DCDC converters/")
		(sheetfile "DCDC_converters_X710.kicad_sch")
		(attr smd)
		(fp_line
			(start -0.15 -0.55)
			(end 0.15 -0.55)
			(stroke
				(width 0.15)
				(type solid)
			)
			(layer "F.SilkS")
		)
		(fp_line
			(start -0.15 0.55)
			(end 0.15 0.55)
			(stroke
				(width 0.15)
				(type solid)
			)
			(layer "F.SilkS")
		)
		(fp_rect
			(start -1.25 -0.65)
			(end 1.25 0.65)
			(stroke
				(width 0.05)
				(type solid)
			)
			(fill no)
			(layer "F.CrtYd")
		)
		(fp_rect
			(start -0.8 -0.45)
			(end 0.8 0.45)
			(stroke
				(width 0.15)
				(type solid)
			)
			(fill no)
			(layer "F.Fab")
		)
		(fp_text user "Author: Antmicro"
			(at -1.682 4.894 90)
			(layer "F.Fab")
			(effects
				(font
					(size 0.7 0.7)
					(thickness 0.15)
				)
				(justify left bottom)
			)
		)
		(fp_text user "License: Apache-2.0"
			(at -1.682 5.895 90)
			(layer "F.Fab")
			(effects
				(font
					(size 0.7 0.7)
					(thickness 0.15)
				)
				(justify left bottom)
			)
		)
		(fp_text user "${REFERENCE}"
			(at -1.682 3.895 90)
			(layer "F.Fab")
			(effects
				(font
					(size 0.7 0.7)
					(thickness 0.15)
				)
				(justify left bottom)
			)
		)
		(pad "1" smd roundrect
			(at -0.7 0 90)
			(size 0.8 1.1)
			(layers "F.Cu" "F.Mask" "F.Paste")
			(roundrect_rratio 0.2)
			(net 23 "GND")
			(pintype "passive")
		)
		(pad "2" smd roundrect
			(at 0.7 0 90)
			(size 0.8 1.1)
			(layers "F.Cu" "F.Mask" "F.Paste")
			(roundrect_rratio 0.2)
			(net 339 "/X710 DCDC converters/+1V0_OUT")
			(pintype "passive")
		)
	)
	(footprint "antmicro-footprints:R_0603_1608Metric"
		(layer "F.Cu")
		(at 135.1 103.05 90)
		(descr "Resistor SMD 0603")
		(tags "resistor SMD 0603")
		(property "Reference" "R109"
			(at -17.649996 16.849997 90)
			(layer "F.SilkS")
			(effects
				(font
					(size 0.7 0.7)
					(thickness 0.15)
				)
			)
		)
		(property "Value" "R_0R_22.4A_0603"
			(at 0 1.6 90)
			(layer "F.Fab")
			(effects
				(font
					(size 0.7 0.7)
					(thickness 0.15)
				)
				(justify left bottom)
			)
		)
		(property "Datasheet" "https://fscdn.rohm.com/en/products/databook/datasheet/passive/resistor/chip_resistor/pmr-jpw-e.pdf"
			(at 0 0 90)
			(layer "F.Fab")
			(hide yes)
			(effects
				(font
					(size 1.27 1.27)
					(thickness 0.15)
				)
			)
		)
		(property "Description" "SMD Chip Resistor"
			(at 0 0 90)
			(layer "F.Fab")
			(hide yes)
			(effects
				(font
					(size 1.27 1.27)
					(thickness 0.15)
				)
			)
		)
		(property "MPN" "PMR03EZPJ000"
			(at 0 0 90)
			(unlocked yes)
			(layer "F.Fab")
			(hide yes)
			(effects
				(font
					(size 1 1)
					(thickness 0.15)
				)
			)
		)
		(property "Manufacturer" "ROHM Semiconductor"
			(at 0 0 90)
			(unlocked yes)
			(layer "F.Fab")
			(hide yes)
			(effects
				(font
					(size 1 1)
					(thickness 0.15)
				)
			)
		)
		(property "Val" "0R"
			(at 0 0 90)
			(unlocked yes)
			(layer "F.Fab")
			(hide yes)
			(effects
				(font
					(size 1 1)
					(thickness 0.15)
				)
			)
		)
		(property "Max. Curr." "22.4A"
			(at 0 0 90)
			(unlocked yes)
			(layer "F.Fab")
			(hide yes)
			(effects
				(font
					(size 1 1)
					(thickness 0.15)
				)
			)
		)
		(property "Author" "Antmicro"
			(at 0 0 90)
			(unlocked yes)
			(layer "F.Fab")
			(hide yes)
			(effects
				(font
					(size 1 1)
					(thickness 0.15)
				)
			)
		)
		(property "License" "Apache-2.0"
			(at 0 0 90)
			(unlocked yes)
			(layer "F.Fab")
			(hide yes)
			(effects
				(font
					(size 1 1)
					(thickness 0.15)
				)
			)
		)
		(property "Tolerance" "template_tolerance"
			(at 0 0 90)
			(unlocked yes)
			(layer "F.Fab")
			(hide yes)
			(effects
				(font
					(size 1 1)
					(thickness 0.15)
				)
			)
		)
		(sheetname "/X710 DCDC converters/")
		(sheetfile "DCDC_converters_X710.kicad_sch")
		(attr smd)
		(fp_line
			(start -0.15 -0.4)
			(end 0.15 -0.4)
			(stroke
				(width 0.15)
				(type solid)
			)
			(layer "F.SilkS")
		)
		(fp_line
			(start -0.15 0.4)
			(end 0.15 0.4)
			(stroke
				(width 0.15)
				(type solid)
			)
			(layer "F.SilkS")
		)
		(fp_rect
			(start -1.25 -0.65)
			(end 1.25 0.65)
			(stroke
				(width 0.05)
				(type solid)
			)
			(fill no)
			(layer "F.CrtYd")
		)
		(fp_rect
			(start -0.8 -0.4)
			(end 0.8 0.4)
			(stroke
				(width 0.15)
				(type solid)
			)
			(fill no)
			(layer "F.Fab")
		)
		(fp_text user "Author: Antmicro"
			(at -1.25 4.9 90)
			(layer "F.Fab")
			(effects
				(font
					(size 0.7 0.7)
					(thickness 0.15)
				)
				(justify left bottom)
			)
		)
		(fp_text user "${REFERENCE}"
			(at -1.25 3.898 90)
			(layer "F.Fab")
			(effects
				(font
					(size 0.7 0.7)
					(thickness 0.15)
				)
				(justify left bottom)
			)
		)
		(fp_text user "License: Apache-2.0"
			(at -1.25 5.9 90)
			(layer "F.Fab")
			(effects
				(font
					(size 0.7 0.7)
					(thickness 0.15)
				)
				(justify left bottom)
			)
		)
		(pad "1" smd roundrect
			(at -0.7 0 90)
			(size 0.8 1)
			(layers "F.Cu" "F.Mask" "F.Paste")
			(roundrect_rratio 0.2)
			(net 335 "/X710 DCDC converters/+VCCD_OUT")
			(pintype "passive")
		)
		(pad "2" smd roundrect
			(at 0.7 0 90)
			(size 0.8 1)
			(layers "F.Cu" "F.Mask" "F.Paste")
			(roundrect_rratio 0.2)
			(net 9 "VCCD")
			(pintype "passive")
		)
	)
	(footprint "antmicro-footprints:R_0402_1005Metric"
		(layer "F.Cu")
		(at 157.155 65.174999 -90)
		(descr "Resistor SMD 0402")
		(tags "resistor SMD 0402")
		(property "Reference" "R147"
			(at -2.374999 -0.095001 270)
			(layer "F.SilkS")
			(effects
				(font
					(size 0.7 0.7)
					(thickness 0.15)
				)
			)
		)
		(property "Value" "R_100k_0402"
			(at -1.011843 1.772047 270)
			(layer "F.Fab")
			(effects
				(font
					(size 0.7 0.7)
					(thickness 0.15)
				)
				(justify left bottom)
			)
		)
		(property "Datasheet" "https://www.bourns.com/docs/product-datasheets/cr.pdf"
			(at 0 0 270)
			(layer "F.Fab")
			(hide yes)
			(effects
				(font
					(size 1.27 1.27)
					(thickness 0.15)
				)
			)
		)
		(property "Description" "SMD Chip Resistor, 100 kohm, ± 1%, 62.5 mW, 0402 [1005 Metric], Thick Film, General Purpose"
			(at 0 0 270)
			(layer "F.Fab")
			(hide yes)
			(effects
				(font
					(size 1.27 1.27)
					(thickness 0.15)
				)
			)
		)
		(property "MPN" "CR0402-FX-1003GLF"
			(at 0 0 270)
			(unlocked yes)
			(layer "F.Fab")
			(hide yes)
			(effects
				(font
					(size 1 1)
					(thickness 0.15)
				)
			)
		)
		(property "Manufacturer" "Bourns"
			(at 0 0 270)
			(unlocked yes)
			(layer "F.Fab")
			(hide yes)
			(effects
				(font
					(size 1 1)
					(thickness 0.15)
				)
			)
		)
		(property "License" "Apache-2.0"
			(at 0 0 270)
			(unlocked yes)
			(layer "F.Fab")
			(hide yes)
			(effects
				(font
					(size 1 1)
					(thickness 0.15)
				)
			)
		)
		(property "Author" "Antmicro"
			(at 0 0 270)
			(unlocked yes)
			(layer "F.Fab")
			(hide yes)
			(effects
				(font
					(size 1 1)
					(thickness 0.15)
				)
			)
		)
		(property "Val" "100k"
			(at 0 0 270)
			(unlocked yes)
			(layer "F.Fab")
			(hide yes)
			(effects
				(font
					(size 1 1)
					(thickness 0.15)
				)
			)
		)
		(property "Tolerance" "1%"
			(at 0 0 270)
			(unlocked yes)
			(layer "F.Fab")
			(hide yes)
			(effects
				(font
					(size 1 1)
					(thickness 0.15)
				)
			)
		)
		(sheetname "/X710-AT2 Misc/")
		(sheetfile "x710-at2-mics.kicad_sch")
		(attr smd)
		(fp_rect
			(start -0.925 -0.47)
			(end 0.925 0.47)
			(stroke
				(width 0.05)
				(type default)
			)
			(fill no)
			(layer "F.CrtYd")
		)
		(fp_rect
			(start -0.5 -0.25)
			(end 0.5 0.25)
			(stroke
				(width 0.15)
				(type solid)
			)
			(fill no)
			(layer "F.Fab")
		)
		(fp_text user "License: Apache-2.0"
			(at -0.95 5.169 270)
			(layer "F.Fab")
			(effects
				(font
					(size 0.7 0.7)
					(thickness 0.15)
				)
				(justify left bottom)
			)
		)
		(fp_text user "${REFERENCE}"
			(at -0.95 3.168 270)
			(layer "F.Fab")
			(effects
				(font
					(size 0.7 0.7)
					(thickness 0.15)
				)
				(justify left bottom)
			)
		)
		(fp_text user "Author: Antmicro"
			(at -0.95 4.169 270)
			(layer "F.Fab")
			(effects
				(font
					(size 0.7 0.7)
					(thickness 0.15)
				)
				(justify left bottom)
			)
		)
		(pad "1" smd roundrect
			(at -0.48 0 270)
			(size 0.59 0.64)
			(layers "F.Cu" "F.Mask" "F.Paste")
			(roundrect_rratio 0.25)
			(net 138 "/X710-AT2 Misc/NCSI.TXD_1")
			(pintype "passive")
		)
		(pad "2" smd roundrect
			(at 0.48 0 270)
			(size 0.59 0.64)
			(layers "F.Cu" "F.Mask" "F.Paste")
			(roundrect_rratio 0.25)
			(net 7 "+3V3")
			(pintype "passive")
		)
	)
	(footprint "antmicro-footprints:R_0402_1005Metric"
		(layer "F.Cu")
		(at 170.6 72.1 -90)
		(descr "Resistor SMD 0402")
		(tags "resistor SMD 0402")
		(property "Reference" "R201"
			(at -0.9 -0.4 270)
			(layer "F.SilkS")
			(effects
				(font
					(size 0.7 0.7)
					(thickness 0.15)
				)
				(justify left bottom)
			)
		)
		(property "Value" "R_3k3_0402"
			(at -1.011843 1.772047 270)
			(layer "F.Fab")
			(effects
				(font
					(size 0.7 0.7)
					(thickness 0.15)
				)
				(justify left bottom)
			)
		)
		(property "Datasheet" "https://www.bourns.com/docs/product-datasheets/cr.pdf"
			(at 0 0 270)
			(layer "F.Fab")
			(hide yes)
			(effects
				(font
					(size 1.27 1.27)
					(thickness 0.15)
				)
			)
		)
		(property "Description" "SMD Chip Resistor, 3.3 kohm, ± 1%, 63 mW, 0402 [1005 Metric], Thick Film, General Purpose"
			(at 0 0 270)
			(layer "F.Fab")
			(hide yes)
			(effects
				(font
					(size 1.27 1.27)
					(thickness 0.15)
				)
			)
		)
		(property "MPN" "CR0402-FX-3301GLF"
			(at 0 0 270)
			(unlocked yes)
			(layer "F.Fab")
			(hide yes)
			(effects
				(font
					(size 1 1)
					(thickness 0.15)
				)
			)
		)
		(property "Manufacturer" "Bourns"
			(at 0 0 270)
			(unlocked yes)
			(layer "F.Fab")
			(hide yes)
			(effects
				(font
					(size 1 1)
					(thickness 0.15)
				)
			)
		)
		(property "License" "Apache-2.0"
			(at 0 0 270)
			(unlocked yes)
			(layer "F.Fab")
			(hide yes)
			(effects
				(font
					(size 1 1)
					(thickness 0.15)
				)
			)
		)
		(property "Author" "Antmicro"
			(at 0 0 270)
			(unlocked yes)
			(layer "F.Fab")
			(hide yes)
			(effects
				(font
					(size 1 1)
					(thickness 0.15)
				)
			)
		)
		(property "Val" "3k3"
			(at 0 0 270)
			(unlocked yes)
			(layer "F.Fab")
			(hide yes)
			(effects
				(font
					(size 1 1)
					(thickness 0.15)
				)
			)
		)
		(property "Tolerance" "1%"
			(at 0 0 270)
			(unlocked yes)
			(layer "F.Fab")
			(hide yes)
			(effects
				(font
					(size 1 1)
					(thickness 0.15)
				)
			)
		)
		(sheetname "/X710-AT2 10GbE/")
		(sheetfile "x710-at2-10gbe.kicad_sch")
		(attr smd)
		(fp_rect
			(start -0.925 -0.47)
			(end 0.925 0.47)
			(stroke
				(width 0.05)
				(type default)
			)
			(fill no)
			(layer "F.CrtYd")
		)
		(fp_rect
			(start -0.5 -0.25)
			(end 0.5 0.25)
			(stroke
				(width 0.15)
				(type solid)
			)
			(fill no)
			(layer "F.Fab")
		)
		(fp_text user "License: Apache-2.0"
			(at -0.95 5.169 270)
			(layer "F.Fab")
			(effects
				(font
					(size 0.7 0.7)
					(thickness 0.15)
				)
				(justify left bottom)
			)
		)
		(fp_text user "${REFERENCE}"
			(at -0.95 3.168 270)
			(layer "F.Fab")
			(effects
				(font
					(size 0.7 0.7)
					(thickness 0.15)
				)
				(justify left bottom)
			)
		)
		(fp_text user "Author: Antmicro"
			(at -0.95 4.169 270)
			(layer "F.Fab")
			(effects
				(font
					(size 0.7 0.7)
					(thickness 0.15)
				)
				(justify left bottom)
			)
		)
		(pad "1" smd roundrect
			(at -0.48 0 270)
			(size 0.59 0.64)
			(layers "F.Cu" "F.Mask" "F.Paste")
			(roundrect_rratio 0.25)
			(net 102 "/X710-AT2 10GbE/MDIO0_SDA0")
			(pintype "passive")
		)
		(pad "2" smd roundrect
			(at 0.48 0 270)
			(size 0.59 0.64)
			(layers "F.Cu" "F.Mask" "F.Paste")
			(roundrect_rratio 0.25)
			(net 7 "+3V3")
			(pintype "passive")
		)
	)
	(footprint "antmicro-footprints:C_0402_1005Metric"
		(layer "F.Cu")
		(at 124 70 180)
		(descr "Capacitor SMD 0402")
		(tags "capacitor SMD 0402")
		(property "Reference" "C74"
			(at -1 0.2 180)
			(layer "F.SilkS")
			(effects
				(font
					(size 0.7 0.7)
					(thickness 0.15)
				)
				(justify left bottom)
			)
		)
		(property "Value" "C_100n_0402"
			(at -1.022927 2.155213 180)
			(layer "F.Fab")
			(effects
				(font
					(size 0.7 0.7)
					(thickness 0.15)
				)
				(justify left bottom)
			)
		)
		(property "Datasheet" "https://www.murata.com/products/productdetail?partno=GRM155R61H104KE14%23"
			(at 0 0 180)
			(layer "F.Fab")
			(hide yes)
			(effects
				(font
					(size 1.27 1.27)
					(thickness 0.15)
				)
			)
		)
		(property "Description" "SMD Multilayer Ceramic Capacitor, 0.1 µF, 50 V, 0402 [1005 Metric], ± 10%, X5R, GRM Series"
			(at 0 0 180)
			(layer "F.Fab")
			(hide yes)
			(effects
				(font
					(size 1.27 1.27)
					(thickness 0.15)
				)
			)
		)
		(property "MPN" "GRM155R61H104KE14D"
			(at 0 0 180)
			(unlocked yes)
			(layer "F.Fab")
			(hide yes)
			(effects
				(font
					(size 1 1)
					(thickness 0.15)
				)
			)
		)
		(property "Manufacturer" "Murata"
			(at 0 0 180)
			(unlocked yes)
			(layer "F.Fab")
			(hide yes)
			(effects
				(font
					(size 1 1)
					(thickness 0.15)
				)
			)
		)
		(property "License" "Apache-2.0"
			(at 0 0 180)
			(unlocked yes)
			(layer "F.Fab")
			(hide yes)
			(effects
				(font
					(size 1 1)
					(thickness 0.15)
				)
			)
		)
		(property "Author" "Antmicro"
			(at 0 0 180)
			(unlocked yes)
			(layer "F.Fab")
			(hide yes)
			(effects
				(font
					(size 1 1)
					(thickness 0.15)
				)
			)
		)
		(property "Val" "100n"
			(at 0 0 180)
			(unlocked yes)
			(layer "F.Fab")
			(hide yes)
			(effects
				(font
					(size 1 1)
					(thickness 0.15)
				)
			)
		)
		(property "Voltage" "50V"
			(at 0 0 180)
			(unlocked yes)
			(layer "F.Fab")
			(hide yes)
			(effects
				(font
					(size 1 1)
					(thickness 0.15)
				)
			)
		)
		(property "Dielectric" "X5R"
			(at 0 0 180)
			(unlocked yes)
			(layer "F.Fab")
			(hide yes)
			(effects
				(font
					(size 1 1)
					(thickness 0.15)
				)
			)
		)
		(sheetname "/Fan controller/")
		(sheetfile "fan-controller.kicad_sch")
		(attr smd)
		(fp_rect
			(start -0.925 -0.47)
			(end 0.925 0.47)
			(stroke
				(width 0.05)
				(type default)
			)
			(fill no)
			(layer "F.CrtYd")
		)
		(fp_line
			(start 0.504 0.248)
			(end -0.494 0.248)
			(stroke
				(width 0.15)
				(type solid)
			)
			(layer "F.Fab")
		)
		(fp_line
			(start 0.504 -0.25)
			(end 0.504 0.248)
			(stroke
				(width 0.15)
				(type solid)
			)
			(layer "F.Fab")
		)
		(fp_line
			(start -0.494 0.248)
			(end -0.494 -0.25)
			(stroke
				(width 0.15)
				(type solid)
			)
			(layer "F.Fab")
		)
		(fp_line
			(start -0.494 -0.25)
			(end 0.504 -0.25)
			(stroke
				(width 0.15)
				(type solid)
			)
			(layer "F.Fab")
		)
		(fp_text user "License: Apache-2.0"
			(at -0.939 5.799 180)
			(layer "F.Fab")
			(effects
				(font
					(size 0.7 0.7)
					(thickness 0.15)
				)
				(justify left bottom)
			)
		)
		(fp_text user "Author: Antmicro"
			(at -0.939 3.399 180)
			(layer "F.Fab")
			(effects
				(font
					(size 0.7 0.7)
					(thickness 0.15)
				)
				(justify left bottom)
			)
		)
		(fp_text user "${REFERENCE}"
			(at -0.939 4.599 180)
			(layer "F.Fab")
			(effects
				(font
					(size 0.7 0.7)
					(thickness 0.15)
				)
				(justify left bottom)
			)
		)
		(pad "1" smd roundrect
			(at -0.48 0 180)
			(size 0.59 0.64)
			(layers "F.Cu" "F.Mask" "F.Paste")
			(roundrect_rratio 0.25)
			(net 23 "GND")
			(pintype "passive")
		)
		(pad "2" smd roundrect
			(at 0.48 0 180)
			(size 0.59 0.64)
			(layers "F.Cu" "F.Mask" "F.Paste")
			(roundrect_rratio 0.25)
			(net 40 "+5V")
			(pintype "passive")
		)
	)
	(footprint "antmicro-footprints:C_0603_1608Metric_EIA"
		(layer "F.Cu")
		(at 136.450001 103.050001 -90)
		(descr "Capacitor SMD 0603, IPC-7351 Density Level A")
		(tags "Capacitor 0603")
		(property "Reference" "C140"
			(at 17.649996 -16.849997 270)
			(layer "F.SilkS")
			(effects
				(font
					(size 0.7 0.7)
					(thickness 0.15)
				)
			)
		)
		(property "Value" "C_22u_16V_0603"
			(at -1.42757 1.770288 270)
			(layer "F.Fab")
			(effects
				(font
					(size 0.7 0.7)
					(thickness 0.15)
				)
				(justify left bottom)
			)
		)
		(property "Datasheet" "https://product.samsungsem.com/mlcc/CL10A226MO7JZN.do"
			(at 0 0 270)
			(layer "F.Fab")
			(hide yes)
			(effects
				(font
					(size 1.27 1.27)
					(thickness 0.15)
				)
			)
		)
		(property "Description" "SMD Multilayer Ceramic Capacitor"
			(at 0 0 270)
			(layer "F.Fab")
			(hide yes)
			(effects
				(font
					(size 1.27 1.27)
					(thickness 0.15)
				)
			)
		)
		(property "MPN" "CL10A226MO7JZNC"
			(at 0 0 270)
			(unlocked yes)
			(layer "F.Fab")
			(hide yes)
			(effects
				(font
					(size 1 1)
					(thickness 0.15)
				)
			)
		)
		(property "Manufacturer" "Samsung Electro-Mechanics"
			(at 0 0 270)
			(unlocked yes)
			(layer "F.Fab")
			(hide yes)
			(effects
				(font
					(size 1 1)
					(thickness 0.15)
				)
			)
		)
		(property "License" "Apache-2.0"
			(at 0 0 270)
			(unlocked yes)
			(layer "F.Fab")
			(hide yes)
			(effects
				(font
					(size 1 1)
					(thickness 0.15)
				)
			)
		)
		(property "Author" "Antmicro"
			(at 0 0 270)
			(unlocked yes)
			(layer "F.Fab")
			(hide yes)
			(effects
				(font
					(size 1 1)
					(thickness 0.15)
				)
			)
		)
		(property "Val" "22u"
			(at 0 0 270)
			(unlocked yes)
			(layer "F.Fab")
			(hide yes)
			(effects
				(font
					(size 1 1)
					(thickness 0.15)
				)
			)
		)
		(property "Voltage" "16V"
			(at 0 0 270)
			(unlocked yes)
			(layer "F.Fab")
			(hide yes)
			(effects
				(font
					(size 1 1)
					(thickness 0.15)
				)
			)
		)
		(property "Dielectric" ""
			(at 0 0 270)
			(unlocked yes)
			(layer "F.Fab")
			(hide yes)
			(effects
				(font
					(size 1 1)
					(thickness 0.15)
				)
			)
		)
		(sheetname "/X710 DCDC converters/")
		(sheetfile "DCDC_converters_X710.kicad_sch")
		(attr smd)
		(fp_line
			(start -0.15 0.55)
			(end 0.15 0.55)
			(stroke
				(width 0.15)
				(type solid)
			)
			(layer "F.SilkS")
		)
		(fp_line
			(start -0.15 -0.55)
			(end 0.15 -0.55)
			(stroke
				(width 0.15)
				(type solid)
			)
			(layer "F.SilkS")
		)
		(fp_rect
			(start -1.25 -0.65)
			(end 1.25 0.65)
			(stroke
				(width 0.05)
				(type solid)
			)
			(fill no)
			(layer "F.CrtYd")
		)
		(fp_rect
			(start -0.8 -0.45)
			(end 0.8 0.45)
			(stroke
				(width 0.15)
				(type solid)
			)
			(fill no)
			(layer "F.Fab")
		)
		(fp_text user "Author: Antmicro"
			(at -1.682 4.894 270)
			(layer "F.Fab")
			(effects
				(font
					(size 0.7 0.7)
					(thickness 0.15)
				)
				(justify left bottom)
			)
		)
		(fp_text user "License: Apache-2.0"
			(at -1.682 5.895 270)
			(layer "F.Fab")
			(effects
				(font
					(size 0.7 0.7)
					(thickness 0.15)
				)
				(justify left bottom)
			)
		)
		(fp_text user "${REFERENCE}"
			(at -1.682 3.895 270)
			(layer "F.Fab")
			(effects
				(font
					(size 0.7 0.7)
					(thickness 0.15)
				)
				(justify left bottom)
			)
		)
		(pad "1" smd roundrect
			(at -0.7 0 270)
			(size 0.8 1.1)
			(layers "F.Cu" "F.Mask" "F.Paste")
			(roundrect_rratio 0.2)
			(net 23 "GND")
			(pintype "passive")
		)
		(pad "2" smd roundrect
			(at 0.7 0 270)
			(size 0.8 1.1)
			(layers "F.Cu" "F.Mask" "F.Paste")
			(roundrect_rratio 0.2)
			(net 335 "/X710 DCDC converters/+VCCD_OUT")
			(pintype "passive")
		)
	)
	(footprint "antmicro-footprints:LED_0603_1608Metric_G"
		(layer "F.Cu")
		(at 183.2 70)
		(descr "LED SMD 0603 Green")
		(tags "LED SMD 0603 Green")
		(property "Reference" "D6"
			(at -1.2 7.75 0)
			(layer "F.SilkS")
			(effects
				(font
					(size 0.7 0.7)
					(thickness 0.15)
				)
				(justify left bottom)
			)
		)
		(property "Value" "LED_G_0603_LG_L29K-G2J1-24-Z"
			(at -0.001 1.599 0)
			(layer "F.Fab")
			(effects
				(font
					(size 0.7 0.7)
					(thickness 0.15)
				)
				(justify left bottom)
			)
		)
		(property "Datasheet" "https://look.ams-osram.com/m/19ee86b3ae0ee95b/original/LG-L29K.pdf"
			(at 0 0 0)
			(layer "F.Fab")
			(hide yes)
			(effects
				(font
					(size 1.27 1.27)
					(thickness 0.15)
				)
			)
		)
		(property "Description" "LED, Green, SMD, 0603, 20 mA, 1.7 V, 570 nm"
			(at 0 0 0)
			(layer "F.Fab")
			(hide yes)
			(effects
				(font
					(size 1.27 1.27)
					(thickness 0.15)
				)
			)
		)
		(property "MPN" "LG L29K-G2J1-24-Z"
			(at 0 0 0)
			(unlocked yes)
			(layer "F.Fab")
			(hide yes)
			(effects
				(font
					(size 1 1)
					(thickness 0.15)
				)
			)
		)
		(property "Manufacturer" "OSRAM"
			(at 0 0 0)
			(unlocked yes)
			(layer "F.Fab")
			(hide yes)
			(effects
				(font
					(size 1 1)
					(thickness 0.15)
				)
			)
		)
		(property "Color" "Green"
			(at 0 0 0)
			(unlocked yes)
			(layer "F.Fab")
			(hide yes)
			(effects
				(font
					(size 1 1)
					(thickness 0.15)
				)
			)
		)
		(property "Author" "Antmicro"
			(at 0 0 0)
			(unlocked yes)
			(layer "F.Fab")
			(hide yes)
			(effects
				(font
					(size 1 1)
					(thickness 0.15)
				)
			)
		)
		(property "License" "Apache-2.0"
			(at 0 0 0)
			(unlocked yes)
			(layer "F.Fab")
			(hide yes)
			(effects
				(font
					(size 1 1)
					(thickness 0.15)
				)
			)
		)
		(sheetname "/X710 DCDC converters/")
		(sheetfile "DCDC_converters_X710.kicad_sch")
		(attr smd)
		(fp_line
			(start -1.18 -0.319)
			(end -1.18 0.321)
			(stroke
				(width 0.15)
				(type solid)
			)
			(layer "F.SilkS")
		)
		(fp_line
			(start -0.094672 0.001008)
			(end -0.24 0.001008)
			(stroke
				(width 0.1)
				(type solid)
			)
			(layer "F.SilkS")
		)
		(fp_line
			(start -0.094672 0.001008)
			(end 0.105328 -0.198992)
			(stroke
				(width 0.1)
				(type solid)
			)
			(layer "F.SilkS")
		)
		(fp_line
			(start -0.094672 0.201008)
			(end -0.094672 -0.198992)
			(stroke
				(width 0.1)
				(type solid)
			)
			(layer "F.SilkS")
		)
		(fp_line
			(start 0.105328 0.001008)
			(end 0.24 0.001)
			(stroke
				(width 0.1)
				(type solid)
			)
			(layer "F.SilkS")
		)
		(fp_line
			(start 0.105328 0.201008)
			(end -0.094672 0.001008)
			(stroke
				(width 0.1)
				(type solid)
			)
			(layer "F.SilkS")
		)
		(fp_line
			(start 0.105328 0.201008)
			(end 0.105328 -0.198992)
			(stroke
				(width 0.1)
				(type solid)
			)
			(layer "F.SilkS")
		)
		(fp_line
			(start 0.22 -0.35)
			(end -0.22 -0.35)
			(stroke
				(width 0.15)
				(type solid)
			)
			(layer "F.SilkS")
		)
		(fp_line
			(start 0.22 0.35)
			(end -0.22 0.35)
			(stroke
				(width 0.15)
				(type solid)
			)
			(layer "F.SilkS")
		)
		(fp_rect
			(start 1.25 0.65)
			(end -1.25 -0.65)
			(stroke
				(width 0.05)
				(type solid)
			)
			(fill no)
			(layer "F.CrtYd")
		)
		(fp_line
			(start -0.199 -0.202)
			(end -0.199 0.1)
			(stroke
				(width 0.15)
				(type solid)
			)
			(layer "F.Fab")
		)
		(fp_line
			(start -0.199 0)
			(end -0.597 0)
			(stroke
				(width 0.15)
				(type solid)
			)
			(layer "F.Fab")
		)
		(fp_line
			(start -0.199 0.2)
			(end -0.199 0.1)
			(stroke
				(width 0.15)
				(type solid)
			)
			(layer "F.Fab")
		)
		(fp_line
			(start -0.101 0)
			(end 0.201 0.2)
			(stroke
				(width 0.15)
				(type solid)
			)
			(layer "F.Fab")
		)
		(fp_line
			(start 0.201 -0.202)
			(end -0.101 0)
			(stroke
				(width 0.15)
				(type solid)
			)
			(layer "F.Fab")
		)
		(fp_line
			(start 0.201 0)
			(end 0.201 -0.202)
			(stroke
				(width 0.15)
				(type solid)
			)
			(layer "F.Fab")
		)
		(fp_line
			(start 0.201 0.2)
			(end 0.201 0)
			(stroke
				(width 0.15)
				(type solid)
			)
			(layer "F.Fab")
		)
		(fp_line
			(start 0.599 0)
			(end 0.201 0)
			(stroke
				(width 0.15)
				(type solid)
			)
			(layer "F.Fab")
		)
		(fp_rect
			(start 0.848 0.4)
			(end -0.85 -0.402)
			(stroke
				(width 0.15)
				(type solid)
			)
			(fill no)
			(layer "F.Fab")
		)
		(fp_text user "${REFERENCE}"
			(at -1.4224 5.999 0)
			(layer "F.Fab")
			(effects
				(font
					(size 0.7 0.7)
					(thickness 0.15)
				)
				(justify left bottom)
			)
		)
		(fp_text user "Author: Antmicro"
			(at -1.4224 4.799 0)
			(layer "F.Fab")
			(effects
				(font
					(size 0.7 0.7)
					(thickness 0.15)
				)
				(justify left bottom)
			)
		)
		(fp_text user "License: Apache-2.0"
			(at -1.4224 3.599 0)
			(layer "F.Fab")
			(effects
				(font
					(size 0.7 0.7)
					(thickness 0.15)
				)
				(justify left bottom)
			)
		)
		(pad "1" smd roundrect
			(at -0.7 0 180)
			(size 0.8 1)
			(layers "F.Cu" "F.Mask" "F.Paste")
			(roundrect_rratio 0.2)
			(net 414 "Net-(D6-C)")
			(pinfunction "C")
			(pintype "passive")
		)
		(pad "2" smd roundrect
			(at 0.7 0 180)
			(size 0.8 1)
			(layers "F.Cu" "F.Mask" "F.Paste")
			(roundrect_rratio 0.2)
			(net 334 "/X710 DCDC converters/+3V3_OUT")
			(pinfunction "A")
			(pintype "passive")
		)
	)
	(footprint "antmicro-footprints:Fiducial_1mm_Mask2mm"
		(layer "F.Cu")
		(at 179 129)
		(descr "Circular Fiducial, 1mm bare copper, 3mm soldermask opening")
		(tags "fiducial")
		(property "Reference" "FD7"
			(at 1.5 0.5 0)
			(layer "F.SilkS")
			(effects
				(font
					(size 0.7 0.7)
					(thickness 0.15)
				)
				(justify left bottom)
			)
		)
		(property "Value" "Fiducial_1mm_Mask2mm"
			(at 0 2.2 0)
			(layer "F.Fab")
			(effects
				(font
					(size 0.7 0.7)
					(thickness 0.15)
				)
				(justify left bottom)
			)
		)
		(property "Description" "Fiducial mask"
			(at 0 0 0)
			(layer "F.Fab")
			(hide yes)
			(effects
				(font
					(size 1.27 1.27)
					(thickness 0.15)
				)
			)
		)
		(property "Author" "Antmicro"
			(at 0 0 0)
			(unlocked yes)
			(layer "F.Fab")
			(hide yes)
			(effects
				(font
					(size 1 1)
					(thickness 0.15)
				)
			)
		)
		(property "License" "Apache-2.0"
			(at 0 0 0)
			(unlocked yes)
			(layer "F.Fab")
			(hide yes)
			(effects
				(font
					(size 1 1)
					(thickness 0.15)
				)
			)
		)
		(sheetname "/")
		(sheetfile "thunderbolt-to-10gbe-adapter.kicad_sch")
		(attr exclude_from_pos_files exclude_from_bom)
		(fp_circle
			(center 0 0)
			(end 1.24 0)
			(stroke
				(width 0.05)
				(type solid)
			)
			(fill no)
			(layer "F.CrtYd")
		)
		(fp_circle
			(center 0 0)
			(end 0.999 0)
			(stroke
				(width 0.15)
				(type solid)
			)
			(fill no)
			(layer "F.Fab")
		)
		(fp_text user "${REFERENCE}"
			(at -1.25 4.603 0)
			(layer "F.Fab")
			(effects
				(font
					(size 0.7 0.7)
					(thickness 0.15)
				)
				(justify left bottom)
			)
		)
		(fp_text user "Author: Antmicro"
			(at -1.25 5.803 0)
			(layer "F.Fab")
			(effects
				(font
					(size 0.7 0.7)
					(thickness 0.15)
				)
				(justify left bottom)
			)
		)
		(fp_text user "License: Apache-2.0"
			(at -1.25 7.003 0)
			(layer "F.Fab")
			(effects
				(font
					(size 0.7 0.7)
					(thickness 0.15)
				)
				(justify left bottom)
			)
		)
		(pad "" smd circle
			(at 0 0)
			(size 1 1)
			(layers "F.Cu" "F.Mask")
			(solder_mask_margin 0.5)
			(clearance 0.5)
		)
	)
	(footprint "antmicro-footprints:QFN-11_2x2mm_P0.5mm"
		(layer "F.Cu")
		(at 119.15 104.1 90)
		(property "Reference" "U2"
			(at 2 -1.05 0)
			(unlocked yes)
			(layer "F.SilkS")
			(effects
				(font
					(size 0.7 0.7)
					(thickness 0.15)
				)
			)
		)
		(property "Value" "MP2386GG"
			(at -1.637158 2.644508 90)
			(unlocked yes)
			(layer "F.Fab")
			(effects
				(font
					(size 0.7 0.7)
					(thickness 0.15)
				)
				(justify left bottom)
			)
		)
		(property "Datasheet" "https://www.monolithicpower.com/en/documentview/productdocument/index/version/2/document_type/Datasheet/lang/en/sku/MP2386GG-Z/document_id/4066/"
			(at 0 0 90)
			(layer "F.Fab")
			(hide yes)
			(effects
				(font
					(size 1.27 1.27)
					(thickness 0.15)
				)
			)
		)
		(property "Description" "DC/DC converter"
			(at 0 0 90)
			(layer "F.Fab")
			(hide yes)
			(effects
				(font
					(size 1.27 1.27)
					(thickness 0.15)
				)
			)
		)
		(property "Manufacturer" "Monolithic Power Systems"
			(at 0 0 90)
			(unlocked yes)
			(layer "F.Fab")
			(hide yes)
			(effects
				(font
					(size 1 1)
					(thickness 0.15)
				)
			)
		)
		(property "MPN" "MP2386GG-P"
			(at 0 0 90)
			(unlocked yes)
			(layer "F.Fab")
			(hide yes)
			(effects
				(font
					(size 1 1)
					(thickness 0.15)
				)
			)
		)
		(property "License" "Apache-2.0"
			(at 0 0 90)
			(unlocked yes)
			(layer "F.Fab")
			(hide yes)
			(effects
				(font
					(size 1 1)
					(thickness 0.15)
				)
			)
		)
		(property "Author" "Antmicro"
			(at 0 0 90)
			(unlocked yes)
			(layer "F.Fab")
			(hide yes)
			(effects
				(font
					(size 1 1)
					(thickness 0.15)
				)
			)
		)
		(sheetname "/PD and TB DC-DC/")
		(sheetfile "PD_and_TB_DC_DC.kicad_sch")
		(attr smd)
		(fp_line
			(start 1.249 -1.25)
			(end 1.249 -0.951)
			(stroke
				(width 0.15)
				(type solid)
			)
			(layer "F.SilkS")
		)
		(fp_line
			(start 0.949 -1.25)
			(end 1.249 -1.25)
			(stroke
				(width 0.15)
				(type solid)
			)
			(layer "F.SilkS")
		)
		(fp_line
			(start -1.25 -0.951)
			(end -1.25 -1.25)
			(stroke
				(width 0.15)
				(type solid)
			)
			(layer "F.SilkS")
		)
		(fp_line
			(start 1.249 0.949)
			(end 1.249 1.249)
			(stroke
				(width 0.15)
				(type solid)
			)
			(layer "F.SilkS")
		)
		(fp_line
			(start 1.249 1.249)
			(end 0.949 1.249)
			(stroke
				(width 0.15)
				(type solid)
			)
			(layer "F.SilkS")
		)
		(fp_line
			(start -0.951 1.249)
			(end -1.25 1.249)
			(stroke
				(width 0.15)
				(type solid)
			)
			(layer "F.SilkS")
		)
		(fp_line
			(start -1.25 1.249)
			(end -1.25 0.949)
			(stroke
				(width 0.15)
				(type solid)
			)
			(layer "F.SilkS")
		)
		(fp_circle
			(center -1.7 -1.1)
			(end -1.649 -1.1)
			(stroke
				(width 0.15)
				(type solid)
			)
			(fill yes)
			(layer "F.SilkS")
		)
		(fp_rect
			(start -1.5 -1.5)
			(end 1.498 1.498)
			(stroke
				(width 0.05)
				(type solid)
			)
			(fill no)
			(layer "F.CrtYd")
		)
		(fp_line
			(start 1.1 -1.101)
			(end 1.1 1.1)
			(stroke
				(width 0.15)
				(type solid)
			)
			(layer "F.Fab")
		)
		(fp_line
			(start -0.552 -1.101)
			(end 1.1 -1.101)
			(stroke
				(width 0.15)
				(type solid)
			)
			(layer "F.Fab")
		)
		(fp_line
			(start -0.552 -1.101)
			(end -1.101 -0.552)
			(stroke
				(width 0.15)
				(type solid)
			)
			(layer "F.Fab")
		)
		(fp_line
			(start 1.1 1.1)
			(end -1.101 1.1)
			(stroke
				(width 0.15)
				(type solid)
			)
			(layer "F.Fab")
		)
		(fp_line
			(start -1.101 1.1)
			(end -1.101 -0.552)
			(stroke
				(width 0.15)
				(type solid)
			)
			(layer "F.Fab")
		)
		(fp_text user "License: Apache-2.0"
			(at -1.401 5.85 90)
			(layer "F.Fab")
			(effects
				(font
					(size 0.7 0.7)
					(thickness 0.15)
				)
				(justify left bottom)
			)
		)
		(fp_text user "${REFERENCE}"
			(at -1.401 3.45 90)
			(layer "F.Fab")
			(effects
				(font
					(size 0.7 0.7)
					(thickness 0.15)
				)
				(justify left bottom)
			)
		)
		(fp_text user "Author: Antmicro"
			(at -1.401 4.65 90)
			(layer "F.Fab")
			(effects
				(font
					(size 0.7 0.7)
					(thickness 0.15)
				)
				(justify left bottom)
			)
		)
		(pad "1" smd roundrect
			(at -0.552 -0.25 270)
			(size 1.5 0.25)
			(layers "F.Cu" "F.Mask" "F.Paste")
			(roundrect_rratio 0.25)
			(net 161 "Net-(U2-VIN)")
			(pinfunction "VIN")
			(pintype "power_in")
		)
		(pad "2" smd roundrect
			(at -0.75 0.998 180)
			(size 0.7 0.25)
			(layers "F.Cu" "F.Mask" "F.Paste")
			(roundrect_rratio 0.25)
			(net 23 "GND")
			(pinfunction "PGND")
			(pintype "power_in")
		)
		(pad "3" smd roundrect
			(at -0.25 0.998 180)
			(size 0.7 0.25)
			(layers "F.Cu" "F.Mask" "F.Paste")
			(roundrect_rratio 0.25)
			(net 23 "GND")
			(pinfunction "PGND")
			(pintype "passive")
		)
		(pad "4" smd roundrect
			(at 0.248 0.998 180)
			(size 0.7 0.25)
			(layers "F.Cu" "F.Mask" "F.Paste")
			(roundrect_rratio 0.25)
			(net 23 "GND")
			(pinfunction "PGND")
			(pintype "passive")
		)
		(pad "5" smd roundrect
			(at 0.748 0.998 180)
			(size 0.7 0.25)
			(layers "F.Cu" "F.Mask" "F.Paste")
			(roundrect_rratio 0.25)
			(net 17 "Net-(U2-PG)")
			(pinfunction "PG")
			(pintype "open_collector")
		)
		(pad "6" smd roundrect
			(at 0.55 0.2 270)
			(size 1.5 0.25)
			(layers "F.Cu" "F.Mask" "F.Paste")
			(roundrect_rratio 0.25)
			(net 163 "Net-(U2-SW)")
			(pinfunction "SW")
			(pintype "power_out")
		)
		(pad "7" smd roundrect
			(at 0.949 -0.25 270)
			(size 0.7 0.25)
			(layers "F.Cu" "F.Mask" "F.Paste")
			(roundrect_rratio 0.25)
			(net 162 "Net-(U2-BST)")
			(pinfunction "BST")
			(pintype "input")
		)
		(pad "8" smd roundrect
			(at 0.748 -1 180)
			(size 0.7 0.25)
			(layers "F.Cu" "F.Mask" "F.Paste")
			(roundrect_rratio 0.25)
			(net 303 "/PD and TB DC-DC/SMPS_LDO")
			(pinfunction "VCC")
			(pintype "power_out")
		)
		(pad "9" smd roundrect
			(at 0.248 -1 180)
			(size 0.7 0.25)
			(layers "F.Cu" "F.Mask" "F.Paste")
			(roundrect_rratio 0.25)
			(net 23 "GND")
			(pinfunction "AGND")
			(pintype "power_in")
		)
		(pad "10" smd roundrect
			(at -0.25 -1 180)
			(size 0.7 0.25)
			(layers "F.Cu" "F.Mask" "F.Paste")
			(roundrect_rratio 0.25)
			(net 166 "Net-(U2-FB)")
			(pinfunction "FB")
			(pintype "input")
		)
		(pad "11" smd roundrect
			(at -0.75 -1 180)
			(size 0.7 0.25)
			(layers "F.Cu" "F.Mask" "F.Paste")
			(roundrect_rratio 0.25)
			(net 413 "Net-(D3-C)")
			(pinfunction "EN")
			(pintype "input")
		)
	)
	(footprint "antmicro-footprints:FCBGA-503_22x22mm_Layout21x24_P1mm"
		(layer "F.Cu")
		(at 151.005 81.499999 -90)
		(property "Reference" "U14"
			(at -11.499999 11.005 0)
			(layer "F.SilkS")
			(effects
				(font
					(size 0.7 0.7)
					(thickness 0.15)
				)
				(justify left bottom)
			)
		)
		(property "Value" "EZX710AT2_S_LMR5"
			(at -11.4 12.5 270)
			(layer "F.Fab")
			(effects
				(font
					(size 0.7 0.7)
					(thickness 0.15)
				)
				(justify left bottom)
			)
		)
		(property "Datasheet" "https://www.google.com/url?sa=t&source=web&rct=j&opi=89978449&url=https://cdrdv2-public.intel.com/596333/596333_X710-TM4_Datasheet_v_2_4.pdf&ved=2ahUKEwiSuv20_sCOAxXVCRAIHdxGO_UQFnoECBEQAQ&usg=AOvVaw1CjGyrGWE8ZvOdw4VBsY6U"
			(at 0 0 270)
			(layer "F.Fab")
			(effects
				(font
					(size 0.7 0.7)
					(thickness 0.15)
				)
				(justify left bottom)
			)
		)
		(property "Description" "Ethernet ICs Intel Ethernet Controller 10 Gigabit X7"
			(at 0 0 270)
			(layer "F.Fab")
			(effects
				(font
					(size 0.7 0.7)
					(thickness 0.15)
				)
				(justify left bottom)
			)
		)
		(property "MPN" "EZX710AT2 S LMR5"
			(at 0 0 270)
			(unlocked yes)
			(layer "F.Fab")
			(hide yes)
			(effects
				(font
					(size 1 1)
					(thickness 0.15)
				)
			)
		)
		(property "Manufacturer" "Intel"
			(at 0 0 270)
			(unlocked yes)
			(layer "F.Fab")
			(hide yes)
			(effects
				(font
					(size 1 1)
					(thickness 0.15)
				)
			)
		)
		(property "Author" "Antmicro"
			(at 0 0 270)
			(unlocked yes)
			(layer "F.Fab")
			(hide yes)
			(effects
				(font
					(size 1 1)
					(thickness 0.15)
				)
			)
		)
		(property "License" "Apache-2.0"
			(at 0 0 270)
			(unlocked yes)
			(layer "F.Fab")
			(hide yes)
			(effects
				(font
					(size 1 1)
					(thickness 0.15)
				)
			)
		)
		(sheetname "/X710-AT2 power/")
		(sheetfile "x710-at2-power.kicad_sch")
		(attr smd)
		(fp_line
			(start -11.12 11.12)
			(end -11.12 5.62)
			(stroke
				(width 0.15)
				(type solid)
			)
			(layer "F.SilkS")
		)
		(fp_line
			(start -5.62 11.12)
			(end -11.12 11.12)
			(stroke
				(width 0.15)
				(type solid)
			)
			(layer "F.SilkS")
		)
		(fp_line
			(start 5.62 11.12)
			(end 11.12 11.12)
			(stroke
				(width 0.15)
				(type solid)
			)
			(layer "F.SilkS")
		)
		(fp_line
			(start 11.12 11.12)
			(end 11.12 5.62)
			(stroke
				(width 0.15)
				(type solid)
			)
			(layer "F.SilkS")
		)
		(fp_line
			(start -11.12 -10)
			(end -11.12 -5.62)
			(stroke
				(width 0.15)
				(type solid)
			)
			(layer "F.SilkS")
		)
		(fp_line
			(start -10 -11.12)
			(end -11.12 -10)
			(stroke
				(width 0.15)
				(type solid)
			)
			(layer "F.SilkS")
		)
		(fp_line
			(start -5.62 -11.12)
			(end -10 -11.12)
			(stroke
				(width 0.15)
				(type solid)
			)
			(layer "F.SilkS")
		)
		(fp_line
			(start 5.62 -11.12)
			(end 11.12 -11.12)
			(stroke
				(width 0.15)
				(type solid)
			)
			(layer "F.SilkS")
		)
		(fp_line
			(start 11.12 -11.12)
			(end 11.12 -5.62)
			(stroke
				(width 0.15)
				(type solid)
			)
			(layer "F.SilkS")
		)
		(fp_circle
			(center -11 -11)
			(end -11 -10.9)
			(stroke
				(width 0.15)
				(type solid)
			)
			(fill yes)
			(layer "F.SilkS")
		)
		(fp_rect
			(start -11.4 -11.4)
			(end 11.4 11.4)
			(stroke
				(width 0.05)
				(type solid)
			)
			(fill no)
			(layer "F.CrtYd")
		)
		(fp_line
			(start -11 11)
			(end 11 11)
			(stroke
				(width 0.15)
				(type solid)
			)
			(layer "F.Fab")
		)
		(fp_line
			(start 11 11)
			(end 11 -11)
			(stroke
				(width 0.15)
				(type solid)
			)
			(layer "F.Fab")
		)
		(fp_line
			(start -11 -10)
			(end -11 11)
			(stroke
				(width 0.15)
				(type solid)
			)
			(layer "F.Fab")
		)
		(fp_line
			(start -10 -11)
			(end -11 -10)
			(stroke
				(width 0.15)
				(type solid)
			)
			(layer "F.Fab")
		)
		(fp_line
			(start 11 -11)
			(end -10 -11)
			(stroke
				(width 0.15)
				(type solid)
			)
			(layer "F.Fab")
		)
		(fp_text user "Author: Antmicro"
			(at -11.4 16.1 270)
			(layer "F.Fab")
			(effects
				(font
					(size 0.7 0.7)
					(thickness 0.15)
				)
				(justify left bottom)
			)
		)
		(fp_text user "License: Apache-2.0"
			(at -11.4 14.9 270)
			(layer "F.Fab")
			(effects
				(font
					(size 0.7 0.7)
					(thickness 0.15)
				)
				(justify left bottom)
			)
		)
		(fp_text user "${REFERENCE}"
			(at -11.4 13.7 270)
			(layer "F.Fab")
			(effects
				(font
					(size 0.7 0.7)
					(thickness 0.15)
				)
				(justify left bottom)
			)
		)
		(pad "A3" smd circle
			(at -9.25 -9.95 270)
			(size 0.5 0.5)
			(layers "F.Cu" "F.Mask" "F.Paste")
			(net 23 "GND")
			(pinfunction "VSSA")
			(pintype "power_in")
		)
		(pad "A5" smd circle
			(at -8.25 -9.95 270)
			(size 0.5 0.5)
			(layers "F.Cu" "F.Mask" "F.Paste")
			(net 512 "unconnected-(U14B-SER1_RX_N-PadA5)")
			(pinfunction "SER1_RX_N")
			(pintype "input+no_connect")
		)
		(pad "A7" smd circle
			(at -7.25 -9.95 270)
			(size 0.5 0.5)
			(layers "F.Cu" "F.Mask" "F.Paste")
			(net 23 "GND")
			(pinfunction "VSSA")
			(pintype "passive")
		)
		(pad "A9" smd circle
			(at -6.25 -9.95 270)
			(size 0.5 0.5)
			(layers "F.Cu" "F.Mask" "F.Paste")
			(net 509 "unconnected-(U14B-SER1_TX_P-PadA9)")
			(pinfunction "SER1_TX_P")
			(pintype "output+no_connect")
		)
		(pad "A11" smd circle
			(at -5.25 -9.95 270)
			(size 0.5 0.5)
			(layers "F.Cu" "F.Mask" "F.Paste")
			(net 23 "GND")
			(pinfunction "VSSA")
			(pintype "passive")
		)
		(pad "A13" smd circle
			(at -4.25 -9.95 270)
			(size 0.5 0.5)
			(layers "F.Cu" "F.Mask" "F.Paste")
			(net 548 "unconnected-(U14B-SER0_RX_N-PadA13)")
			(pinfunction "SER0_RX_N")
			(pintype "input+no_connect")
		)
		(pad "A15" smd circle
			(at -3.25 -9.95 270)
			(size 0.5 0.5)
			(layers "F.Cu" "F.Mask" "F.Paste")
			(net 23 "GND")
			(pinfunction "VSSA")
			(pintype "passive")
		)
		(pad "A17" smd circle
			(at -2.25 -9.95 270)
			(size 0.5 0.5)
			(layers "F.Cu" "F.Mask" "F.Paste")
			(net 475 "unconnected-(U14B-SER0_TX_P-PadA17)")
			(pinfunction "SER0_TX_P")
			(pintype "output+no_connect")
		)
		(pad "A19" smd circle
			(at -1.25 -9.95 270)
			(size 0.5 0.5)
			(layers "F.Cu" "F.Mask" "F.Paste")
			(net 23 "GND")
			(pinfunction "VSSA")
			(pintype "passive")
		)
		(pad "A21" smd circle
			(at -0.25 -9.95 270)
			(size 0.5 0.5)
			(layers "F.Cu" "F.Mask" "F.Paste")
			(net 23 "GND")
			(pinfunction "AVSS")
			(pintype "power_in")
		)
		(pad "A23" smd circle
			(at 0.75 -9.95 270)
			(size 0.5 0.5)
			(layers "F.Cu" "F.Mask" "F.Paste")
			(net 52 "/2xRJ45/Ethernet_P1.D1+")
			(pinfunction "P1_A_P")
			(pintype "bidirectional")
		)
		(pad "A25" smd circle
			(at 1.75 -9.95 270)
			(size 0.5 0.5)
			(layers "F.Cu" "F.Mask" "F.Paste")
			(net 46 "/2xRJ45/Ethernet_P1.D2-")
			(pinfunction "P1_B_N")
			(pintype "bidirectional")
		)
		(pad "A27" smd circle
			(at 2.75 -9.95 270)
			(size 0.5 0.5)
			(layers "F.Cu" "F.Mask" "F.Paste")
			(net 48 "/2xRJ45/Ethernet_P1.D3+")
			(pinfunction "P1_C_P")
			(pintype "bidirectional")
		)
		(pad "A29" smd circle
			(at 3.75 -9.95 270)
			(size 0.5 0.5)
			(layers "F.Cu" "F.Mask" "F.Paste")
			(net 51 "/2xRJ45/Ethernet_P1.D4-")
			(pinfunction "P1_D_N")
			(pintype "bidirectional")
		)
		(pad "A31" smd circle
			(at 4.75 -9.95 270)
			(size 0.5 0.5)
			(layers "F.Cu" "F.Mask" "F.Paste")
			(net 23 "GND")
			(pinfunction "AVSS")
			(pintype "passive")
		)
		(pad "A33" smd circle
			(at 5.75 -9.95 270)
			(size 0.5 0.5)
			(layers "F.Cu" "F.Mask" "F.Paste")
			(net 41 "/2xRJ45/Ethernet_P0.D4+")
			(pinfunction "P0_D_P")
			(pintype "bidirectional")
		)
		(pad "A35" smd circle
			(at 6.75 -9.95 270)
			(size 0.5 0.5)
			(layers "F.Cu" "F.Mask" "F.Paste")
			(net 38 "/2xRJ45/Ethernet_P0.D3-")
			(pinfunction "P0_C_N")
			(pintype "bidirectional")
		)
		(pad "A37" smd circle
			(at 7.75 -9.95 270)
			(size 0.5 0.5)
			(layers "F.Cu" "F.Mask" "F.Paste")
			(net 39 "/2xRJ45/Ethernet_P0.D2+")
			(pinfunction "P0_B_P")
			(pintype "bidirectional")
		)
		(pad "A39" smd circle
			(at 8.75 -9.95 270)
			(size 0.5 0.5)
			(layers "F.Cu" "F.Mask" "F.Paste")
			(net 37 "/2xRJ45/Ethernet_P0.D1-")
			(pinfunction "P0_A_N")
			(pintype "bidirectional")
		)
		(pad "A41" smd circle
			(at 9.75 -9.95 270)
			(size 0.5 0.5)
			(layers "F.Cu" "F.Mask" "F.Paste")
			(net 504 "unconnected-(U14G-RSVDA41_NC-PadA41)")
			(pinfunction "RSVDA41_NC")
			(pintype "passive+no_connect")
		)
		(pad "AA1" smd circle
			(at -10.25 7.35 270)
			(size 0.5 0.5)
			(layers "F.Cu" "F.Mask" "F.Paste")
			(net 159 "/X710-AT2 PCIe/CLK+")
			(pinfunction "PE_CLK_P")
			(pintype "input")
		)
		(pad "AA3" smd circle
			(at -9.25 7.35 270)
			(size 0.5 0.5)
			(layers "F.Cu" "F.Mask" "F.Paste")
			(net 23 "GND")
			(pinfunction "VSSA")
			(pintype "passive")
		)
		(pad "AA5" smd circle
			(at -8.25 7.35 270)
			(size 0.5 0.5)
			(layers "F.Cu" "F.Mask" "F.Paste")
			(net 314 "/TB Controller/PCIex4.RX0+")
			(pinfunction "PER_0_P")
			(pintype "input")
		)
		(pad "AA7" smd circle
			(at -7.25 7.35 270)
			(size 0.5 0.5)
			(layers "F.Cu" "F.Mask" "F.Paste")
			(net 322 "/TB Controller/PCIex4.RX0-")
			(pinfunction "PER_0_N")
			(pintype "input")
		)
		(pad "AA9" smd circle
			(at -6.25 7.35 270)
			(size 0.5 0.5)
			(layers "F.Cu" "F.Mask" "F.Paste")
			(net 23 "GND")
			(pinfunction "VSSA")
			(pintype "passive")
		)
		(pad "AA11" smd circle
			(at -5.25 7.35 270)
			(size 0.5 0.5)
			(layers "F.Cu" "F.Mask" "F.Paste")
			(net 23 "GND")
			(pinfunction "VSSA")
			(pintype "passive")
		)
		(pad "AA13" smd circle
			(at -4.25 7.35 270)
			(size 0.5 0.5)
			(layers "F.Cu" "F.Mask" "F.Paste")
			(net 23 "GND")
			(pinfunction "VSSA")
			(pintype "passive")
		)
		(pad "AA15" smd circle
			(at -3.25 7.35 270)
			(size 0.5 0.5)
			(layers "F.Cu" "F.Mask" "F.Paste")
			(net 23 "GND")
			(pinfunction "VSSA")
			(pintype "passive")
		)
		(pad "AA17" smd circle
			(at -2.25 7.35 270)
			(size 0.5 0.5)
			(layers "F.Cu" "F.Mask" "F.Paste")
			(net 23 "GND")
			(pinfunction "VSSA")
			(pintype "passive")
		)
		(pad "AA19" smd circle
			(at -1.25 7.35 270)
			(size 0.5 0.5)
			(layers "F.Cu" "F.Mask" "F.Paste")
			(net 23 "GND")
			(pinfunction "VSSA")
			(pintype "passive")
		)
		(pad "AA21" smd circle
			(at -0.25 7.35 270)
			(size 0.5 0.5)
			(layers "F.Cu" "F.Mask" "F.Paste")
			(net 23 "GND")
			(pinfunction "VSSA")
			(pintype "passive")
		)
		(pad "AA23" smd circle
			(at 0.75 7.35 270)
			(size 0.5 0.5)
			(layers "F.Cu" "F.Mask" "F.Paste")
			(net 23 "GND")
			(pinfunction "VSSA")
			(pintype "passive")
		)
		(pad "AA25" smd circle
			(at 1.75 7.35 270)
			(size 0.5 0.5)
			(layers "F.Cu" "F.Mask" "F.Paste")
			(net 23 "GND")
			(pinfunction "VSSA")
			(pintype "passive")
		)
		(pad "AA27" smd circle
			(at 2.75 7.35 270)
			(size 0.5 0.5)
			(layers "F.Cu" "F.Mask" "F.Paste")
			(net 448 "unconnected-(U14A-PER_4_P-PadAA27)")
			(pinfunction "PER_4_P")
			(pintype "input+no_connect")
		)
		(pad "AA29" smd circle
			(at 3.75 7.35 270)
			(size 0.5 0.5)
			(layers "F.Cu" "F.Mask" "F.Paste")
			(net 23 "GND")
			(pinfunction "VSSA")
			(pintype "passive")
		)
		(pad "AA31" smd circle
			(at 4.75 7.35 270)
			(size 0.5 0.5)
			(layers "F.Cu" "F.Mask" "F.Paste")
			(net 463 "unconnected-(U14A-PER_5_N-PadAA31)")
			(pinfunction "PER_5_N")
			(pintype "input+no_connect")
		)
		(pad "AA33" smd circle
			(at 5.75 7.35 270)
			(size 0.5 0.5)
			(layers "F.Cu" "F.Mask" "F.Paste")
			(net 23 "GND")
			(pinfunction "VSSA")
			(pintype "passive")
		)
		(pad "AA35" smd circle
			(at 6.75 7.35 270)
			(size 0.5 0.5)
			(layers "F.Cu" "F.Mask" "F.Paste")
			(net 450 "unconnected-(U14A-PER_6_N-PadAA35)")
			(pinfunction "PER_6_N")
			(pintype "input+no_connect")
		)
		(pad "AA37" smd circle
			(at 7.75 7.35 270)
			(size 0.5 0.5)
			(layers "F.Cu" "F.Mask" "F.Paste")
			(net 23 "GND")
			(pinfunction "VSSA")
			(pintype "passive")
		)
		(pad "AA39" smd circle
			(at 8.75 7.35 270)
			(size 0.5 0.5)
			(layers "F.Cu" "F.Mask" "F.Paste")
			(net 490 "unconnected-(U14A-PER_7_N-PadAA39)")
			(pinfunction "PER_7_N")
			(pintype "input+no_connect")
		)
		(pad "AA41" smd circle
			(at 9.75 7.35 270)
			(size 0.5 0.5)
			(layers "F.Cu" "F.Mask" "F.Paste")
			(net 23 "GND")
			(pinfunction "VSSA")
			(pintype "passive")
		)
		(pad "AB2" smd circle
			(at -9.75 8.215 270)
			(size 0.5 0.5)
			(layers "F.Cu" "F.Mask" "F.Paste")
			(net 160 "/X710-AT2 PCIe/CLK-")
			(pinfunction "PE_CLK_N")
			(pintype "input")
		)
		(pad "AB4" smd circle
			(at -8.75 8.215 270)
			(size 0.5 0.5)
			(layers "F.Cu" "F.Mask" "F.Paste")
			(net 23 "GND")
			(pinfunction "VSSA")
			(pintype "passive")
		)
		(pad "AB6" smd circle
			(at -7.75 8.215 270)
			(size 0.5 0.5)
			(layers "F.Cu" "F.Mask" "F.Paste")
			(net 23 "GND")
			(pinfunction "VSSA")
			(pintype "passive")
		)
		(pad "AB8" smd circle
			(at -6.75 8.215 270)
			(size 0.5 0.5)
			(layers "F.Cu" "F.Mask" "F.Paste")
			(net 23 "GND")
			(pinfunction "VSSA")
			(pintype "passive")
		)
		(pad "AB10" smd circle
			(at -5.75 8.215 270)
			(size 0.5 0.5)
			(layers "F.Cu" "F.Mask" "F.Paste")
			(net 317 "/TB Controller/PCIex4.RX1+")
			(pinfunction "PER_1_P")
			(pintype "input")
		)
		(pad "AB12" smd circle
			(at -4.75 8.215 270)
			(size 0.5 0.5)
			(layers "F.Cu" "F.Mask" "F.Paste")
			(net 324 "/TB Controller/PCIex4.RX1-")
			(pinfunction "PER_1_N")
			(pintype "input")
		)
		(pad "AB14" smd circle
			(at -3.75 8.215 270)
			(size 0.5 0.5)
			(layers "F.Cu" "F.Mask" "F.Paste")
			(net 23 "GND")
			(pinfunction "VSSA")
			(pintype "passive")
		)
		(pad "AB16" smd circle
			(at -2.75 8.215 270)
			(size 0.5 0.5)
			(layers "F.Cu" "F.Mask" "F.Paste")
			(net 319 "/TB Controller/PCIex4.RX2+")
			(pinfunction "PER_2_P")
			(pintype "input")
		)
		(pad "AB18" smd circle
			(at -1.75 8.215 270)
			(size 0.5 0.5)
			(layers "F.Cu" "F.Mask" "F.Paste")
			(net 326 "/TB Controller/PCIex4.RX2-")
			(pinfunction "PER_2_N")
			(pintype "input")
		)
		(pad "AB20" smd circle
			(at -0.75 8.215 270)
			(size 0.5 0.5)
			(layers "F.Cu" "F.Mask" "F.Paste")
			(net 23 "GND")
			(pinfunction "VSSA")
			(pintype "passive")
		)
		(pad "AB22" smd circle
			(at 0.25 8.215 270)
			(size 0.5 0.5)
			(layers "F.Cu" "F.Mask" "F.Paste")
			(net 321 "/TB Controller/PCIex4.RX3+")
			(pinfunction "PER_3_P")
			(pintype "input")
		)
		(pad "AB24" smd circle
			(at 1.25 8.215 270)
			(size 0.5 0.5)
			(layers "F.Cu" "F.Mask" "F.Paste")
			(net 328 "/TB Controller/PCIex4.RX3-")
			(pinfunction "PER_3_N")
			(pintype "input")
		)
		(pad "AB26" smd circle
			(at 2.25 8.215 270)
			(size 0.5 0.5)
			(layers "F.Cu" "F.Mask" "F.Paste")
			(net 23 "GND")
			(pinfunction "VSSA")
			(pintype "passive")
		)
		(pad "AB28" smd circle
			(at 3.25 8.215 270)
			(size 0.5 0.5)
			(layers "F.Cu" "F.Mask" "F.Paste")
			(net 471 "unconnected-(U14A-PER_4_N-PadAB28)")
			(pinfunction "PER_4_N")
			(pintype "input+no_connect")
		)
		(pad "AB30" smd circle
			(at 4.25 8.215 270)
			(size 0.5 0.5)
			(layers "F.Cu" "F.Mask" "F.Paste")
			(net 23 "GND")
			(pinfunction "VSSA")
			(pintype "passive")
		)
		(pad "AB32" smd circle
			(at 5.25 8.215 270)
			(size 0.5 0.5)
			(layers "F.Cu" "F.Mask" "F.Paste")
			(net 23 "GND")
			(pinfunction "VSSA")
			(pintype "passive")
		)
		(pad "AB34" smd circle
			(at 6.25 8.215 270)
			(size 0.5 0.5)
			(layers "F.Cu" "F.Mask" "F.Paste")
			(net 23 "GND")
			(pinfunction "VSSA")
			(pintype "passive")
		)
		(pad "AB36" smd circle
			(at 7.25 8.215 270)
			(size 0.5 0.5)
			(layers "F.Cu" "F.Mask" "F.Paste")
			(net 23 "GND")
			(pinfunction "VSSA")
			(pintype "passive")
		)
		(pad "AB38" smd circle
			(at 8.25 8.215 270)
			(size 0.5 0.5)
			(layers "F.Cu" "F.Mask" "F.Paste")
			(net 23 "GND")
			(pinfunction "VSSA")
			(pintype "passive")
		)
		(pad "AB40" smd circle
			(at 9.25 8.215 270)
			(size 0.5 0.5)
			(layers "F.Cu" "F.Mask" "F.Paste")
			(net 23 "GND")
			(pinfunction "VSSA")
			(pintype "passive")
		)
		(pad "AB42" smd circle
			(at 10.25 8.215 270)
			(size 0.5 0.5)
			(layers "F.Cu" "F.Mask" "F.Paste")
			(net 74 "/X710-AT2 Misc/LAN_PWR_GOOD")
			(pinfunction "LAN_PWR_GOOD")
			(pintype "input")
		)
		(pad "AC1" smd circle
			(at -10.25 9.08 270)
			(size 0.5 0.5)
			(layers "F.Cu" "F.Mask" "F.Paste")
			(net 23 "GND")
			(pinfunction "VSSA")
			(pintype "passive")
		)
		(pad "AC3" smd circle
			(at -9.25 9.08 270)
			(size 0.5 0.5)
			(layers "F.Cu" "F.Mask" "F.Paste")
			(net 23 "GND")
			(pinfunction "VSSA")
			(pintype "passive")
		)
		(pad "AC5" smd circle
			(at -8.25 9.08 270)
			(size 0.5 0.5)
			(layers "F.Cu" "F.Mask" "F.Paste")
			(net 28 "/X710-AT2 PCIe/PCIe_{x4}_AC.TX0-")
			(pinfunction "PET_0_N")
			(pintype "output")
		)
		(pad "AC7" smd circle
			(at -7.25 9.08 270)
			(size 0.5 0.5)
			(layers "F.Cu" "F.Mask" "F.Paste")
			(net 23 "GND")
			(pinfunction "VSSA")
			(pintype "passive")
		)
		(pad "AC9" smd circle
			(at -6.25 9.08 270)
			(size 0.5 0.5)
			(layers "F.Cu" "F.Mask" "F.Paste")
			(net 23 "GND")
			(pinfunction "VSSA")
			(pintype "passive")
		)
		(pad "AC11" smd circle
			(at -5.25 9.08 270)
			(size 0.5 0.5)
			(layers "F.Cu" "F.Mask" "F.Paste")
			(net 23 "GND")
			(pinfunction "VSSA")
			(pintype "passive")
		)
		(pad "AC13" smd circle
			(at -4.25 9.08 270)
			(size 0.5 0.5)
			(layers "F.Cu" "F.Mask" "F.Paste")
			(net 23 "GND")
			(pinfunction "VSSA")
			(pintype "passive")
		)
		(pad "AC15" smd circle
			(at -3.25 9.08 270)
			(size 0.5 0.5)
			(layers "F.Cu" "F.Mask" "F.Paste")
			(net 23 "GND")
			(pinfunction "VSSA")
			(pintype "passive")
		)
		(pad "AC17" smd circle
			(at -2.25 9.08 270)
			(size 0.5 0.5)
			(layers "F.Cu" "F.Mask" "F.Paste")
			(net 23 "GND")
			(pinfunction "VSSA")
			(pintype "passive")
		)
		(pad "AC19" smd circle
			(at -1.25 9.08 270)
			(size 0.5 0.5)
			(layers "F.Cu" "F.Mask" "F.Paste")
			(net 23 "GND")
			(pinfunction "VSSA")
			(pintype "passive")
		)
		(pad "AC21" smd circle
			(at -0.25 9.08 270)
			(size 0.5 0.5)
			(layers "F.Cu" "F.Mask" "F.Paste")
			(net 23 "GND")
			(pinfunction "VSSA")
			(pintype "passive")
		)
		(pad "AC23" smd circle
			(at 0.75 9.08 270)
			(size 0.5 0.5)
			(layers "F.Cu" "F.Mask" "F.Paste")
			(net 23 "GND")
			(pinfunction "VSSA")
			(pintype "passive")
		)
		(pad "AC25" smd circle
			(at 1.75 9.08 270)
			(size 0.5 0.5)
			(layers "F.Cu" "F.Mask" "F.Paste")
			(net 23 "GND")
			(pinfunction "VSSA")
			(pintype "passive")
		)
		(pad "AC27" smd circle
			(at 2.75 9.08 270)
			(size 0.5 0.5)
			(layers "F.Cu" "F.Mask" "F.Paste")
			(net 23 "GND")
			(pinfunction "VSSA")
			(pintype "passive")
		)
		(pad "AC29" smd circle
			(at 3.75 9.08 270)
			(size 0.5 0.5)
			(layers "F.Cu" "F.Mask" "F.Paste")
			(net 23 "GND")
			(pinfunction "VSSA")
			(pintype "passive")
		)
		(pad "AC31" smd circle
			(at 4.75 9.08 270)
			(size 0.5 0.5)
			(layers "F.Cu" "F.Mask" "F.Paste")
			(net 579 "unconnected-(U14A-PET_5_P-PadAC31)")
			(pinfunction "PET_5_P")
			(pintype "output+no_connect")
		)
		(pad "AC33" smd circle
			(at 5.75 9.08 270)
			(size 0.5 0.5)
			(layers "F.Cu" "F.Mask" "F.Paste")
			(net 23 "GND")
			(pinfunction "VSSA")
			(pintype "passive")
		)
		(pad "AC35" smd circle
			(at 6.75 9.08 270)
			(size 0.5 0.5)
			(layers "F.Cu" "F.Mask" "F.Paste")
			(net 581 "unconnected-(U14A-PET_6_P-PadAC35)")
			(pinfunction "PET_6_P")
			(pintype "output+no_connect")
		)
		(pad "AC37" smd circle
			(at 7.75 9.08 270)
			(size 0.5 0.5)
			(layers "F.Cu" "F.Mask" "F.Paste")
			(net 23 "GND")
			(pinfunction "VSSA")
			(pintype "passive")
		)
		(pad "AC39" smd circle
			(at 8.75 9.08 270)
			(size 0.5 0.5)
			(layers "F.Cu" "F.Mask" "F.Paste")
			(net 571 "unconnected-(U14A-PET_7_P-PadAC39)")
			(pinfunction "PET_7_P")
			(pintype "output+no_connect")
		)
		(pad "AC41" smd circle
			(at 9.75 9.08 270)
			(size 0.5 0.5)
			(layers "F.Cu" "F.Mask" "F.Paste")
			(net 23 "GND")
			(pinfunction "VSSA")
			(pintype "passive")
		)
		(pad "AD2" smd circle
			(at -9.75 9.945 270)
			(size 0.5 0.5)
			(layers "F.Cu" "F.Mask" "F.Paste")
			(net 23 "GND")
			(pinfunction "VSSA")
			(pintype "passive")
		)
		(pad "AD4" smd circle
			(at -8.75 9.945 270)
			(size 0.5 0.5)
			(layers "F.Cu" "F.Mask" "F.Paste")
			(net 27 "/X710-AT2 PCIe/PCIe_{x4}_AC.TX0+")
			(pinfunction "PET_0_P")
			(pintype "output")
		)
		(pad "AD6" smd circle
			(at -7.75 9.945 270)
			(size 0.5 0.5)
			(layers "F.Cu" "F.Mask" "F.Paste")
			(net 23 "GND")
			(pinfunction "VSSA")
			(pintype "passive")
		)
		(pad "AD8" smd circle
			(at -6.75 9.945 270)
			(size 0.5 0.5)
			(layers "F.Cu" "F.Mask" "F.Paste")
			(net 29 "/X710-AT2 PCIe/PCIe_{x4}_AC.TX1+")
			(pinfunction "PET_1_P")
			(pintype "output")
		)
		(pad "AD10" smd circle
			(at -5.75 9.945 270)
			(size 0.5 0.5)
			(layers "F.Cu" "F.Mask" "F.Paste")
			(net 30 "/X710-AT2 PCIe/PCIe_{x4}_AC.TX1-")
			(pinfunction "PET_1_N")
			(pintype "output")
		)
		(pad "AD12" smd circle
			(at -4.75 9.945 270)
			(size 0.5 0.5)
			(layers "F.Cu" "F.Mask" "F.Paste")
			(net 23 "GND")
			(pinfunction "VSSA")
			(pintype "passive")
		)
		(pad "AD14" smd circle
			(at -3.75 9.945 270)
			(size 0.5 0.5)
			(layers "F.Cu" "F.Mask" "F.Paste")
			(net 31 "/X710-AT2 PCIe/PCIe_{x4}_AC.TX2+")
			(pinfunction "PET_2_P")
			(pintype "output")
		)
		(pad "AD16" smd circle
			(at -2.75 9.945 270)
			(size 0.5 0.5)
			(layers "F.Cu" "F.Mask" "F.Paste")
			(net 32 "/X710-AT2 PCIe/PCIe_{x4}_AC.TX2-")
			(pinfunction "PET_2_N")
			(pintype "output")
		)
		(pad "AD18" smd circle
			(at -1.75 9.945 270)
			(size 0.5 0.5)
			(layers "F.Cu" "F.Mask" "F.Paste")
			(net 23 "GND")
			(pinfunction "VSSA")
			(pintype "passive")
		)
		(pad "AD20" smd circle
			(at -0.75 9.945 270)
			(size 0.5 0.5)
			(layers "F.Cu" "F.Mask" "F.Paste")
			(net 33 "/X710-AT2 PCIe/PCIe_{x4}_AC.TX3+")
			(pinfunction "PET_3_P")
			(pintype "output")
		)
		(pad "AD22" smd circle
			(at 0.25 9.945 270)
			(size 0.5 0.5)
			(layers "F.Cu" "F.Mask" "F.Paste")
			(net 34 "/X710-AT2 PCIe/PCIe_{x4}_AC.TX3-")
			(pinfunction "PET_3_N")
			(pintype "output")
		)
		(pad "AD24" smd circle
			(at 1.25 9.945 270)
			(size 0.5 0.5)
			(layers "F.Cu" "F.Mask" "F.Paste")
			(net 23 "GND")
			(pinfunction "VSSA")
			(pintype "passive")
		)
		(pad "AD26" smd circle
			(at 2.25 9.945 270)
			(size 0.5 0.5)
			(layers "F.Cu" "F.Mask" "F.Paste")
			(net 487 "unconnected-(U14A-PET_4_P-PadAD26)")
			(pinfunction "PET_4_P")
			(pintype "output+no_connect")
		)
		(pad "AD28" smd circle
			(at 3.25 9.945 270)
			(size 0.5 0.5)
			(layers "F.Cu" "F.Mask" "F.Paste")
			(net 532 "unconnected-(U14A-PET_4_N-PadAD28)")
			(pinfunction "PET_4_N")
			(pintype "output+no_connect")
		)
		(pad "AD30" smd circle
			(at 4.25 9.945 270)
			(size 0.5 0.5)
			(layers "F.Cu" "F.Mask" "F.Paste")
			(net 23 "GND")
			(pinfunction "VSSA")
			(pintype "passive")
		)
		(pad "AD32" smd circle
			(at 5.25 9.945 270)
			(size 0.5 0.5)
			(layers "F.Cu" "F.Mask" "F.Paste")
			(net 536 "unconnected-(U14A-PET_5_N-PadAD32)")
			(pinfunction "PET_5_N")
			(pintype "output+no_connect")
		)
		(pad "AD34" smd circle
			(at 6.25 9.945 270)
			(size 0.5 0.5)
			(layers "F.Cu" "F.Mask" "F.Paste")
			(net 23 "GND")
			(pinfunction "VSSA")
			(pintype "passive")
		)
		(pad "AD36" smd circle
			(at 7.25 9.945 270)
			(size 0.5 0.5)
			(layers "F.Cu" "F.Mask" "F.Paste")
			(net 511 "unconnected-(U14A-PET_6_N-PadAD36)")
			(pinfunction "PET_6_N")
			(pintype "output+no_connect")
		)
		(pad "AD38" smd circle
			(at 8.25 9.945 270)
			(size 0.5 0.5)
			(layers "F.Cu" "F.Mask" "F.Paste")
			(net 23 "GND")
			(pinfunction "VSSA")
			(pintype "passive")
		)
		(pad "AD40" smd circle
			(at 9.25 9.945 270)
			(size 0.5 0.5)
			(layers "F.Cu" "F.Mask" "F.Paste")
			(net 516 "unconnected-(U14A-PET_7_N-PadAD40)")
			(pinfunction "PET_7_N")
			(pintype "output+no_connect")
		)
		(pad "AD42" smd circle
			(at 10.25 9.945 270)
			(size 0.5 0.5)
			(layers "F.Cu" "F.Mask" "F.Paste")
			(net 23 "GND")
			(pinfunction "VSSA")
			(pintype "passive")
		)
		(pad "B2" smd circle
			(at -9.75 -9.085 270)
			(size 0.5 0.5)
			(layers "F.Cu" "F.Mask" "F.Paste")
			(net 23 "GND")
			(pinfunction "VSSA")
			(pintype "passive")
		)
		(pad "B4" smd circle
			(at -8.75 -9.085 270)
			(size 0.5 0.5)
			(layers "F.Cu" "F.Mask" "F.Paste")
			(net 23 "GND")
			(pinfunction "VSSA")
			(pintype "passive")
		)
		(pad "B6" smd circle
			(at -7.75 -9.085 270)
			(size 0.5 0.5)
			(layers "F.Cu" "F.Mask" "F.Paste")
			(net 545 "unconnected-(U14B-SER1_RX_P-PadB6)")
			(pinfunction "SER1_RX_P")
			(pintype "input+no_connect")
		)
		(pad "B8" smd circle
			(at -6.75 -9.085 270)
			(size 0.5 0.5)
			(layers "F.Cu" "F.Mask" "F.Paste")
			(net 23 "GND")
			(pinfunction "VSSA")
			(pintype "passive")
		)
		(pad "B10" smd circle
			(at -5.75 -9.085 270)
			(size 0.5 0.5)
			(layers "F.Cu" "F.Mask" "F.Paste")
			(net 456 "unconnected-(U14B-SER1_TX_N-PadB10)")
			(pinfunction "SER1_TX_N")
			(pintype "output+no_connect")
		)
		(pad "B12" smd circle
			(at -4.75 -9.085 270)
			(size 0.5 0.5)
			(layers "F.Cu" "F.Mask" "F.Paste")
			(net 23 "GND")
			(pinfunction "VSSA")
			(pintype "passive")
		)
		(pad "B14" smd circle
			(at -3.75 -9.085 270)
			(size 0.5 0.5)
			(layers "F.Cu" "F.Mask" "F.Paste")
			(net 538 "unconnected-(U14B-SER0_RX_P-PadB14)")
			(pinfunction "SER0_RX_P")
			(pintype "input+no_connect")
		)
		(pad "B16" smd circle
			(at -2.75 -9.085 270)
			(size 0.5 0.5)
			(layers "F.Cu" "F.Mask" "F.Paste")
			(net 23 "GND")
			(pinfunction "VSSA")
			(pintype "passive")
		)
		(pad "B18" smd circle
			(at -1.75 -9.085 270)
			(size 0.5 0.5)
			(layers "F.Cu" "F.Mask" "F.Paste")
			(net 518 "unconnected-(U14B-SER0_TX_N-PadB18)")
			(pinfunction "SER0_TX_N")
			(pintype "output+no_connect")
		)
		(pad "B20" smd circle
			(at -0.75 -9.085 270)
			(size 0.5 0.5)
			(layers "F.Cu" "F.Mask" "F.Paste")
			(net 23 "GND")
			(pinfunction "VSSA")
			(pintype "passive")
		)
		(pad "B22" smd circle
			(at 0.25 -9.085 270)
			(size 0.5 0.5)
			(layers "F.Cu" "F.Mask" "F.Paste")
			(net 23 "GND")
			(pinfunction "AVSS")
			(pintype "passive")
		)
		(pad "B24" smd circle
			(at 1.25 -9.085 270)
			(size 0.5 0.5)
			(layers "F.Cu" "F.Mask" "F.Paste")
			(net 45 "/2xRJ45/Ethernet_P1.D1-")
			(pinfunction "P1_A_N")
			(pintype "bidirectional")
		)
		(pad "B26" smd circle
			(at 2.25 -9.085 270)
			(size 0.5 0.5)
			(layers "F.Cu" "F.Mask" "F.Paste")
			(net 47 "/2xRJ45/Ethernet_P1.D2+")
			(pinfunction "P1_B_P")
			(pintype "bidirectional")
		)
		(pad "B28" smd circle
			(at 3.25 -9.085 270)
			(size 0.5 0.5)
			(layers "F.Cu" "F.Mask" "F.Paste")
			(net 49 "/2xRJ45/Ethernet_P1.D3-")
			(pinfunction "P1_C_N")
			(pintype "bidirectional")
		)
		(pad "B30" smd circle
			(at 4.25 -9.085 270)
			(size 0.5 0.5)
			(layers "F.Cu" "F.Mask" "F.Paste")
			(net 50 "/2xRJ45/Ethernet_P1.D4+")
			(pinfunction "P1_D_P")
			(pintype "bidirectional")
		)
		(pad "B32" smd circle
			(at 5.25 -9.085 270)
			(size 0.5 0.5)
			(layers "F.Cu" "F.Mask" "F.Paste")
			(net 23 "GND")
			(pinfunction "AVSS")
			(pintype "passive")
		)
		(pad "B34" smd circle
			(at 6.25 -9.085 270)
			(size 0.5 0.5)
			(layers "F.Cu" "F.Mask" "F.Paste")
			(net 43 "/2xRJ45/Ethernet_P0.D4-")
			(pinfunction "P0_D_N")
			(pintype "bidirectional")
		)
		(pad "B36" smd circle
			(at 7.25 -9.085 270)
			(size 0.5 0.5)
			(layers "F.Cu" "F.Mask" "F.Paste")
			(net 44 "/2xRJ45/Ethernet_P0.D3+")
			(pinfunction "P0_C_P")
			(pintype "bidirectional")
		)
		(pad "B38" smd circle
			(at 8.25 -9.085 270)
			(size 0.5 0.5)
			(layers "F.Cu" "F.Mask" "F.Paste")
			(net 36 "/2xRJ45/Ethernet_P0.D2-")
			(pinfunction "P0_B_N")
			(pintype "bidirectional")
		)
		(pad "B40" smd circle
			(at 9.25 -9.085 270)
			(size 0.5 0.5)
			(layers "F.Cu" "F.Mask" "F.Paste")
			(net 42 "/2xRJ45/Ethernet_P0.D1+")
			(pinfunction "P0_A_P")
			(pintype "bidirectional")
		)
		(pad "B42" smd circle
			(at 10.25 -9.085 270)
			(size 0.5 0.5)
			(layers "F.Cu" "F.Mask" "F.Paste")
			(net 508 "unconnected-(U14G-RSVDB42_NC-PadB42)")
			(pinfunction "RSVDB42_NC")
			(pintype "passive+no_connect")
		)
		(pad "C1" smd circle
			(at -10.25 -8.22 270)
			(size 0.5 0.5)
			(layers "F.Cu" "F.Mask" "F.Paste")
			(net 24 "/X710-AT2 10GbE/25MHZ_OSC.+")
			(pinfunction "REFCLKIN_P")
			(pintype "input")
		)
		(pad "C3" smd circle
			(at -9.25 -8.22 270)
			(size 0.5 0.5)
			(layers "F.Cu" "F.Mask" "F.Paste")
			(net 26 "/X710-AT2 10GbE/25MHZ_OSC.-")
			(pinfunction "REFCLKIN_N")
			(pintype "input")
		)
		(pad "C5" smd circle
			(at -8.25 -8.22 270)
			(size 0.5 0.5)
			(layers "F.Cu" "F.Mask" "F.Paste")
			(net 23 "GND")
			(pinfunction "VSSA")
			(pintype "passive")
		)
		(pad "C7" smd circle
			(at -7.25 -8.22 270)
			(size 0.5 0.5)
			(layers "F.Cu" "F.Mask" "F.Paste")
			(net 23 "GND")
			(pinfunction "VSSA")
			(pintype "passive")
		)
		(pad "C9" smd circle
			(at -6.25 -8.22 270)
			(size 0.5 0.5)
			(layers "F.Cu" "F.Mask" "F.Paste")
			(net 23 "GND")
			(pinfunction "VSSA")
			(pintype "passive")
		)
		(pad "C11" smd circle
			(at -5.25 -8.22 270)
			(size 0.5 0.5)
			(layers "F.Cu" "F.Mask" "F.Paste")
			(net 23 "GND")
			(pinfunction "VSSA")
			(pintype "passive")
		)
		(pad "C13" smd circle
			(at -4.25 -8.22 270)
			(size 0.5 0.5)
			(layers "F.Cu" "F.Mask" "F.Paste")
			(net 23 "GND")
			(pinfunction "VSSA")
			(pintype "passive")
		)
		(pad "C15" smd circle
			(at -3.25 -8.22 270)
			(size 0.5 0.5)
			(layers "F.Cu" "F.Mask" "F.Paste")
			(net 23 "GND")
			(pinfunction "VSSA")
			(pintype "passive")
		)
		(pad "C17" smd circle
			(at -2.25 -8.22 270)
			(size 0.5 0.5)
			(layers "F.Cu" "F.Mask" "F.Paste")
			(net 23 "GND")
			(pinfunction "VSSA")
			(pintype "passive")
		)
		(pad "C19" smd circle
			(at -1.25 -8.22 270)
			(size 0.5 0.5)
			(layers "F.Cu" "F.Mask" "F.Paste")
			(net 23 "GND")
			(pinfunction "VSSA")
			(pintype "passive")
		)
		(pad "C21" smd circle
			(at -0.25 -8.22 270)
			(size 0.5 0.5)
			(layers "F.Cu" "F.Mask" "F.Paste")
			(net 562 "unconnected-(U14G-RSVDC21_NC-PadC21)")
			(pinfunction "RSVDC21_NC")
			(pintype "passive+no_connect")
		)
		(pad "C23" smd circle
			(at 0.75 -8.22 270)
			(size 0.5 0.5)
			(layers "F.Cu" "F.Mask" "F.Paste")
			(net 14 "P1_AVDDL")
			(pinfunction "P1_AVDDL")
			(pintype "power_in")
		)
		(pad "C25" smd circle
			(at 1.75 -8.22 270)
			(size 0.5 0.5)
			(layers "F.Cu" "F.Mask" "F.Paste")
			(net 14 "P1_AVDDL")
			(pinfunction "P1_AVDDL")
			(pintype "passive")
		)
		(pad "C27" smd circle
			(at 2.75 -8.22 270)
			(size 0.5 0.5)
			(layers "F.Cu" "F.Mask" "F.Paste")
			(net 14 "P1_AVDDL")
			(pinfunction "P1_AVDDL")
			(pintype "passive")
		)
		(pad "C29" smd circle
			(at 3.75 -8.22 270)
			(size 0.5 0.5)
			(layers "F.Cu" "F.Mask" "F.Paste")
			(net 14 "P1_AVDDL")
			(pinfunction "P1_AVDDL")
			(pintype "passive")
		)
		(pad "C31" smd circle
			(at 4.75 -8.22 270)
			(size 0.5 0.5)
			(layers "F.Cu" "F.Mask" "F.Paste")
			(net 23 "GND")
			(pinfunction "AVSS")
			(pintype "passive")
		)
		(pad "C33" smd circle
			(at 5.75 -8.22 270)
			(size 0.5 0.5)
			(layers "F.Cu" "F.Mask" "F.Paste")
			(net 5 "P0_AVDDL")
			(pinfunction "P0_AVDDL")
			(pintype "power_in")
		)
		(pad "C35" smd circle
			(at 6.75 -8.22 270)
			(size 0.5 0.5)
			(layers "F.Cu" "F.Mask" "F.Paste")
			(net 5 "P0_AVDDL")
			(pinfunction "P0_AVDDL")
			(pintype "passive")
		)
		(pad "C37" smd circle
			(at 7.75 -8.22 270)
			(size 0.5 0.5)
			(layers "F.Cu" "F.Mask" "F.Paste")
			(net 5 "P0_AVDDL")
			(pinfunction "P0_AVDDL")
			(pintype "passive")
		)
		(pad "C39" smd circle
			(at 8.75 -8.22 270)
			(size 0.5 0.5)
			(layers "F.Cu" "F.Mask" "F.Paste")
			(net 5 "P0_AVDDL")
			(pinfunction "P0_AVDDL")
			(pintype "passive")
		)
		(pad "C41" smd circle
			(at 9.75 -8.22 270)
			(size 0.5 0.5)
			(layers "F.Cu" "F.Mask" "F.Paste")
			(net 23 "GND")
			(pinfunction "AVSS")
			(pintype "passive")
		)
		(pad "D2" smd circle
			(at -9.75 -7.355 270)
			(size 0.5 0.5)
			(layers "F.Cu" "F.Mask" "F.Paste")
			(net 127 "/X710-AT2 Misc/~{DEV_DIS}")
			(pinfunction "~{DEV_DIS}")
			(pintype "tri_state")
		)
		(pad "D4" smd circle
			(at -8.75 -7.355 270)
			(size 0.5 0.5)
			(layers "F.Cu" "F.Mask" "F.Paste")
			(net 149 "/X710-AT2 Misc/REFCLK_SEL")
			(pinfunction "REFCLK_SEL")
			(pintype "input")
		)
		(pad "D6" smd circle
			(at -7.75 -7.355 270)
			(size 0.5 0.5)
			(layers "F.Cu" "F.Mask" "F.Paste")
			(net 23 "GND")
			(pinfunction "RSVDD6_VSS")
			(pintype "passive")
		)
		(pad "D8" smd circle
			(at -6.75 -7.355 270)
			(size 0.5 0.5)
			(layers "F.Cu" "F.Mask" "F.Paste")
			(net 101 "/X710-AT2 RSVD/RSVDD8_1P88V")
			(pinfunction "RSVDD8_1P88V")
			(pintype "passive")
		)
		(pad "D10" smd circle
			(at -5.75 -7.355 270)
			(size 0.5 0.5)
			(layers "F.Cu" "F.Mask" "F.Paste")
			(net 132 "/X710-AT2 Misc/XTAL_BYPASS")
			(pinfunction "XTAL_BYPASS")
			(pintype "passive")
		)
		(pad "D12" smd circle
			(at -4.75 -7.355 270)
			(size 0.5 0.5)
			(layers "F.Cu" "F.Mask" "F.Paste")
			(net 150 "/X710-AT2 Misc/~{PHY_RESET}")
			(pinfunction "~{RESET}")
			(pintype "input")
		)
		(pad "D14" smd circle
			(at -3.75 -7.355 270)
			(size 0.5 0.5)
			(layers "F.Cu" "F.Mask" "F.Paste")
			(net 23 "GND")
			(pinfunction "RSVDD14")
			(pintype "input")
		)
		(pad "D16" smd circle
			(at -2.75 -7.355 270)
			(size 0.5 0.5)
			(layers "F.Cu" "F.Mask" "F.Paste")
			(net 105 "/X710-AT2 Misc/PHY_TMS")
			(pinfunction "PHY_TMS")
			(pintype "input")
		)
		(pad "D18" smd circle
			(at -1.75 -7.355 270)
			(size 0.5 0.5)
			(layers "F.Cu" "F.Mask" "F.Paste")
			(net 88 "/X710-AT2 Misc/~{PHY_TRST}")
			(pinfunction "~{PHY_TRST}")
			(pintype "input")
		)
		(pad "D20" smd circle
			(at -0.75 -7.355 270)
			(size 0.5 0.5)
			(layers "F.Cu" "F.Mask" "F.Paste")
			(net 517 "unconnected-(U14G-RSVDD20_NC-PadD20)")
			(pinfunction "RSVDD20_NC")
			(pintype "passive+no_connect")
		)
		(pad "D22" smd circle
			(at 0.25 -7.355 270)
			(size 0.5 0.5)
			(layers "F.Cu" "F.Mask" "F.Paste")
			(net 23 "GND")
			(pinfunction "RSVDD22_VSS")
			(pintype "passive")
		)
		(pad "D24" smd circle
			(at 1.25 -7.355 270)
			(size 0.5 0.5)
			(layers "F.Cu" "F.Mask" "F.Paste")
			(net 23 "GND")
			(pinfunction "AVSS")
			(pintype "passive")
		)
		(pad "D26" smd circle
			(at 2.25 -7.355 270)
			(size 0.5 0.5)
			(layers "F.Cu" "F.Mask" "F.Paste")
			(net 23 "GND")
			(pinfunction "AVSS")
			(pintype "passive")
		)
		(pad "D28" smd circle
			(at 3.25 -7.355 270)
			(size 0.5 0.5)
			(layers "F.Cu" "F.Mask" "F.Paste")
			(net 23 "GND")
			(pinfunction "AVSS")
			(pintype "passive")
		)
		(pad "D30" smd circle
			(at 4.25 -7.355 270)
			(size 0.5 0.5)
			(layers "F.Cu" "F.Mask" "F.Paste")
			(net 10 "AVDDH")
			(pinfunction "BIAS_AVDDH")
			(pintype "power_in")
		)
		(pad "D32" smd circle
			(at 5.25 -7.355 270)
			(size 0.5 0.5)
			(layers "F.Cu" "F.Mask" "F.Paste")
			(net 566 "unconnected-(U14G-RSVDD32_NC-PadD32)")
			(pinfunction "RSVDD32_NC")
			(pintype "passive+no_connect")
		)
		(pad "D34" smd circle
			(at 6.25 -7.355 270)
			(size 0.5 0.5)
			(layers "F.Cu" "F.Mask" "F.Paste")
			(net 20 "XGB_AVDDH")
			(pinfunction "XGB_AVDDH")
			(pintype "power_in")
		)
		(pad "D36" smd circle
			(at 7.25 -7.355 270)
			(size 0.5 0.5)
			(layers "F.Cu" "F.Mask" "F.Paste")
			(net 23 "GND")
			(pinfunction "AVSS")
			(pintype "passive")
		)
		(pad "D38" smd circle
			(at 8.25 -7.355 270)
			(size 0.5 0.5)
			(layers "F.Cu" "F.Mask" "F.Paste")
			(net 23 "GND")
			(pinfunction "AVSS")
			(pintype "passive")
		)
		(pad "D40" smd circle
			(at 9.25 -7.355 270)
			(size 0.5 0.5)
			(layers "F.Cu" "F.Mask" "F.Paste")
			(net 23 "GND")
			(pinfunction "AVSS")
			(pintype "passive")
		)
		(pad "D42" smd circle
			(at 10.25 -7.355 270)
			(size 0.5 0.5)
			(layers "F.Cu" "F.Mask" "F.Paste")
			(net 115 "/X710-AT2 Misc/50MHZ_XTAL.+")
			(pinfunction "XTAL_P")
			(pintype "input")
		)
		(pad "E1" smd circle
			(at -10.25 -6.49 270)
			(size 0.5 0.5)
			(layers "F.Cu" "F.Mask" "F.Paste")
			(net 75 "/X710-AT2 Misc/AUX_PWR")
			(pinfunction "AUX_PWR")
			(pintype "tri_state")
		)
		(pad "E3" smd circle
			(at -9.25 -6.49 270)
			(size 0.5 0.5)
			(layers "F.Cu" "F.Mask" "F.Paste")
			(net 103 "/X710-AT2 Misc/MAIN_PWR_OK")
			(pinfunction "MAIN_PWR_OK")
			(pintype "input")
		)
		(pad "E5" smd circle
			(at -8.25 -6.49 270)
			(size 0.5 0.5)
			(layers "F.Cu" "F.Mask" "F.Paste")
			(net 110 "/X710-AT2 10GbE/~{PHY_RESET_3V3_R}")
			(pinfunction "SDP0_0")
			(pintype "tri_state")
		)
		(pad "E7" smd circle
			(at -7.25 -6.49 270)
			(size 0.5 0.5)
			(layers "F.Cu" "F.Mask" "F.Paste")
			(net 537 "unconnected-(U14C-SDP2_2-PadE7)")
			(pinfunction "SDP2_2")
			(pintype "passive+no_connect")
		)
		(pad "E9" smd circle
			(at -6.25 -6.49 270)
			(size 0.5 0.5)
			(layers "F.Cu" "F.Mask" "F.Paste")
			(net 522 "unconnected-(U14F-SYNCE_LOCK_1-PadE9)")
			(pinfunction "SYNCE_LOCK_1")
			(pintype "output+no_connect")
		)
		(pad "E11" smd circle
			(at -5.25 -6.49 270)
			(size 0.5 0.5)
			(layers "F.Cu" "F.Mask" "F.Paste")
			(net 565 "unconnected-(U14F-SYNCE_LOCK_2-PadE11)")
			(pinfunction "SYNCE_LOCK_2")
			(pintype "output+no_connect")
		)
		(pad "E13" smd circle
			(at -4.25 -6.49 270)
			(size 0.5 0.5)
			(layers "F.Cu" "F.Mask" "F.Paste")
			(net 514 "unconnected-(U14F-SYNCE_CLKOUT_3-PadE13)")
			(pinfunction "SYNCE_CLKOUT_3")
			(pintype "output+no_connect")
		)
		(pad "E15" smd circle
			(at -3.25 -6.49 270)
			(size 0.5 0.5)
			(layers "F.Cu" "F.Mask" "F.Paste")
			(net 106 "/X710-AT2 Misc/PHY_TDI")
			(pinfunction "PHY_TDI")
			(pintype "input")
		)
		(pad "E17" smd circle
			(at -2.25 -6.49 270)
			(size 0.5 0.5)
			(layers "F.Cu" "F.Mask" "F.Paste")
			(net 104 "/X710-AT2 Misc/PHY_TCK")
			(pinfunction "PHY_TCK")
			(pintype "input")
		)
		(pad "E19" smd circle
			(at -1.25 -6.49 270)
			(size 0.5 0.5)
			(layers "F.Cu" "F.Mask" "F.Paste")
			(net 129 "/X710-AT2 RSVD/RSVDE19_1P88V")
			(pinfunction "RSVDE19_1P88V")
			(pintype "passive")
		)
		(pad "E21" smd circle
			(at -0.25 -6.49 270)
			(size 0.5 0.5)
			(layers "F.Cu" "F.Mask" "F.Paste")
			(net 23 "GND")
			(pinfunction "RSVDE21_VSS")
			(pintype "passive")
		)
		(pad "E23" smd circle
			(at 0.75 -6.49 270)
			(size 0.5 0.5)
			(layers "F.Cu" "F.Mask" "F.Paste")
			(net 23 "GND")
			(pinfunction "RSVDE23_VSS")
			(pintype "passive")
		)
		(pad "E25" smd circle
			(at 1.75 -6.49 270)
			(size 0.5 0.5)
			(layers "F.Cu" "F.Mask" "F.Paste")
			(net 23 "GND")
			(pinfunction "RSVDE25_VSS")
			(pintype "passive")
		)
		(pad "E27" smd circle
			(at 2.75 -6.49 270)
			(size 0.5 0.5)
			(layers "F.Cu" "F.Mask" "F.Paste")
			(net 10 "AVDDH")
			(pinfunction "P1_AVDDH")
			(pintype "power_in")
		)
		(pad "E29" smd circle
			(at 3.75 -6.49 270)
			(size 0.5 0.5)
			(layers "F.Cu" "F.Mask" "F.Paste")
			(net 10 "AVDDH")
			(pinfunction "P1_AVDDH")
			(pintype "passive")
		)
		(pad "E31" smd circle
			(at 4.75 -6.49 270)
			(size 0.5 0.5)
			(layers "F.Cu" "F.Mask" "F.Paste")
			(net 23 "GND")
			(pinfunction "AVSS")
			(pintype "passive")
		)
		(pad "E33" smd circle
			(at 5.75 -6.49 270)
			(size 0.5 0.5)
			(layers "F.Cu" "F.Mask" "F.Paste")
			(net 23 "GND")
			(pinfunction "AVSS")
			(pintype "passive")
		)
		(pad "E35" smd circle
			(at 6.75 -6.49 270)
			(size 0.5 0.5)
			(layers "F.Cu" "F.Mask" "F.Paste")
			(net 10 "AVDDH")
			(pinfunction "P0_AVDDH")
			(pintype "power_in")
		)
		(pad "E37" smd circle
			(at 7.75 -6.49 270)
			(size 0.5 0.5)
			(layers "F.Cu" "F.Mask" "F.Paste")
			(net 10 "AVDDH")
			(pinfunction "P0_AVDDH")
			(pintype "passive")
		)
		(pad "E39" smd circle
			(at 8.75 -6.49 270)
			(size 0.5 0.5)
			(layers "F.Cu" "F.Mask" "F.Paste")
			(net 63 "/X710-AT2 10GbE/BIAS_RDAC")
			(pinfunction "BIAS_RDAC")
			(pintype "passive")
		)
		(pad "E41" smd circle
			(at 9.75 -6.49 270)
			(size 0.5 0.5)
			(layers "F.Cu" "F.Mask" "F.Paste")
			(net 120 "/X710-AT2 Misc/50MHZ_XTAL.-")
			(pinfunction "XTAL_N")
			(pintype "input")
		)
		(pad "F2" smd circle
			(at -9.75 -5.625 270)
			(size 0.5 0.5)
			(layers "F.Cu" "F.Mask" "F.Paste")
			(net 140 "/X710-AT2 Misc/NCSI.TXD_0")
			(pinfunction "NCSI_TXD_0")
			(pintype "input")
		)
		(pad "F4" smd circle
			(at -8.75 -5.625 270)
			(size 0.5 0.5)
			(layers "F.Cu" "F.Mask" "F.Paste")
			(net 440 "Net-(U14D-NCSI_ARB_OUT)")
			(pinfunction "NCSI_ARB_OUT")
			(pintype "output")
		)
		(pad "F6" smd circle
			(at -7.75 -5.625 270)
			(size 0.5 0.5)
			(layers "F.Cu" "F.Mask" "F.Paste")
			(net 583 "unconnected-(U14C-SDP2_0-PadF6)")
			(pinfunction "SDP2_0")
			(pintype "passive+no_connect")
		)
		(pad "F8" smd circle
			(at -6.75 -5.625 270)
			(size 0.5 0.5)
			(layers "F.Cu" "F.Mask" "F.Paste")
			(net 531 "unconnected-(U14F-SYNCE_LOCK_0-PadF8)")
			(pinfunction "SYNCE_LOCK_0")
			(pintype "output+no_connect")
		)
		(pad "F10" smd circle
			(at -5.75 -5.625 270)
			(size 0.5 0.5)
			(layers "F.Cu" "F.Mask" "F.Paste")
			(net 543 "unconnected-(U14F-SYNCE_CLKOUT_1-PadF10)")
			(pinfunction "SYNCE_CLKOUT_1")
			(pintype "output+no_connect")
		)
		(pad "F12" smd circle
			(at -4.75 -5.625 270)
			(size 0.5 0.5)
			(layers "F.Cu" "F.Mask" "F.Paste")
			(net 569 "unconnected-(U14F-SYNCE_LOCK_3-PadF12)")
			(pinfunction "SYNCE_LOCK_3")
			(pintype "output+no_connect")
		)
		(pad "F14" smd circle
			(at -3.75 -5.625 270)
			(size 0.5 0.5)
			(layers "F.Cu" "F.Mask" "F.Paste")
			(net 124 "/X710-AT2 10GbE/~{P1_INT}")
			(pinfunction "P1_INT_MLC")
			(pintype "passive")
		)
		(pad "F16" smd circle
			(at -2.75 -5.625 270)
			(size 0.5 0.5)
			(layers "F.Cu" "F.Mask" "F.Paste")
			(net 107 "/X710-AT2 Misc/PHY_TDO")
			(pinfunction "PHY_TDO")
			(pintype "open_collector")
		)
		(pad "F18" smd circle
			(at -1.75 -5.625 270)
			(size 0.5 0.5)
			(layers "F.Cu" "F.Mask" "F.Paste")
			(net 23 "GND")
			(pinfunction "RSVDF18_VSS")
			(pintype "passive")
		)
		(pad "F20" smd circle
			(at -0.75 -5.625 270)
			(size 0.5 0.5)
			(layers "F.Cu" "F.Mask" "F.Paste")
			(net 23 "GND")
			(pinfunction "RSVDF20_VSS")
			(pintype "passive")
		)
		(pad "F22" smd circle
			(at 0.25 -5.625 270)
			(size 0.5 0.5)
			(layers "F.Cu" "F.Mask" "F.Paste")
			(net 23 "GND")
			(pinfunction "RSVDF22_VSS")
			(pintype "passive")
		)
		(pad "F24" smd circle
			(at 1.25 -5.625 270)
			(size 0.5 0.5)
			(layers "F.Cu" "F.Mask" "F.Paste")
			(net 23 "GND")
			(pinfunction "VSS")
			(pintype "power_in")
		)
		(pad "F26" smd circle
			(at 2.25 -5.625 270)
			(size 0.5 0.5)
			(layers "F.Cu" "F.Mask" "F.Paste")
			(net 23 "GND")
			(pinfunction "VSS")
			(pintype "passive")
		)
		(pad "F28" smd circle
			(at 3.25 -5.625 270)
			(size 0.5 0.5)
			(layers "F.Cu" "F.Mask" "F.Paste")
			(net 23 "GND")
			(pinfunction "VSS")
			(pintype "passive")
		)
		(pad "F30" smd circle
			(at 4.25 -5.625 270)
			(size 0.5 0.5)
			(layers "F.Cu" "F.Mask" "F.Paste")
			(net 23 "GND")
			(pinfunction "VSS")
			(pintype "passive")
		)
		(pad "F32" smd circle
			(at 5.25 -5.625 270)
			(size 0.5 0.5)
			(layers "F.Cu" "F.Mask" "F.Paste")
			(net 23 "GND")
			(pinfunction "VSS")
			(pintype "passive")
		)
		(pad "F34" smd circle
			(at 6.25 -5.625 270)
			(size 0.5 0.5)
			(layers "F.Cu" "F.Mask" "F.Paste")
			(net 23 "GND")
			(pinfunction "VSS")
			(pintype "passive")
		)
		(pad "F36" smd circle
			(at 7.25 -5.625 270)
			(size 0.5 0.5)
			(layers "F.Cu" "F.Mask" "F.Paste")
			(net 23 "GND")
			(pinfunction "VSS")
			(pintype "passive")
		)
		(pad "F38" smd circle
			(at 8.25 -5.625 270)
			(size 0.5 0.5)
			(layers "F.Cu" "F.Mask" "F.Paste")
			(net 23 "GND")
			(pinfunction "RSVDF38_VSS")
			(pintype "passive")
		)
		(pad "F40" smd circle
			(at 9.25 -5.625 270)
			(size 0.5 0.5)
			(layers "F.Cu" "F.Mask" "F.Paste")
			(net 23 "GND")
			(pinfunction "AVSS")
			(pintype "passive")
		)
		(pad "F42" smd circle
			(at 10.25 -5.625 270)
			(size 0.5 0.5)
			(layers "F.Cu" "F.Mask" "F.Paste")
			(net 23 "GND")
			(pinfunction "AVSS")
			(pintype "passive")
		)
		(pad "G1" smd circle
			(at -10.25 -4.76 270)
			(size 0.5 0.5)
			(layers "F.Cu" "F.Mask" "F.Paste")
			(net 138 "/X710-AT2 Misc/NCSI.TXD_1")
			(pinfunction "NCSI_TXD_1")
			(pintype "input")
		)
		(pad "G3" smd circle
			(at -9.25 -4.76 270)
			(size 0.5 0.5)
			(layers "F.Cu" "F.Mask" "F.Paste")
			(net 145 "/X710-AT2 Misc/NCSI.ARB_IN")
			(pinfunction "NCSI_ARB_IN")
			(pintype "input")
		)
		(pad "G5" smd circle
			(at -8.25 -4.76 270)
			(size 0.5 0.5)
			(layers "F.Cu" "F.Mask" "F.Paste")
			(net 121 "/X710-AT2 10GbE/~{P0_INT_R}")
			(pinfunction "SDP0_1")
			(pintype "tri_state")
		)
		(pad "G7" smd circle
			(at -7.25 -4.76 270)
			(size 0.5 0.5)
			(layers "F.Cu" "F.Mask" "F.Paste")
			(net 550 "unconnected-(U14C-SDP2_3-PadG7)")
			(pinfunction "SDP2_3")
			(pintype "passive+no_connect")
		)
		(pad "G9" smd circle
			(at -6.25 -4.76 270)
			(size 0.5 0.5)
			(layers "F.Cu" "F.Mask" "F.Paste")
			(net 555 "unconnected-(U14F-SYNCE_CLKOUT_0-PadG9)")
			(pinfunction "SYNCE_CLKOUT_0")
			(pintype "output+no_connect")
		)
		(pad "G11" smd circle
			(at -5.25 -4.76 270)
			(size 0.5 0.5)
			(layers "F.Cu" "F.Mask" "F.Paste")
			(net 567 "unconnected-(U14F-SYNCE_CLKOUT_2-PadG11)")
			(pinfunction "SYNCE_CLKOUT_2")
			(pintype "output+no_connect")
		)
		(pad "G13" smd circle
			(at -4.25 -4.76 270)
			(size 0.5 0.5)
			(layers "F.Cu" "F.Mask" "F.Paste")
			(net 575 "unconnected-(U14F-RSVDG13_NC-PadG13)")
			(pinfunction "RSVDG13_NC")
			(pintype "passive+no_connect")
		)
		(pad "G15" smd circle
			(at -3.25 -4.76 270)
			(size 0.5 0.5)
			(layers "F.Cu" "F.Mask" "F.Paste")
			(net 541 "unconnected-(U14F-RSVDG15_NC-PadG15)")
			(pinfunction "RSVDG15_NC")
			(pintype "passive+no_connect")
		)
		(pad "G17" smd circle
			(at -2.25 -4.76 270)
			(size 0.5 0.5)
			(layers "F.Cu" "F.Mask" "F.Paste")
			(net 131 "/X710-AT2 10GbE/TPIN_5")
			(pinfunction "TPIN_5")
			(pintype "passive")
		)
		(pad "G19" smd circle
			(at -1.25 -4.76 270)
			(size 0.5 0.5)
			(layers "F.Cu" "F.Mask" "F.Paste")
			(net 23 "GND")
			(pinfunction "RSVDG19_VSS")
			(pintype "passive")
		)
		(pad "G21" smd circle
			(at -0.25 -4.76 270)
			(size 0.5 0.5)
			(layers "F.Cu" "F.Mask" "F.Paste")
			(net 23 "GND")
			(pinfunction "RSVDG21_VSS")
			(pintype "passive")
		)
		(pad "G23" smd circle
			(at 0.75 -4.76 270)
			(size 0.5 0.5)
			(layers "F.Cu" "F.Mask" "F.Paste")
			(net 23 "GND")
			(pinfunction "RSVDG23_VSS")
			(pintype "passive")
		)
		(pad "G25" smd circle
			(at 1.75 -4.76 270)
			(size 0.5 0.5)
			(layers "F.Cu" "F.Mask" "F.Paste")
			(net 18 "+1V88")
			(pinfunction "VDDIO1")
			(pintype "power_in")
		)
		(pad "G27" smd circle
			(at 2.75 -4.76 270)
			(size 0.5 0.5)
			(layers "F.Cu" "F.Mask" "F.Paste")
			(net 6 "DVDD")
			(pinfunction "DVDD")
			(pintype "power_in")
		)
		(pad "G29" smd circle
			(at 3.75 -4.76 270)
			(size 0.5 0.5)
			(layers "F.Cu" "F.Mask" "F.Paste")
			(net 6 "DVDD")
			(pinfunction "DVDD")
			(pintype "passive")
		)
		(pad "G31" smd circle
			(at 4.75 -4.76 270)
			(size 0.5 0.5)
			(layers "F.Cu" "F.Mask" "F.Paste")
			(net 6 "DVDD")
			(pinfunction "DVDD")
			(pintype "passive")
		)
		(pad "G33" smd circle
			(at 5.75 -4.76 270)
			(size 0.5 0.5)
			(layers "F.Cu" "F.Mask" "F.Paste")
			(net 6 "DVDD")
			(pinfunction "DVDD")
			(pintype "passive")
		)
		(pad "G35" smd circle
			(at 6.75 -4.76 270)
			(size 0.5 0.5)
			(layers "F.Cu" "F.Mask" "F.Paste")
			(net 6 "DVDD")
			(pinfunction "DVDD")
			(pintype "passive")
		)
		(pad "G37" smd circle
			(at 7.75 -4.76 270)
			(size 0.5 0.5)
			(layers "F.Cu" "F.Mask" "F.Paste")
			(net 18 "+1V88")
			(pinfunction "VDDIO1")
			(pintype "passive")
		)
		(pad "G39" smd circle
			(at 8.75 -4.76 270)
			(size 0.5 0.5)
			(layers "F.Cu" "F.Mask" "F.Paste")
			(net 22 "PLL_VDD")
			(pinfunction "PLL_VDD")
			(pintype "power_in")
		)
		(pad "G41" smd circle
			(at 9.75 -4.76 270)
			(size 0.5 0.5)
			(layers "F.Cu" "F.Mask" "F.Paste")
			(net 23 "GND")
			(pinfunction "AVSS")
			(pintype "passive")
		)
		(pad "H2" smd circle
			(at -9.75 -3.895 270)
			(size 0.5 0.5)
			(layers "F.Cu" "F.Mask" "F.Paste")
			(net 144 "/X710-AT2 Misc/NCSI.REF_CLK")
			(pinfunction "NCSI_CLK_IN")
			(pintype "input")
		)
		(pad "H4" smd circle
			(at -8.75 -3.895 270)
			(size 0.5 0.5)
			(layers "F.Cu" "F.Mask" "F.Paste")
			(net 143 "/X710-AT2 Misc/NCSI.TX_EN")
			(pinfunction "NCSI_TX_EN")
			(pintype "input")
		)
		(pad "H6" smd circle
			(at -7.75 -3.895 270)
			(size 0.5 0.5)
			(layers "F.Cu" "F.Mask" "F.Paste")
			(net 486 "unconnected-(U14C-SDP1_3-PadH6)")
			(pinfunction "SDP1_3")
			(pintype "passive+no_connect")
		)
		(pad "H8" smd circle
			(at -6.75 -3.895 270)
			(size 0.5 0.5)
			(layers "F.Cu" "F.Mask" "F.Paste")
			(net 551 "unconnected-(U14D-GPIO_4-PadH8)")
			(pinfunction "GPIO_4")
			(pintype "passive+no_connect")
		)
		(pad "H10" smd circle
			(at -5.75 -3.895 270)
			(size 0.5 0.5)
			(layers "F.Cu" "F.Mask" "F.Paste")
			(net 558 "unconnected-(U14F-P1_PTP_SYNC0-PadH10)")
			(pinfunction "P1_PTP_SYNC0")
			(pintype "passive+no_connect")
		)
		(pad "H12" smd circle
			(at -4.75 -3.895 270)
			(size 0.5 0.5)
			(layers "F.Cu" "F.Mask" "F.Paste")
			(net 561 "unconnected-(U14F-P1_PTP_SYNC1-PadH12)")
			(pinfunction "P1_PTP_SYNC1")
			(pintype "passive+no_connect")
		)
		(pad "H14" smd circle
			(at -3.75 -3.895 270)
			(size 0.5 0.5)
			(layers "F.Cu" "F.Mask" "F.Paste")
			(net 459 "unconnected-(U14F-RSVDH14_NC-PadH14)")
			(pinfunction "RSVDH14_NC")
			(pintype "passive+no_connect")
		)
		(pad "H16" smd circle
			(at -2.75 -3.895 270)
			(size 0.5 0.5)
			(layers "F.Cu" "F.Mask" "F.Paste")
			(net 586 "unconnected-(U14F-RSVDH16_NC-PadH16)")
			(pinfunction "RSVDH16_NC")
			(pintype "passive+no_connect")
		)
		(pad "H18" smd circle
			(at -1.75 -3.895 270)
			(size 0.5 0.5)
			(layers "F.Cu" "F.Mask" "F.Paste")
			(net 23 "GND")
			(pinfunction "RSVH18_VSS")
			(pintype "passive")
		)
		(pad "H20" smd circle
			(at -0.75 -3.895 270)
			(size 0.5 0.5)
			(layers "F.Cu" "F.Mask" "F.Paste")
			(net 130 "/X710-AT2 10GbE/TPIN_3")
			(pinfunction "TPIN_3")
			(pintype "passive")
		)
		(pad "H22" smd circle
			(at 0.25 -3.895 270)
			(size 0.5 0.5)
			(layers "F.Cu" "F.Mask" "F.Paste")
			(net 23 "GND")
			(pinfunction "RSVDH22_VSS")
			(pintype "passive")
		)
		(pad "H24" smd circle
			(at 1.25 -3.895 270)
			(size 0.5 0.5)
			(layers "F.Cu" "F.Mask" "F.Paste")
			(net 23 "GND")
			(pinfunction "RSVDH24_VSS")
			(pintype "passive")
		)
		(pad "H26" smd circle
			(at 2.25 -3.895 270)
			(size 0.5 0.5)
			(layers "F.Cu" "F.Mask" "F.Paste")
			(net 23 "GND")
			(pinfunction "VSSA")
			(pintype "passive")
		)
		(pad "H28" smd circle
			(at 3.25 -3.895 270)
			(size 0.5 0.5)
			(layers "F.Cu" "F.Mask" "F.Paste")
			(net 23 "GND")
			(pinfunction "VSSA")
			(pintype "passive")
		)
		(pad "H30" smd circle
			(at 4.25 -3.895 270)
			(size 0.5 0.5)
			(layers "F.Cu" "F.Mask" "F.Paste")
			(net 23 "GND")
			(pinfunction "VSSA")
			(pintype "passive")
		)
		(pad "H32" smd circle
			(at 5.25 -3.895 270)
			(size 0.5 0.5)
			(layers "F.Cu" "F.Mask" "F.Paste")
			(net 23 "GND")
			(pinfunction "VSSA")
			(pintype "passive")
		)
		(pad "H34" smd circle
			(at 6.25 -3.895 270)
			(size 0.5 0.5)
			(layers "F.Cu" "F.Mask" "F.Paste")
			(net 23 "GND")
			(pinfunction "VSSA")
			(pintype "passive")
		)
		(pad "H36" smd circle
			(at 7.25 -3.895 270)
			(size 0.5 0.5)
			(layers "F.Cu" "F.Mask" "F.Paste")
			(net 23 "GND")
			(pinfunction "VSSA")
			(pintype "passive")
		)
		(pad "H38" smd circle
			(at 8.25 -3.895 270)
			(size 0.5 0.5)
			(layers "F.Cu" "F.Mask" "F.Paste")
			(net 23 "GND")
			(pinfunction "VSSA")
			(pintype "passive")
		)
		(pad "H40" smd circle
			(at 9.25 -3.895 270)
			(size 0.5 0.5)
			(layers "F.Cu" "F.Mask" "F.Paste")
			(net 23 "GND")
			(pinfunction "RSVDH40_VSS")
			(pintype "passive")
		)
		(pad "H42" smd circle
			(at 10.25 -3.895 270)
			(size 0.5 0.5)
			(layers "F.Cu" "F.Mask" "F.Paste")
			(net 453 "unconnected-(U14F-XTAL_PTP_XTAL_N-PadH42)")
			(pinfunction "XTAL_PTP_XTAL_N")
			(pintype "passive+no_connect")
		)
		(pad "J1" smd circle
			(at -10.25 -3.03 270)
			(size 0.5 0.5)
			(layers "F.Cu" "F.Mask" "F.Paste")
			(net 442 "Net-(U14D-NCSI_RXD_0)")
			(pinfunction "NCSI_RXD_0")
			(pintype "output")
		)
		(pad "J3" smd circle
			(at -9.25 -3.03 270)
			(size 0.5 0.5)
			(layers "F.Cu" "F.Mask" "F.Paste")
			(net 443 "Net-(U14D-NCSI_RXD_1)")
			(pinfunction "NCSI_RXD_1")
			(pintype "output")
		)
		(pad "J5" smd circle
			(at -8.25 -3.03 270)
			(size 0.5 0.5)
			(layers "F.Cu" "F.Mask" "F.Paste")
			(net 441 "Net-(U14D-NCSI_CRS_DV)")
			(pinfunction "NCSI_CRS_DV")
			(pintype "output")
		)
		(pad "J7" smd circle
			(at -7.25 -3.03 270)
			(size 0.5 0.5)
			(layers "F.Cu" "F.Mask" "F.Paste")
			(net 468 "unconnected-(U14C-SDP2_1-PadJ7)")
			(pinfunction "SDP2_1")
			(pintype "passive+no_connect")
		)
		(pad "J9" smd circle
			(at -6.25 -3.03 270)
			(size 0.5 0.5)
			(layers "F.Cu" "F.Mask" "F.Paste")
			(net 64 "/X710-AT2 10GbE/OSC_SEL")
			(pinfunction "OSC_SEL")
			(pintype "tri_state")
		)
		(pad "J11" smd circle
			(at -5.25 -3.03 270)
			(size 0.5 0.5)
			(layers "F.Cu" "F.Mask" "F.Paste")
			(net 87 "/X710-AT2 Misc/RSVD_J11_VSS")
			(pinfunction "RSVD_J11_VSS")
			(pintype "passive")
		)
		(pad "J13" smd circle
			(at -4.25 -3.03 270)
			(size 0.5 0.5)
			(layers "F.Cu" "F.Mask" "F.Paste")
			(net 23 "GND")
			(pinfunction "RSVDJ13_VSS")
			(pintype "passive")
		)
		(pad "J15" smd circle
			(at -3.25 -3.03 270)
			(size 0.5 0.5)
			(layers "F.Cu" "F.Mask" "F.Paste")
			(net 534 "unconnected-(U14F-RSVDJ15_NC-PadJ15)")
			(pinfunction "RSVDJ15_NC")
			(pintype "passive+no_connect")
		)
		(pad "J17" smd circle
			(at -2.25 -3.03 270)
			(size 0.5 0.5)
			(layers "F.Cu" "F.Mask" "F.Paste")
			(net 23 "GND")
			(pinfunction "RSVDJ17_VSS")
			(pintype "passive")
		)
		(pad "J19" smd circle
			(at -1.25 -3.03 270)
			(size 0.5 0.5)
			(layers "F.Cu" "F.Mask" "F.Paste")
			(net 23 "GND")
			(pinfunction "RSVDJ19_VSS")
			(pintype "passive")
		)
		(pad "J21" smd circle
			(at -0.25 -3.03 270)
			(size 0.5 0.5)
			(layers "F.Cu" "F.Mask" "F.Paste")
			(net 23 "GND")
			(pinfunction "RSVDJ21_VSS")
			(pintype "passive")
		)
		(pad "J23" smd circle
			(at 0.75 -3.03 270)
			(size 0.5 0.5)
			(layers "F.Cu" "F.Mask" "F.Paste")
			(net 556 "unconnected-(U14E-RSVDJ23_NC-PadJ23)")
			(pinfunction "RSVDJ23_NC")
			(pintype "passive+no_connect")
		)
		(pad "J25" smd circle
			(at 1.75 -3.03 270)
			(size 0.5 0.5)
			(layers "F.Cu" "F.Mask" "F.Paste")
			(net 480 "unconnected-(U14E-RSVDJ25_NC-PadJ25)")
			(pinfunction "RSVDJ25_NC")
			(pintype "passive+no_connect")
		)
		(pad "J27" smd circle
			(at 2.75 -3.03 270)
			(size 0.5 0.5)
			(layers "F.Cu" "F.Mask" "F.Paste")
			(net 12 "XFI_VDD")
			(pinfunction "XFI_VDD")
			(pintype "power_in")
		)
		(pad "J29" smd circle
			(at 3.75 -3.03 270)
			(size 0.5 0.5)
			(layers "F.Cu" "F.Mask" "F.Paste")
			(net 12 "XFI_VDD")
			(pinfunction "XFI_VDD")
			(pintype "passive")
		)
		(pad "J31" smd circle
			(at 4.75 -3.03 270)
			(size 0.5 0.5)
			(layers "F.Cu" "F.Mask" "F.Paste")
			(net 12 "XFI_VDD")
			(pinfunction "XFI_VDD")
			(pintype "passive")
		)
		(pad "J33" smd circle
			(at 5.75 -3.03 270)
			(size 0.5 0.5)
			(layers "F.Cu" "F.Mask" "F.Paste")
			(net 21 "XFI_PVDD")
			(pinfunction "XFI_PVDD")
			(pintype "power_in")
		)
		(pad "J35" smd circle
			(at 6.75 -3.03 270)
			(size 0.5 0.5)
			(layers "F.Cu" "F.Mask" "F.Paste")
			(net 12 "XFI_VDD")
			(pinfunction "XFI_VDD")
			(pintype "passive")
		)
		(pad "J37" smd circle
			(at 7.75 -3.03 270)
			(size 0.5 0.5)
			(layers "F.Cu" "F.Mask" "F.Paste")
			(net 62 "/X710-AT2 10GbE/RESCAL_RES_P")
			(pinfunction "RESCAL_RES_P")
			(pintype "passive")
		)
		(pad "J39" smd circle
			(at 8.75 -3.03 270)
			(size 0.5 0.5)
			(layers "F.Cu" "F.Mask" "F.Paste")
			(net 528 "unconnected-(U14G-RSVDJ39_NC-PadJ39)")
			(pinfunction "RSVDJ39_NC")
			(pintype "passive+no_connect")
		)
		(pad "J41" smd circle
			(at 9.75 -3.03 270)
			(size 0.5 0.5)
			(layers "F.Cu" "F.Mask" "F.Paste")
			(net 526 "unconnected-(U14F-XTAL_PTP_XTAL_P-PadJ41)")
			(pinfunction "XTAL_PTP_XTAL_P")
			(pintype "passive+no_connect")
		)
		(pad "K2" smd circle
			(at -9.75 -2.165 270)
			(size 0.5 0.5)
			(layers "F.Cu" "F.Mask" "F.Paste")
			(net 71 "/X710-AT2 10GbE/MDIO3_SDA3")
			(pinfunction "MDIO3_SDA3")
			(pintype "passive")
		)
		(pad "K4" smd circle
			(at -8.75 -2.165 270)
			(size 0.5 0.5)
			(layers "F.Cu" "F.Mask" "F.Paste")
			(net 70 "/X710-AT2 10GbE/MDC3_SCL3")
			(pinfunction "MDC3_SCL3")
			(pintype "passive")
		)
		(pad "K6" smd circle
			(at -7.75 -2.165 270)
			(size 0.5 0.5)
			(layers "F.Cu" "F.Mask" "F.Paste")
			(net 123 "/X710-AT2 10GbE/~{P1_INT_R}")
			(pinfunction "SDP0_2")
			(pintype "tri_state")
		)
		(pad "K8" smd circle
			(at -6.75 -2.165 270)
			(size 0.5 0.5)
			(layers "F.Cu" "F.Mask" "F.Paste")
			(net 23 "GND")
			(pinfunction "VSSA")
			(pintype "passive")
		)
		(pad "K10" smd circle
			(at -5.75 -2.165 270)
			(size 0.5 0.5)
			(layers "F.Cu" "F.Mask" "F.Paste")
			(net 23 "GND")
			(pinfunction "VSSA")
			(pintype "passive")
		)
		(pad "K12" smd circle
			(at -4.75 -2.165 270)
			(size 0.5 0.5)
			(layers "F.Cu" "F.Mask" "F.Paste")
			(net 23 "GND")
			(pinfunction "VSSA")
			(pintype "passive")
		)
		(pad "K14" smd circle
			(at -3.75 -2.165 270)
			(size 0.5 0.5)
			(layers "F.Cu" "F.Mask" "F.Paste")
			(net 23 "GND")
			(pinfunction "VSSA")
			(pintype "passive")
		)
		(pad "K16" smd circle
			(at -2.75 -2.165 270)
			(size 0.5 0.5)
			(layers "F.Cu" "F.Mask" "F.Paste")
			(net 23 "GND")
			(pinfunction "VSSA")
			(pintype "passive")
		)
		(pad "K18" smd circle
			(at -1.75 -2.165 270)
			(size 0.5 0.5)
			(layers "F.Cu" "F.Mask" "F.Paste")
			(net 23 "GND")
			(pinfunction "VSS")
			(pintype "passive")
		)
		(pad "K20" smd circle
			(at -0.75 -2.165 270)
			(size 0.5 0.5)
			(layers "F.Cu" "F.Mask" "F.Paste")
			(net 23 "GND")
			(pinfunction "VSS")
			(pintype "passive")
		)
		(pad "K22" smd circle
			(at 0.25 -2.165 270)
			(size 0.5 0.5)
			(layers "F.Cu" "F.Mask" "F.Paste")
			(net 540 "unconnected-(U14E-RSVDK22_NC-PadK22)")
			(pinfunction "RSVDK22_NC")
			(pintype "passive+no_connect")
		)
		(pad "K24" smd circle
			(at 1.25 -2.165 270)
			(size 0.5 0.5)
			(layers "F.Cu" "F.Mask" "F.Paste")
			(net 499 "unconnected-(U14E-RSVDK24_NC-PadK24)")
			(pinfunction "RSVDK24_NC")
			(pintype "passive+no_connect")
		)
		(pad "K26" smd circle
			(at 2.25 -2.165 270)
			(size 0.5 0.5)
			(layers "F.Cu" "F.Mask" "F.Paste")
			(net 585 "unconnected-(U14G-RSVDK26_NC-PadK26)")
			(pinfunction "RSVDK26_NC")
			(pintype "passive+no_connect")
		)
		(pad "K28" smd circle
			(at 3.25 -2.165 270)
			(size 0.5 0.5)
			(layers "F.Cu" "F.Mask" "F.Paste")
			(net 466 "unconnected-(U14G-RSVDK28_NC-PadK28)")
			(pinfunction "RSVDK28_NC")
			(pintype "passive+no_connect")
		)
		(pad "K30" smd circle
			(at 4.25 -2.165 270)
			(size 0.5 0.5)
			(layers "F.Cu" "F.Mask" "F.Paste")
			(net 470 "unconnected-(U14F-RSVDK30_NC-PadK30)")
			(pinfunction "RSVDK30_NC")
			(pintype "passive+no_connect")
		)
		(pad "K32" smd circle
			(at 5.25 -2.165 270)
			(size 0.5 0.5)
			(layers "F.Cu" "F.Mask" "F.Paste")
			(net 546 "unconnected-(U14F-RSVDK32_NC-PadK32)")
			(pinfunction "RSVDK32_NC")
			(pintype "passive+no_connect")
		)
		(pad "K34" smd circle
			(at 6.25 -2.165 270)
			(size 0.5 0.5)
			(layers "F.Cu" "F.Mask" "F.Paste")
			(net 498 "unconnected-(U14G-RSVDK34_NC-PadK34)")
			(pinfunction "RSVDK34_NC")
			(pintype "passive+no_connect")
		)
		(pad "K36" smd circle
			(at 7.25 -2.165 270)
			(size 0.5 0.5)
			(layers "F.Cu" "F.Mask" "F.Paste")
			(net 476 "unconnected-(U14G-RSVDK36_NC-PadK36)")
			(pinfunction "RSVDK36_NC")
			(pintype "passive+no_connect")
		)
		(pad "K38" smd circle
			(at 8.25 -2.165 270)
			(size 0.5 0.5)
			(layers "F.Cu" "F.Mask" "F.Paste")
			(net 23 "GND")
			(pinfunction "VSSA")
			(pintype "passive")
		)
		(pad "K40" smd circle
			(at 9.25 -2.165 270)
			(size 0.5 0.5)
			(layers "F.Cu" "F.Mask" "F.Paste")
			(net 85 "/X710-AT2 Misc/RSVDK40_1P88V")
			(pinfunction "RSVDK40_1P88V")
			(pintype "passive")
		)
		(pad "K42" smd circle
			(at 10.25 -2.165 270)
			(size 0.5 0.5)
			(layers "F.Cu" "F.Mask" "F.Paste")
			(net 23 "GND")
			(pinfunction "RSVDK42_VSS")
			(pintype "passive")
		)
		(pad "L1" smd circle
			(at -10.25 -1.3 270)
			(size 0.5 0.5)
			(layers "F.Cu" "F.Mask" "F.Paste")
			(net 76 "/X710-AT2 10GbE/MDIO2_SDA2")
			(pinfunction "MDIO2_SDA2")
			(pintype "passive")
		)
		(pad "L3" smd circle
			(at -9.25 -1.3 270)
			(size 0.5 0.5)
			(layers "F.Cu" "F.Mask" "F.Paste")
			(net 72 "/X710-AT2 10GbE/MDC2_SCL2")
			(pinfunction "MDC2_SCL2")
			(pintype "passive")
		)
		(pad "L5" smd circle
			(at -8.25 -1.3 270)
			(size 0.5 0.5)
			(layers "F.Cu" "F.Mask" "F.Paste")
			(net 580 "unconnected-(U14C-SDP0_3-PadL5)")
			(pinfunction "SDP0_3")
			(pintype "passive+no_connect")
		)
		(pad "L7" smd circle
			(at -7.25 -1.3 270)
			(size 0.5 0.5)
			(layers "F.Cu" "F.Mask" "F.Paste")
			(net 82 "/X710-AT2 Misc/GPIO5_POR_BYPASS")
			(pinfunction "GPIO_5")
			(pintype "tri_state")
		)
		(pad "L9" smd circle
			(at -6.25 -1.3 270)
			(size 0.5 0.5)
			(layers "F.Cu" "F.Mask" "F.Paste")
			(net 7 "+3V3")
			(pinfunction "VCC3P3_TX")
			(pintype "power_in")
		)
		(pad "L11" smd circle
			(at -5.25 -1.3 270)
			(size 0.5 0.5)
			(layers "F.Cu" "F.Mask" "F.Paste")
			(net 1 "VCCA")
			(pinfunction "VCCA")
			(pintype "power_in")
		)
		(pad "L13" smd circle
			(at -4.25 -1.3 270)
			(size 0.5 0.5)
			(layers "F.Cu" "F.Mask" "F.Paste")
			(net 1 "VCCA")
			(pinfunction "VCCA")
			(pintype "passive")
		)
		(pad "L15" smd circle
			(at -3.25 -1.3 270)
			(size 0.5 0.5)
			(layers "F.Cu" "F.Mask" "F.Paste")
			(net 1 "VCCA")
			(pinfunction "VCCA")
			(pintype "passive")
		)
		(pad "L17" smd circle
			(at -2.25 -1.3 270)
			(size 0.5 0.5)
			(layers "F.Cu" "F.Mask" "F.Paste")
			(net 1 "VCCA")
			(pinfunction "VCCA")
			(pintype "passive")
		)
		(pad "L19" smd circle
			(at -1.25 -1.3 270)
			(size 0.5 0.5)
			(layers "F.Cu" "F.Mask" "F.Paste")
			(net 9 "VCCD")
			(pinfunction "VCCD")
			(pintype "power_in")
		)
		(pad "L21" smd circle
			(at -0.25 -1.3 270)
			(size 0.5 0.5)
			(layers "F.Cu" "F.Mask" "F.Paste")
			(net 9 "VCCD")
			(pinfunction "VCCD")
			(pintype "passive")
		)
		(pad "L23" smd circle
			(at 0.75 -1.3 270)
			(size 0.5 0.5)
			(layers "F.Cu" "F.Mask" "F.Paste")
			(net 542 "unconnected-(U14E-RSVDL23_NC-PadL23)")
			(pinfunction "RSVDL23_NC")
			(pintype "passive+no_connect")
		)
		(pad "L25" smd circle
			(at 1.75 -1.3 270)
			(size 0.5 0.5)
			(layers "F.Cu" "F.Mask" "F.Paste")
			(net 515 "unconnected-(U14E-RSVDL25_NC-PadL25)")
			(pinfunction "RSVDL25_NC")
			(pintype "passive+no_connect")
		)
		(pad "L27" smd circle
			(at 2.75 -1.3 270)
			(size 0.5 0.5)
			(layers "F.Cu" "F.Mask" "F.Paste")
			(net 505 "unconnected-(U14E-RSVDL27_NC-PadL27)")
			(pinfunction "RSVDL27_NC")
			(pintype "passive+no_connect")
		)
		(pad "L29" smd circle
			(at 3.75 -1.3 270)
			(size 0.5 0.5)
			(layers "F.Cu" "F.Mask" "F.Paste")
			(net 521 "unconnected-(U14G-RSVDL29_NC-PadL29)")
			(pinfunction "RSVDL29_NC")
			(pintype "passive+no_connect")
		)
		(pad "L31" smd circle
			(at 4.75 -1.3 270)
			(size 0.5 0.5)
			(layers "F.Cu" "F.Mask" "F.Paste")
			(net 23 "GND")
			(pinfunction "RSVDL31_VSS")
			(pintype "passive")
		)
		(pad "L33" smd circle
			(at 5.75 -1.3 270)
			(size 0.5 0.5)
			(layers "F.Cu" "F.Mask" "F.Paste")
			(net 84 "/X710-AT2 Misc/RSVDL33")
			(pinfunction "RSVDL33")
			(pintype "passive")
		)
		(pad "L35" smd circle
			(at 6.75 -1.3 270)
			(size 0.5 0.5)
			(layers "F.Cu" "F.Mask" "F.Paste")
			(net 484 "unconnected-(U14F-RSVDL35_NC-PadL35)")
			(pinfunction "RSVDL35_NC")
			(pintype "passive+no_connect")
		)
		(pad "L37" smd circle
			(at 7.75 -1.3 270)
			(size 0.5 0.5)
			(layers "F.Cu" "F.Mask" "F.Paste")
			(net 23 "GND")
			(pinfunction "RSVDL37_VSS")
			(pintype "passive")
		)
		(pad "L39" smd circle
			(at 8.75 -1.3 270)
			(size 0.5 0.5)
			(layers "F.Cu" "F.Mask" "F.Paste")
			(net 18 "+1V88")
			(pinfunction "VDDIO2")
			(pintype "power_in")
		)
		(pad "L41" smd circle
			(at 9.75 -1.3 270)
			(size 0.5 0.5)
			(layers "F.Cu" "F.Mask" "F.Paste")
			(net 148 "/X710-AT2 Misc/MDIO.MDC")
			(pinfunction "MDC")
			(pintype "input")
		)
		(pad "M2" smd circle
			(at -9.75 -0.435 270)
			(size 0.5 0.5)
			(layers "F.Cu" "F.Mask" "F.Paste")
			(net 78 "/X710-AT2 10GbE/MDIO1_SDA1")
			(pinfunction "MDIO1_SDA1")
			(pintype "passive")
		)
		(pad "M4" smd circle
			(at -8.75 -0.435 270)
			(size 0.5 0.5)
			(layers "F.Cu" "F.Mask" "F.Paste")
			(net 77 "/X710-AT2 10GbE/MDC1_SCL1")
			(pinfunction "MDC1_SCL1")
			(pintype "passive")
		)
		(pad "M6" smd circle
			(at -7.75 -0.435 270)
			(size 0.5 0.5)
			(layers "F.Cu" "F.Mask" "F.Paste")
			(net 495 "unconnected-(U14C-SDP3_2-PadM6)")
			(pinfunction "SDP3_2")
			(pintype "passive+no_connect")
		)
		(pad "M8" smd circle
			(at -6.75 -0.435 270)
			(size 0.5 0.5)
			(layers "F.Cu" "F.Mask" "F.Paste")
			(net 513 "unconnected-(U14C-SDP3_3-PadM8)")
			(pinfunction "SDP3_3")
			(pintype "passive+no_connect")
		)
		(pad "M10" smd circle
			(at -5.75 -0.435 270)
			(size 0.5 0.5)
			(layers "F.Cu" "F.Mask" "F.Paste")
			(net 23 "GND")
			(pinfunction "VSSA")
			(pintype "passive")
		)
		(pad "M12" smd circle
			(at -4.75 -0.435 270)
			(size 0.5 0.5)
			(layers "F.Cu" "F.Mask" "F.Paste")
			(net 23 "GND")
			(pinfunction "VSSA")
			(pintype "passive")
		)
		(pad "M14" smd circle
			(at -3.75 -0.435 270)
			(size 0.5 0.5)
			(layers "F.Cu" "F.Mask" "F.Paste")
			(net 23 "GND")
			(pinfunction "VSSA")
			(pintype "passive")
		)
		(pad "M16" smd circle
			(at -2.75 -0.435 270)
			(size 0.5 0.5)
			(layers "F.Cu" "F.Mask" "F.Paste")
			(net 23 "GND")
			(pinfunction "VSSA")
			(pintype "passive")
		)
		(pad "M18" smd circle
			(at -1.75 -0.435 270)
			(size 0.5 0.5)
			(layers "F.Cu" "F.Mask" "F.Paste")
			(net 23 "GND")
			(pinfunction "VSS")
			(pintype "passive")
		)
		(pad "M20" smd circle
			(at -0.75 -0.435 270)
			(size 0.5 0.5)
			(layers "F.Cu" "F.Mask" "F.Paste")
			(net 23 "GND")
			(pinfunction "VSS")
			(pintype "passive")
		)
		(pad "M22" smd circle
			(at 0.25 -0.435 270)
			(size 0.5 0.5)
			(layers "F.Cu" "F.Mask" "F.Paste")
			(net 549 "unconnected-(U14E-RSVDM22_NC-PadM22)")
			(pinfunction "RSVDM22_NC")
			(pintype "passive+no_connect")
		)
		(pad "M24" smd circle
			(at 1.25 -0.435 270)
			(size 0.5 0.5)
			(layers "F.Cu" "F.Mask" "F.Paste")
			(net 564 "unconnected-(U14E-RSVDM24_NC-PadM24)")
			(pinfunction "RSVDM24_NC")
			(pintype "passive+no_connect")
		)
		(pad "M26" smd circle
			(at 2.25 -0.435 270)
			(size 0.5 0.5)
			(layers "F.Cu" "F.Mask" "F.Paste")
			(net 460 "unconnected-(U14E-RSVDM26_NC-PadM26)")
			(pinfunction "RSVDM26_NC")
			(pintype "passive+no_connect")
		)
		(pad "M28" smd circle
			(at 3.25 -0.435 270)
			(size 0.5 0.5)
			(layers "F.Cu" "F.Mask" "F.Paste")
			(net 494 "unconnected-(U14E-RSVDM28_NC-PadM28)")
			(pinfunction "RSVDM28_NC")
			(pintype "passive+no_connect")
		)
		(pad "M30" smd circle
			(at 4.25 -0.435 270)
			(size 0.5 0.5)
			(layers "F.Cu" "F.Mask" "F.Paste")
			(net 560 "unconnected-(U14G-RSVDM30_NC-PadM30)")
			(pinfunction "RSVDM30_NC")
			(pintype "passive+no_connect")
		)
		(pad "M32" smd circle
			(at 5.25 -0.435 270)
			(size 0.5 0.5)
			(layers "F.Cu" "F.Mask" "F.Paste")
			(net 570 "unconnected-(U14G-RSVDM32_NC-PadM32)")
			(pinfunction "RSVDM32_NC")
			(pintype "passive+no_connect")
		)
		(pad "M34" smd circle
			(at 6.25 -0.435 270)
			(size 0.5 0.5)
			(layers "F.Cu" "F.Mask" "F.Paste")
			(net 464 "unconnected-(U14F-RSVDM34_NC-PadM34)")
			(pinfunction "RSVDM34_NC")
			(pintype "passive+no_connect")
		)
		(pad "M36" smd circle
			(at 7.25 -0.435 270)
			(size 0.5 0.5)
			(layers "F.Cu" "F.Mask" "F.Paste")
			(net 472 "unconnected-(U14F-RSVDM36_NC-PadM36)")
			(pinfunction "RSVDM36_NC")
			(pintype "passive+no_connect")
		)
		(pad "M38" smd circle
			(at 8.25 -0.435 270)
			(size 0.5 0.5)
			(layers "F.Cu" "F.Mask" "F.Paste")
			(net 18 "+1V88")
			(pinfunction "VDDP2")
			(pintype "power_in")
		)
		(pad "M40" smd circle
			(at 9.25 -0.435 270)
			(size 0.5 0.5)
			(layers "F.Cu" "F.Mask" "F.Paste")
			(net 111 "/X710-AT2 10GbE/~{P0_INT}")
			(pinfunction "P0_INT_MLC")
			(pintype "passive")
		)
		(pad "M42" smd circle
			(at 10.25 -0.435 270)
			(size 0.5 0.5)
			(layers "F.Cu" "F.Mask" "F.Paste")
			(net 147 "/X710-AT2 Misc/MDIO.MDIO")
			(pinfunction "MDIO")
			(pintype "bidirectional")
		)
		(pad "N1" smd circle
			(at -10.25 0.43 270)
			(size 0.5 0.5)
			(layers "F.Cu" "F.Mask" "F.Paste")
			(net 102 "/X710-AT2 10GbE/MDIO0_SDA0")
			(pinfunction "MDIO0_SDA0")
			(pintype "bidirectional")
		)
		(pad "N3" smd circle
			(at -9.25 0.43 270)
			(size 0.5 0.5)
			(layers "F.Cu" "F.Mask" "F.Paste")
			(net 100 "/X710-AT2 10GbE/MDC0_SCL0")
			(pinfunction "MDC0_SCL0")
			(pintype "output")
		)
		(pad "N5" smd circle
			(at -8.25 0.43 270)
			(size 0.5 0.5)
			(layers "F.Cu" "F.Mask" "F.Paste")
			(net 574 "unconnected-(U14C-SDP3_0-PadN5)")
			(pinfunction "SDP3_0")
			(pintype "passive+no_connect")
		)
		(pad "N7" smd circle
			(at -7.25 0.43 270)
			(size 0.5 0.5)
			(layers "F.Cu" "F.Mask" "F.Paste")
			(net 496 "unconnected-(U14C-SDP3_1-PadN7)")
			(pinfunction "SDP3_1")
			(pintype "passive+no_connect")
		)
		(pad "N9" smd circle
			(at -6.25 0.43 270)
			(size 0.5 0.5)
			(layers "F.Cu" "F.Mask" "F.Paste")
			(net 95 "/X710-AT2 RSVD/RSVDN9_VSS")
			(pinfunction "RSVDN9_VSS")
			(pintype "passive")
		)
		(pad "N11" smd circle
			(at -5.25 0.43 270)
			(size 0.5 0.5)
			(layers "F.Cu" "F.Mask" "F.Paste")
			(net 1 "VCCA")
			(pinfunction "VCCA")
			(pintype "passive")
		)
		(pad "N13" smd circle
			(at -4.25 0.43 270)
			(size 0.5 0.5)
			(layers "F.Cu" "F.Mask" "F.Paste")
			(net 1 "VCCA")
			(pinfunction "VCCA")
			(pintype "passive")
		)
		(pad "N15" smd circle
			(at -3.25 0.43 270)
			(size 0.5 0.5)
			(layers "F.Cu" "F.Mask" "F.Paste")
			(net 1 "VCCA")
			(pinfunction "VCCA")
			(pintype "passive")
		)
		(pad "N17" smd circle
			(at -2.25 0.43 270)
			(size 0.5 0.5)
			(layers "F.Cu" "F.Mask" "F.Paste")
			(net 9 "VCCD")
			(pinfunction "VCCD")
			(pintype "passive")
		)
		(pad "N19" smd circle
			(at -1.25 0.43 270)
			(size 0.5 0.5)
			(layers "F.Cu" "F.Mask" "F.Paste")
			(net 9 "VCCD")
			(pinfunction "VCCD")
			(pintype "passive")
		)
		(pad "N21" smd circle
			(at -0.25 0.43 270)
			(size 0.5 0.5)
			(layers "F.Cu" "F.Mask" "F.Paste")
			(net 9 "VCCD")
			(pinfunction "VCCD")
			(pintype "passive")
		)
		(pad "N23" smd circle
			(at 0.75 0.43 270)
			(size 0.5 0.5)
			(layers "F.Cu" "F.Mask" "F.Paste")
			(net 533 "unconnected-(U14E-RSVDN23_NC-PadN23)")
			(pinfunction "RSVDN23_NC")
			(pintype "passive+no_connect")
		)
		(pad "N25" smd circle
			(at 1.75 0.43 270)
			(size 0.5 0.5)
			(layers "F.Cu" "F.Mask" "F.Paste")
			(net 577 "unconnected-(U14E-RSVDN25_NC-PadN25)")
			(pinfunction "RSVDN25_NC")
			(pintype "passive+no_connect")
		)
		(pad "N27" smd circle
			(at 2.75 0.43 270)
			(size 0.5 0.5)
			(layers "F.Cu" "F.Mask" "F.Paste")
			(net 452 "unconnected-(U14E-RSVDN27_NC-PadN27)")
			(pinfunction "RSVDN27_NC")
			(pintype "passive+no_connect")
		)
		(pad "N29" smd circle
			(at 3.75 0.43 270)
			(size 0.5 0.5)
			(layers "F.Cu" "F.Mask" "F.Paste")
			(net 576 "unconnected-(U14G-RSVDN29_NC-PadN29)")
			(pinfunction "RSVDN29_NC")
			(pintype "passive+no_connect")
		)
		(pad "N31" smd circle
			(at 4.75 0.43 270)
			(size 0.5 0.5)
			(layers "F.Cu" "F.Mask" "F.Paste")
			(net 503 "unconnected-(U14G-RSVDN31_NC-PadN31)")
			(pinfunction "RSVDN31_NC")
			(pintype "passive+no_connect")
		)
		(pad "N33" smd circle
			(at 5.75 0.43 270)
			(size 0.5 0.5)
			(layers "F.Cu" "F.Mask" "F.Paste")
			(net 525 "unconnected-(U14F-RSVDN33_NC-PadN33)")
			(pinfunction "RSVDN33_NC")
			(pintype "passive+no_connect")
		)
		(pad "N35" smd circle
			(at 6.75 0.43 270)
			(size 0.5 0.5)
			(layers "F.Cu" "F.Mask" "F.Paste")
			(net 474 "unconnected-(U14F-RSVDN35_NC-PadN35)")
			(pinfunction "RSVDN35_NC")
			(pintype "passive+no_connect")
		)
		(pad "N37" smd circle
			(at 7.75 0.43 270)
			(size 0.5 0.5)
			(layers "F.Cu" "F.Mask" "F.Paste")
			(net 23 "GND")
			(pinfunction "RSVDN37_VSS")
			(pintype "passive")
		)
		(pad "N39" smd circle
			(at 8.75 0.43 270)
			(size 0.5 0.5)
			(layers "F.Cu" "F.Mask" "F.Paste")
			(net 587 "unconnected-(U14F-P0_PTP_SYNC0-PadN39)")
			(pinfunction "P0_PTP_SYNC0")
			(pintype "passive+no_connect")
		)
		(pad "N41" smd circle
			(at 9.75 0.43 270)
			(size 0.5 0.5)
			(layers "F.Cu" "F.Mask" "F.Paste")
			(net 559 "unconnected-(U14F-P0_PTP_SYNC1-PadN41)")
			(pinfunction "P0_PTP_SYNC1")
			(pintype "passive+no_connect")
		)
		(pad "P2" smd circle
			(at -9.75 1.295 270)
			(size 0.5 0.5)
			(layers "F.Cu" "F.Mask" "F.Paste")
			(net 371 "/TB Controller/~{PE_WAKE}")
			(pinfunction "~{PE_WAKE}")
			(pintype "open_collector")
		)
		(pad "P4" smd circle
			(at -8.75 1.295 270)
			(size 0.5 0.5)
			(layers "F.Cu" "F.Mask" "F.Paste")
			(net 535 "unconnected-(U14C-SDP1_1-PadP4)")
			(pinfunction "SDP1_1")
			(pintype "passive+no_connect")
		)
		(pad "P6" smd circle
			(at -7.75 1.295 270)
			(size 0.5 0.5)
			(layers "F.Cu" "F.Mask" "F.Paste")
			(net 547 "unconnected-(U14C-SDP1_2-PadP6)")
			(pinfunction "SDP1_2")
			(pintype "passive+no_connect")
		)
		(pad "P8" smd circle
			(at -6.75 1.295 270)
			(size 0.5 0.5)
			(layers "F.Cu" "F.Mask" "F.Paste")
			(net 99 "/X710-AT2 RSVD/RSVDP8_VSS")
			(pinfunction "RSVDP8_VSS")
			(pintype "passive")
		)
		(pad "P10" smd circle
			(at -5.75 1.295 270)
			(size 0.5 0.5)
			(layers "F.Cu" "F.Mask" "F.Paste")
			(net 23 "GND")
			(pinfunction "VSS")
			(pintype "passive")
		)
		(pad "P12" smd circle
			(at -4.75 1.295 270)
			(size 0.5 0.5)
			(layers "F.Cu" "F.Mask" "F.Paste")
			(net 23 "GND")
			(pinfunction "VSS")
			(pintype "passive")
		)
		(pad "P14" smd circle
			(at -3.75 1.295 270)
			(size 0.5 0.5)
			(layers "F.Cu" "F.Mask" "F.Paste")
			(net 23 "GND")
			(pinfunction "VSS")
			(pintype "passive")
		)
		(pad "P16" smd circle
			(at -2.75 1.295 270)
			(size 0.5 0.5)
			(layers "F.Cu" "F.Mask" "F.Paste")
			(net 23 "GND")
			(pinfunction "VSS")
			(pintype "passive")
		)
		(pad "P18" smd circle
			(at -1.75 1.295 270)
			(size 0.5 0.5)
			(layers "F.Cu" "F.Mask" "F.Paste")
			(net 23 "GND")
			(pinfunction "VSS")
			(pintype "passive")
		)
		(pad "P20" smd circle
			(at -0.75 1.295 270)
			(size 0.5 0.5)
			(layers "F.Cu" "F.Mask" "F.Paste")
			(net 23 "GND")
			(pinfunction "VSS")
			(pintype "passive")
		)
		(pad "P22" smd circle
			(at 0.25 1.295 270)
			(size 0.5 0.5)
			(layers "F.Cu" "F.Mask" "F.Paste")
			(net 97 "/X710-AT2 RSVD/RSVDP22_VSS")
			(pinfunction "RSVDP22_VSS")
			(pintype "passive")
		)
		(pad "P24" smd circle
			(at 1.25 1.295 270)
			(size 0.5 0.5)
			(layers "F.Cu" "F.Mask" "F.Paste")
			(net 501 "unconnected-(U14E-RSVDP24_NC-PadP24)")
			(pinfunction "RSVDP24_NC")
			(pintype "passive+no_connect")
		)
		(pad "P26" smd circle
			(at 2.25 1.295 270)
			(size 0.5 0.5)
			(layers "F.Cu" "F.Mask" "F.Paste")
			(net 477 "unconnected-(U14E-RSVDP26_NC-PadP26)")
			(pinfunction "RSVDP26_NC")
			(pintype "passive+no_connect")
		)
		(pad "P28" smd circle
			(at 3.25 1.295 270)
			(size 0.5 0.5)
			(layers "F.Cu" "F.Mask" "F.Paste")
			(net 502 "unconnected-(U14E-RSVDP28_NC-PadP28)")
			(pinfunction "RSVDP28_NC")
			(pintype "passive+no_connect")
		)
		(pad "P30" smd circle
			(at 4.25 1.295 270)
			(size 0.5 0.5)
			(layers "F.Cu" "F.Mask" "F.Paste")
			(net 520 "unconnected-(U14G-RSVDP30_NC-PadP30)")
			(pinfunction "RSVDP30_NC")
			(pintype "passive+no_connect")
		)
		(pad "P32" smd circle
			(at 5.25 1.295 270)
			(size 0.5 0.5)
			(layers "F.Cu" "F.Mask" "F.Paste")
			(net 454 "unconnected-(U14G-RSVDP32_NC-PadP32)")
			(pinfunction "RSVDP32_NC")
			(pintype "passive+no_connect")
		)
		(pad "P34" smd circle
			(at 6.25 1.295 270)
			(size 0.5 0.5)
			(layers "F.Cu" "F.Mask" "F.Paste")
			(net 527 "unconnected-(U14F-RSVDP34_NC-PadP34)")
			(pinfunction "RSVDP34_NC")
			(pintype "passive+no_connect")
		)
		(pad "P36" smd circle
			(at 7.25 1.295 270)
			(size 0.5 0.5)
			(layers "F.Cu" "F.Mask" "F.Paste")
			(net 506 "unconnected-(U14F-RSVDP36_NC-PadP36)")
			(pinfunction "RSVDP36_NC")
			(pintype "passive+no_connect")
		)
		(pad "P38" smd circle
			(at 8.25 1.295 270)
			(size 0.5 0.5)
			(layers "F.Cu" "F.Mask" "F.Paste")
			(net 23 "GND")
			(pinfunction "RSVDP38_VSS")
			(pintype "passive")
		)
		(pad "P40" smd circle
			(at 9.25 1.295 270)
			(size 0.5 0.5)
			(layers "F.Cu" "F.Mask" "F.Paste")
			(net 81 "/X710-AT2 Misc/FLSH_SCK")
			(pinfunction "FLSH_SCK")
			(pintype "tri_state")
		)
		(pad "P42" smd circle
			(at 10.25 1.295 270)
			(size 0.5 0.5)
			(layers "F.Cu" "F.Mask" "F.Paste")
			(net 352 "/X710 flash memory/FLASH.MOSI")
			(pinfunction "FLSH_SI")
			(pintype "tri_state")
		)
		(pad "R1" smd circle
			(at -10.25 2.16 270)
			(size 0.5 0.5)
			(layers "F.Cu" "F.Mask" "F.Paste")
			(net 392 "/TB Controller/~{PE_RST}")
			(pinfunction "~{PE_RST}")
			(pintype "input")
		)
		(pad "R3" smd circle
			(at -9.25 2.16 270)
			(size 0.5 0.5)
			(layers "F.Cu" "F.Mask" "F.Paste")
			(net 554 "unconnected-(U14C-LED3_0-PadR3)")
			(pinfunction "LED3_0")
			(pintype "passive+no_connect")
		)
		(pad "R5" smd circle
			(at -8.25 2.16 270)
			(size 0.5 0.5)
			(layers "F.Cu" "F.Mask" "F.Paste")
			(net 481 "unconnected-(U14C-LED3_1-PadR5)")
			(pinfunction "LED3_1")
			(pintype "passive+no_connect")
		)
		(pad "R7" smd circle
			(at -7.25 2.16 270)
			(size 0.5 0.5)
			(layers "F.Cu" "F.Mask" "F.Paste")
			(net 491 "unconnected-(U14C-SDP1_0-PadR7)")
			(pinfunction "SDP1_0")
			(pintype "passive+no_connect")
		)
		(pad "R9" smd circle
			(at -6.25 2.16 270)
			(size 0.5 0.5)
			(layers "F.Cu" "F.Mask" "F.Paste")
			(net 553 "unconnected-(U14E-RSVDR9_NC-PadR9)")
			(pinfunction "RSVDR9_NC")
			(pintype "passive+no_connect")
		)
		(pad "R11" smd circle
			(at -5.25 2.16 270)
			(size 0.5 0.5)
			(layers "F.Cu" "F.Mask" "F.Paste")
			(net 7 "+3V3")
			(pinfunction "VCC3P3")
			(pintype "passive")
		)
		(pad "R13" smd circle
			(at -4.25 2.16 270)
			(size 0.5 0.5)
			(layers "F.Cu" "F.Mask" "F.Paste")
			(net 9 "VCCD")
			(pinfunction "VCCD")
			(pintype "passive")
		)
		(pad "R15" smd circle
			(at -3.25 2.16 270)
			(size 0.5 0.5)
			(layers "F.Cu" "F.Mask" "F.Paste")
			(net 9 "VCCD")
			(pinfunction "VCCD")
			(pintype "passive")
		)
		(pad "R17" smd circle
			(at -2.25 2.16 270)
			(size 0.5 0.5)
			(layers "F.Cu" "F.Mask" "F.Paste")
			(net 9 "VCCD")
			(pinfunction "VCCD")
			(pintype "passive")
		)
		(pad "R19" smd circle
			(at -1.25 2.16 270)
			(size 0.5 0.5)
			(layers "F.Cu" "F.Mask" "F.Paste")
			(net 9 "VCCD")
			(pinfunction "VCCD")
			(pintype "passive")
		)
		(pad "R21" smd circle
			(at -0.25 2.16 270)
			(size 0.5 0.5)
			(layers "F.Cu" "F.Mask" "F.Paste")
			(net 9 "VCCD")
			(pinfunction "VCCD")
			(pintype "passive")
		)
		(pad "R23" smd circle
			(at 0.75 2.16 270)
			(size 0.5 0.5)
			(layers "F.Cu" "F.Mask" "F.Paste")
			(net 483 "unconnected-(U14E-RSVDR23_NC-PadR23)")
			(pinfunction "RSVDR23_NC")
			(pintype "passive+no_connect")
		)
		(pad "R25" smd circle
			(at 1.75 2.16 270)
			(size 0.5 0.5)
			(layers "F.Cu" "F.Mask" "F.Paste")
			(net 497 "unconnected-(U14E-RSVDR25_NC-PadR25)")
			(pinfunction "RSVDR25_NC")
			(pintype "passive+no_connect")
		)
		(pad "R27" smd circle
			(at 2.75 2.16 270)
			(size 0.5 0.5)
			(layers "F.Cu" "F.Mask" "F.Paste")
			(net 478 "unconnected-(U14E-RSVDR27_NC-PadR27)")
			(pinfunction "RSVDR27_NC")
			(pintype "passive+no_connect")
		)
		(pad "R29" smd circle
			(at 3.75 2.16 270)
			(size 0.5 0.5)
			(layers "F.Cu" "F.Mask" "F.Paste")
			(net 449 "unconnected-(U14G-RSVDR29_NC-PadR29)")
			(pinfunction "RSVDR29_NC")
			(pintype "passive+no_connect")
		)
		(pad "R31" smd circle
			(at 4.75 2.16 270)
			(size 0.5 0.5)
			(layers "F.Cu" "F.Mask" "F.Paste")
			(net 492 "unconnected-(U14G-RSVDR31_NC-PadR31)")
			(pinfunction "RSVDR31_NC")
			(pintype "passive+no_connect")
		)
		(pad "R33" smd circle
			(at 5.75 2.16 270)
			(size 0.5 0.5)
			(layers "F.Cu" "F.Mask" "F.Paste")
			(net 455 "unconnected-(U14F-RSVDR33_NC-PadR33)")
			(pinfunction "RSVDR33_NC")
			(pintype "passive+no_connect")
		)
		(pad "R35" smd circle
			(at 6.75 2.16 270)
			(size 0.5 0.5)
			(layers "F.Cu" "F.Mask" "F.Paste")
			(net 23 "GND")
			(pinfunction "VSS")
			(pintype "passive")
		)
		(pad "R37" smd circle
			(at 7.75 2.16 270)
			(size 0.5 0.5)
			(layers "F.Cu" "F.Mask" "F.Paste")
			(net 488 "unconnected-(U14F-RSVDR37_NC-PadR37)")
			(pinfunction "RSVDR37_NC")
			(pintype "passive+no_connect")
		)
		(pad "R39" smd circle
			(at 8.75 2.16 270)
			(size 0.5 0.5)
			(layers "F.Cu" "F.Mask" "F.Paste")
			(net 444 "Net-(U14D-SMBCLK)")
			(pinfunction "SMBCLK")
			(pintype "open_collector")
		)
		(pad "R41" smd circle
			(at 9.75 2.16 270)
			(size 0.5 0.5)
			(layers "F.Cu" "F.Mask" "F.Paste")
			(net 350 "/X710 flash memory/FLASH.~{CE}")
			(pinfunction "~{FLSH_CE}")
			(pintype "tri_state")
		)
		(pad "T2" smd circle
			(at -9.75 3.025 270)
			(size 0.5 0.5)
			(layers "F.Cu" "F.Mask" "F.Paste")
			(net 7 "+3V3")
			(pinfunction "VCC3P3_SVR")
			(pintype "power_in")
		)
		(pad "T4" smd circle
			(at -8.75 3.025 270)
			(size 0.5 0.5)
			(layers "F.Cu" "F.Mask" "F.Paste")
			(net 67 "/2xRJ45/~{P1_LED_ACT}")
			(pinfunction "LED2_0")
			(pintype "output")
		)
		(pad "T6" smd circle
			(at -7.75 3.025 270)
			(size 0.5 0.5)
			(layers "F.Cu" "F.Mask" "F.Paste")
			(net 66 "/2xRJ45/~{P1_LED_LINK_10G}")
			(pinfunction "LED2_1")
			(pintype "output")
		)
		(pad "T8" smd circle
			(at -6.75 3.025 270)
			(size 0.5 0.5)
			(layers "F.Cu" "F.Mask" "F.Paste")
			(net 9 "VCCD")
			(pinfunction "RSVDT8_VCCD")
			(pintype "passive")
		)
		(pad "T10" smd circle
			(at -5.75 3.025 270)
			(size 0.5 0.5)
			(layers "F.Cu" "F.Mask" "F.Paste")
			(net 23 "GND")
			(pinfunction "VSS")
			(pintype "passive")
		)
		(pad "T12" smd circle
			(at -4.75 3.025 270)
			(size 0.5 0.5)
			(layers "F.Cu" "F.Mask" "F.Paste")
			(net 23 "GND")
			(pinfunction "VSS")
			(pintype "passive")
		)
		(pad "T14" smd circle
			(at -3.75 3.025 270)
			(size 0.5 0.5)
			(layers "F.Cu" "F.Mask" "F.Paste")
			(net 23 "GND")
			(pinfunction "VSS")
			(pintype "passive")
		)
		(pad "T16" smd circle
			(at -2.75 3.025 270)
			(size 0.5 0.5)
			(layers "F.Cu" "F.Mask" "F.Paste")
			(net 23 "GND")
			(pinfunction "VSS")
			(pintype "passive")
		)
		(pad "T18" smd circle
			(at -1.75 3.025 270)
			(size 0.5 0.5)
			(layers "F.Cu" "F.Mask" "F.Paste")
			(net 23 "GND")
			(pinfunction "VSS")
			(pintype "passive")
		)
		(pad "T20" smd circle
			(at -0.75 3.025 270)
			(size 0.5 0.5)
			(layers "F.Cu" "F.Mask" "F.Paste")
			(net 23 "GND")
			(pinfunction "VSS")
			(pintype "passive")
		)
		(pad "T22" smd circle
			(at 0.25 3.025 270)
			(size 0.5 0.5)
			(layers "F.Cu" "F.Mask" "F.Paste")
			(net 573 "unconnected-(U14E-RSVDT22_NC-PadT22)")
			(pinfunction "RSVDT22_NC")
			(pintype "passive+no_connect")
		)
		(pad "T24" smd circle
			(at 1.25 3.025 270)
			(size 0.5 0.5)
			(layers "F.Cu" "F.Mask" "F.Paste")
			(net 462 "unconnected-(U14E-RSVDT24_NC-PadT24)")
			(pinfunction "RSVDT24_NC")
			(pintype "passive+no_connect")
		)
		(pad "T26" smd circle
			(at 2.25 3.025 270)
			(size 0.5 0.5)
			(layers "F.Cu" "F.Mask" "F.Paste")
			(net 493 "unconnected-(U14E-RSVDT26_NC-PadT26)")
			(pinfunction "RSVDT26_NC")
			(pintype "passive+no_connect")
		)
		(pad "T28" smd circle
			(at 3.25 3.025 270)
			(size 0.5 0.5)
			(layers "F.Cu" "F.Mask" "F.Paste")
			(net 530 "unconnected-(U14E-RSVDT28_NC-PadT28)")
			(pinfunction "RSVDT28_NC")
			(pintype "passive+no_connect")
		)
		(pad "T30" smd circle
			(at 4.25 3.025 270)
			(size 0.5 0.5)
			(layers "F.Cu" "F.Mask" "F.Paste")
			(net 519 "unconnected-(U14G-RSVDT30_NC-PadT30)")
			(pinfunction "RSVDT30_NC")
			(pintype "passive+no_connect")
		)
		(pad "T32" smd circle
			(at 5.25 3.025 270)
			(size 0.5 0.5)
			(layers "F.Cu" "F.Mask" "F.Paste")
			(net 485 "unconnected-(U14G-RSVDT32_NC-PadT32)")
			(pinfunction "RSVDT32_NC")
			(pintype "passive+no_connect")
		)
		(pad "T34" smd circle
			(at 6.25 3.025 270)
			(size 0.5 0.5)
			(layers "F.Cu" "F.Mask" "F.Paste")
			(net 7 "+3V3")
			(pinfunction "VCC3P3")
			(pintype "passive")
		)
		(pad "T36" smd circle
			(at 7.25 3.025 270)
			(size 0.5 0.5)
			(layers "F.Cu" "F.Mask" "F.Paste")
			(net 11 "/X710-AT2 PCIe/PCIe_JTAG.JTDI")
			(pinfunction "JTDI")
			(pintype "input")
		)
		(pad "T38" smd circle
			(at 8.25 3.025 270)
			(size 0.5 0.5)
			(layers "F.Cu" "F.Mask" "F.Paste")
			(net 8 "/X710-AT2 PCIe/PCIe_JTAG.JTDO")
			(pinfunction "JTDO")
			(pintype "open_collector")
		)
		(pad "T40" smd circle
			(at 9.25 3.025 270)
			(size 0.5 0.5)
			(layers "F.Cu" "F.Mask" "F.Paste")
			(net 445 "Net-(U14D-SMBD)")
			(pinfunction "SMBD")
			(pintype "open_collector")
		)
		(pad "T42" smd circle
			(at 10.25 3.025 270)
			(size 0.5 0.5)
			(layers "F.Cu" "F.Mask" "F.Paste")
			(net 351 "/X710 flash memory/FLASH.MISO")
			(pinfunction "FLSH_SO")
			(pintype "input")
		)
		(pad "U1" smd circle
			(at -10.25 3.89 270)
			(size 0.5 0.5)
			(layers "F.Cu" "F.Mask" "F.Paste")
			(net 23 "GND")
			(pinfunction "VSS_SVR")
			(pintype "power_in")
		)
		(pad "U3" smd circle
			(at -9.25 3.89 270)
			(size 0.5 0.5)
			(layers "F.Cu" "F.Mask" "F.Paste")
			(net 126 "/X710-AT2 Misc/~{PCI_DIS}")
			(pinfunction "~{PCI_DIS}")
			(pintype "tri_state")
		)
		(pad "U5" smd circle
			(at -8.25 3.89 270)
			(size 0.5 0.5)
			(layers "F.Cu" "F.Mask" "F.Paste")
			(net 469 "unconnected-(U14C-LED1_0-PadU5)")
			(pinfunction "LED1_0")
			(pintype "passive+no_connect")
		)
		(pad "U7" smd circle
			(at -7.25 3.89 270)
			(size 0.5 0.5)
			(layers "F.Cu" "F.Mask" "F.Paste")
			(net 457 "unconnected-(U14C-LED1_1-PadU7)")
			(pinfunction "LED1_1")
			(pintype "passive+no_connect")
		)
		(pad "U9" smd circle
			(at -6.25 3.89 270)
			(size 0.5 0.5)
			(layers "F.Cu" "F.Mask" "F.Paste")
			(net 557 "unconnected-(U14E-RSVDU9_NC-PadU9)")
			(pinfunction "RSVDU9_NC")
			(pintype "passive+no_connect")
		)
		(pad "U11" smd circle
			(at -5.25 3.89 270)
			(size 0.5 0.5)
			(layers "F.Cu" "F.Mask" "F.Paste")
			(net 9 "VCCD")
			(pinfunction "VCCD")
			(pintype "passive")
		)
		(pad "U13" smd circle
			(at -4.25 3.89 270)
			(size 0.5 0.5)
			(layers "F.Cu" "F.Mask" "F.Paste")
			(net 9 "VCCD")
			(pinfunction "VCCD")
			(pintype "passive")
		)
		(pad "U15" smd circle
			(at -3.25 3.89 270)
			(size 0.5 0.5)
			(layers "F.Cu" "F.Mask" "F.Paste")
			(net 9 "VCCD")
			(pinfunction "VCCD")
			(pintype "passive")
		)
		(pad "U17" smd circle
			(at -2.25 3.89 270)
			(size 0.5 0.5)
			(layers "F.Cu" "F.Mask" "F.Paste")
			(net 9 "VCCD")
			(pinfunction "VCCD")
			(pintype "passive")
		)
		(pad "U19" smd circle
			(at -1.25 3.89 270)
			(size 0.5 0.5)
			(layers "F.Cu" "F.Mask" "F.Paste")
			(net 9 "VCCD")
			(pinfunction "VCCD")
			(pintype "passive")
		)
		(pad "U21" smd circle
			(at -0.25 3.89 270)
			(size 0.5 0.5)
			(layers "F.Cu" "F.Mask" "F.Paste")
			(net 7 "+3V3")
			(pinfunction "VCC3P3")
			(pintype "power_in")
		)
		(pad "U23" smd circle
			(at 0.75 3.89 270)
			(size 0.5 0.5)
			(layers "F.Cu" "F.Mask" "F.Paste")
			(net 539 "unconnected-(U14E-RSVDU23_NC-PadU23)")
			(pinfunction "RSVDU23_NC")
			(pintype "passive+no_connect")
		)
		(pad "U25" smd circle
			(at 1.75 3.89 270)
			(size 0.5 0.5)
			(layers "F.Cu" "F.Mask" "F.Paste")
			(net 507 "unconnected-(U14E-RSVDU25_NC-PadU25)")
			(pinfunction "RSVDU25_NC")
			(pintype "passive+no_connect")
		)
		(pad "U27" smd circle
			(at 2.75 3.89 270)
			(size 0.5 0.5)
			(layers "F.Cu" "F.Mask" "F.Paste")
			(net 584 "unconnected-(U14E-RSVDU27_NC-PadU27)")
			(pinfunction "RSVDU27_NC")
			(pintype "passive+no_connect")
		)
		(pad "U29" smd circle
			(at 3.75 3.89 270)
			(size 0.5 0.5)
			(layers "F.Cu" "F.Mask" "F.Paste")
			(net 529 "unconnected-(U14E-RSVDU29_NC-PadU29)")
			(pinfunction "RSVDU29_NC")
			(pintype "passive+no_connect")
		)
		(pad "U31" smd circle
			(at 4.75 3.89 270)
			(size 0.5 0.5)
			(layers "F.Cu" "F.Mask" "F.Paste")
			(net 582 "unconnected-(U14G-RSVDU31_NC-PadU31)")
			(pinfunction "RSVDU31_NC")
			(pintype "passive+no_connect")
		)
		(pad "U33" smd circle
			(at 5.75 3.89 270)
			(size 0.5 0.5)
			(layers "F.Cu" "F.Mask" "F.Paste")
			(net 479 "unconnected-(U14G-RSVDU33_NC-PadU33)")
			(pinfunction "RSVDU33_NC")
			(pintype "passive+no_connect")
		)
		(pad "U35" smd circle
			(at 6.75 3.89 270)
			(size 0.5 0.5)
			(layers "F.Cu" "F.Mask" "F.Paste")
			(net 510 "unconnected-(U14G-RSVDU35_NC-PadU35)")
			(pinfunction "RSVDU35_NC")
			(pintype "passive+no_connect")
		)
		(pad "U37" smd circle
			(at 7.75 3.89 270)
			(size 0.5 0.5)
			(layers "F.Cu" "F.Mask" "F.Paste")
			(net 16 "/X710-AT2 PCIe/PCIe_JTAG.JTCK")
			(pinfunction "JTCK")
			(pintype "input")
		)
		(pad "U39" smd circle
			(at 8.75 3.89 270)
			(size 0.5 0.5)
			(layers "F.Cu" "F.Mask" "F.Paste")
			(net 35 "/X710-AT2 Misc/POR_BYPASS")
			(pinfunction "POR_BYPASS")
			(pintype "input")
		)
		(pad "U41" smd circle
			(at 9.75 3.89 270)
			(size 0.5 0.5)
			(layers "F.Cu" "F.Mask" "F.Paste")
			(net 73 "/X710-AT2 Misc/~{SMBALRT}")
			(pinfunction "~{SMBALRT}")
			(pintype "open_collector")
		)
		(pad "V2" smd circle
			(at -9.75 4.755 270)
			(size 0.5 0.5)
			(layers "F.Cu" "F.Mask" "F.Paste")
			(net 427 "Net-(U14H-SVR_IND)")
			(pinfunction "SVR_IND")
			(pintype "passive")
		)
		(pad "V4" smd circle
			(at -8.75 4.755 270)
			(size 0.5 0.5)
			(layers "F.Cu" "F.Mask" "F.Paste")
			(net 61 "/2xRJ45/~{P0_LED_ACT}")
			(pinfunction "LED0_0")
			(pintype "output")
		)
		(pad "V6" smd circle
			(at -7.75 4.755 270)
			(size 0.5 0.5)
			(layers "F.Cu" "F.Mask" "F.Paste")
			(net 60 "/2xRJ45/~{P0_LED_LINK_10G}")
			(pinfunction "LED0_1")
			(pintype "output")
		)
		(pad "V8" smd circle
			(at -6.75 4.755 270)
			(size 0.5 0.5)
			(layers "F.Cu" "F.Mask" "F.Paste")
			(net 572 "unconnected-(U14H-RSVDV8_NC-PadV8)")
			(pinfunction "RSVDV8_NC")
			(pintype "passive+no_connect")
		)
		(pad "V10" smd circle
			(at -5.75 4.755 270)
			(size 0.5 0.5)
			(layers "F.Cu" "F.Mask" "F.Paste")
			(net 465 "unconnected-(U14H-RSVDV10_NC-PadV10)")
			(pinfunction "RSVDV10_NC")
			(pintype "passive+no_connect")
		)
		(pad "V12" smd circle
			(at -4.75 4.755 270)
			(size 0.5 0.5)
			(layers "F.Cu" "F.Mask" "F.Paste")
			(net 23 "GND")
			(pinfunction "VSSA")
			(pintype "passive")
		)
		(pad "V14" smd circle
			(at -3.75 4.755 270)
			(size 0.5 0.5)
			(layers "F.Cu" "F.Mask" "F.Paste")
			(net 23 "GND")
			(pinfunction "VSSA")
			(pintype "passive")
		)
		(pad "V16" smd circle
			(at -2.75 4.755 270)
			(size 0.5 0.5)
			(layers "F.Cu" "F.Mask" "F.Paste")
			(net 23 "GND")
			(pinfunction "VSSA")
			(pintype "passive")
		)
		(pad "V18" smd circle
			(at -1.75 4.755 270)
			(size 0.5 0.5)
			(layers "F.Cu" "F.Mask" "F.Paste")
			(net 23 "GND")
			(pinfunction "VSSA")
			(pintype "passive")
		)
		(pad "V20" smd circle
			(at -0.75 4.755 270)
			(size 0.5 0.5)
			(layers "F.Cu" "F.Mask" "F.Paste")
			(net 23 "GND")
			(pinfunction "VSSA")
			(pintype "passive")
		)
		(pad "V22" smd circle
			(at 0.25 4.755 270)
			(size 0.5 0.5)
			(layers "F.Cu" "F.Mask" "F.Paste")
			(net 458 "unconnected-(U14E-RSVDV22_NC-PadV22)")
			(pinfunction "RSVDV22_NC")
			(pintype "passive+no_connect")
		)
		(pad "V24" smd circle
			(at 1.25 4.755 270)
			(size 0.5 0.5)
			(layers "F.Cu" "F.Mask" "F.Paste")
			(net 524 "unconnected-(U14E-RSVDV24_NC-PadV24)")
			(pinfunction "RSVDV24_NC")
			(pintype "passive+no_connect")
		)
		(pad "V26" smd circle
			(at 2.25 4.755 270)
			(size 0.5 0.5)
			(layers "F.Cu" "F.Mask" "F.Paste")
			(net 552 "unconnected-(U14E-RSVDV26_NC-PadV26)")
			(pinfunction "RSVDV26_NC")
			(pintype "passive+no_connect")
		)
		(pad "V28" smd circle
			(at 3.25 4.755 270)
			(size 0.5 0.5)
			(layers "F.Cu" "F.Mask" "F.Paste")
			(net 461 "unconnected-(U14E-RSVDV28_NC-PadV28)")
			(pinfunction "RSVDV28_NC")
			(pintype "passive+no_connect")
		)
		(pad "V30" smd circle
			(at 4.25 4.755 270)
			(size 0.5 0.5)
			(layers "F.Cu" "F.Mask" "F.Paste")
			(net 473 "unconnected-(U14G-RSVDV30_NC-PadV30)")
			(pinfunction "RSVDV30_NC")
			(pintype "passive+no_connect")
		)
		(pad "V32" smd circle
			(at 5.25 4.755 270)
			(size 0.5 0.5)
			(layers "F.Cu" "F.Mask" "F.Paste")
			(net 568 "unconnected-(U14G-RSVDV32_NC-PadV32)")
			(pinfunction "RSVDV32_NC")
			(pintype "passive+no_connect")
		)
		(pad "V34" smd circle
			(at 6.25 4.755 270)
			(size 0.5 0.5)
			(layers "F.Cu" "F.Mask" "F.Paste")
			(net 523 "unconnected-(U14G-RSVDV34_NC-PadV34)")
			(pinfunction "RSVDV34_NC")
			(pintype "passive+no_connect")
		)
		(pad "V36" smd circle
			(at 7.25 4.755 270)
			(size 0.5 0.5)
			(layers "F.Cu" "F.Mask" "F.Paste")
			(net 15 "/X710-AT2 PCIe/PCIe_JTAG.~{JRST}")
			(pinfunction "~{JRST}")
			(pintype "input")
		)
		(pad "V38" smd circle
			(at 8.25 4.755 270)
			(size 0.5 0.5)
			(layers "F.Cu" "F.Mask" "F.Paste")
			(net 4 "/X710-AT2 PCIe/PCIe_JTAG.JTMS")
			(pinfunction "JTMS")
			(pintype "input")
		)
		(pad "V40" smd circle
			(at 9.25 4.755 270)
			(size 0.5 0.5)
			(layers "F.Cu" "F.Mask" "F.Paste")
			(net 128 "/2xRJ45/~{P0_LINK_LESS_THAN_10G}")
			(pinfunction "GPIO_0")
			(pintype "tri_state")
		)
		(pad "V42" smd circle
			(at 10.25 4.755 270)
			(size 0.5 0.5)
			(layers "F.Cu" "F.Mask" "F.Paste")
			(net 578 "unconnected-(U14D-GPIO_3-PadV42)")
			(pinfunction "GPIO_3")
			(pintype "passive+no_connect")
		)
		(pad "W1" smd circle
			(at -10.25 5.62 270)
			(size 0.5 0.5)
			(layers "F.Cu" "F.Mask" "F.Paste")
			(net 96 "/X710-AT2 RSVD/RSVDW1_VSS")
			(pinfunction "RSVDW1_VSS")
			(pintype "passive")
		)
		(pad "W3" smd circle
			(at -9.25 5.62 270)
			(size 0.5 0.5)
			(layers "F.Cu" "F.Mask" "F.Paste")
			(net 23 "GND")
			(pinfunction "RSVDW3_VSS")
			(pintype "power_in")
		)
		(pad "W5" smd circle
			(at -8.25 5.62 270)
			(size 0.5 0.5)
			(layers "F.Cu" "F.Mask" "F.Paste")
			(net 94 "/X710-AT2 RSVD/RSVDW5_VSS")
			(pinfunction "RSVDW5_VSS")
			(pintype "passive")
		)
		(pad "W7" smd circle
			(at -7.25 5.62 270)
			(size 0.5 0.5)
			(layers "F.Cu" "F.Mask" "F.Paste")
			(net 90 "/X710-AT2 RSVD/DEBUG_W7")
			(pinfunction "DEBUG_W7")
			(pintype "passive")
		)
		(pad "W9" smd circle
			(at -6.25 5.62 270)
			(size 0.5 0.5)
			(layers "F.Cu" "F.Mask" "F.Paste")
			(net 9 "VCCD")
			(pinfunction "VCCD_A")
			(pintype "power_in")
		)
		(pad "W11" smd circle
			(at -5.25 5.62 270)
			(size 0.5 0.5)
			(layers "F.Cu" "F.Mask" "F.Paste")
			(net 7 "+3V3")
			(pinfunction "VCC3P3_A")
			(pintype "power_in")
		)
		(pad "W13" smd circle
			(at -4.25 5.62 270)
			(size 0.5 0.5)
			(layers "F.Cu" "F.Mask" "F.Paste")
			(net 1 "VCCA")
			(pinfunction "VCCA")
			(pintype "passive")
		)
		(pad "W15" smd circle
			(at -3.25 5.62 270)
			(size 0.5 0.5)
			(layers "F.Cu" "F.Mask" "F.Paste")
			(net 1 "VCCA")
			(pinfunction "VCCA")
			(pintype "passive")
		)
		(pad "W17" smd circle
			(at -2.25 5.62 270)
			(size 0.5 0.5)
			(layers "F.Cu" "F.Mask" "F.Paste")
			(net 1 "VCCA")
			(pinfunction "VCCA")
			(pintype "passive")
		)
		(pad "W19" smd circle
			(at -1.25 5.62 270)
			(size 0.5 0.5)
			(layers "F.Cu" "F.Mask" "F.Paste")
			(net 1 "VCCA")
			(pinfunction "VCCA")
			(pintype "passive")
		)
		(pad "W21" smd circle
			(at -0.25 5.62 270)
			(size 0.5 0.5)
			(layers "F.Cu" "F.Mask" "F.Paste")
			(net 1 "VCCA")
			(pinfunction "VCCA")
			(pintype "passive")
		)
		(pad "W23" smd circle
			(at 0.75 5.62 270)
			(size 0.5 0.5)
			(layers "F.Cu" "F.Mask" "F.Paste")
			(net 500 "unconnected-(U14E-RSVDW23_NC-PadW23)")
			(pinfunction "RSVDW23_NC")
			(pintype "passive+no_connect")
		)
		(pad "W25" smd circle
			(at 1.75 5.62 270)
			(size 0.5 0.5)
			(layers "F.Cu" "F.Mask" "F.Paste")
			(net 482 "unconnected-(U14E-RSVDW25_NC-PadW25)")
			(pinfunction "RSVDW25_NC")
			(pintype "passive+no_connect")
		)
		(pad "W27" smd circle
			(at 2.75 5.62 270)
			(size 0.5 0.5)
			(layers "F.Cu" "F.Mask" "F.Paste")
			(net 467 "unconnected-(U14E-RSVDW27_NC-PadW27)")
			(pinfunction "RSVDW27_NC")
			(pintype "passive+no_connect")
		)
		(pad "W29" smd circle
			(at 3.75 5.62 270)
			(size 0.5 0.5)
			(layers "F.Cu" "F.Mask" "F.Paste")
			(net 23 "GND")
			(pinfunction "VSSA")
			(pintype "passive")
		)
		(pad "W31" smd circle
			(at 4.75 5.62 270)
			(size 0.5 0.5)
			(layers "F.Cu" "F.Mask" "F.Paste")
			(net 23 "GND")
			(pinfunction "VSSA")
			(pintype "passive")
		)
		(pad "W33" smd circle
			(at 5.75 5.62 270)
			(size 0.5 0.5)
			(layers "F.Cu" "F.Mask" "F.Paste")
			(net 23 "GND")
			(pinfunction "VSSA")
			(pintype "passive")
		)
		(pad "W35" smd circle
			(at 6.75 5.62 270)
			(size 0.5 0.5)
			(layers "F.Cu" "F.Mask" "F.Paste")
			(net 23 "GND")
			(pinfunction "VSSA")
			(pintype "passive")
		)
		(pad "W37" smd circle
			(at 7.75 5.62 270)
			(size 0.5 0.5)
			(layers "F.Cu" "F.Mask" "F.Paste")
			(net 23 "GND")
			(pinfunction "VSSA")
			(pintype "passive")
		)
		(pad "W39" smd circle
			(at 8.75 5.62 270)
			(size 0.5 0.5)
			(layers "F.Cu" "F.Mask" "F.Paste")
			(net 23 "GND")
			(pinfunction "VSSA")
			(pintype "passive")
		)
		(pad "W41" smd circle
			(at 9.75 5.62 270)
			(size 0.5 0.5)
			(layers "F.Cu" "F.Mask" "F.Paste")
			(net 489 "unconnected-(U14D-GPIO_1-PadW41)")
			(pinfunction "GPIO_1")
			(pintype "passive+no_connect")
		)
		(pad "Y2" smd circle
			(at -9.75 6.485 270)
			(size 0.5 0.5)
			(layers "F.Cu" "F.Mask" "F.Paste")
			(net 23 "GND")
			(pinfunction "VSS_S")
			(pintype "power_in")
		)
		(pad "Y4" smd circle
			(at -8.75 6.485 270)
			(size 0.5 0.5)
			(layers "F.Cu" "F.Mask" "F.Paste")
			(net 23 "GND")
			(pinfunction "VSSA")
			(pintype "passive")
		)
		(pad "Y6" smd circle
			(at -7.75 6.485 270)
			(size 0.5 0.5)
			(layers "F.Cu" "F.Mask" "F.Paste")
			(net 23 "GND")
			(pinfunction "VSSA")
			(pintype "passive")
		)
		(pad "Y8" smd circle
			(at -6.75 6.485 270)
			(size 0.5 0.5)
			(layers "F.Cu" "F.Mask" "F.Paste")
			(net 23 "GND")
			(pinfunction "VSSA")
			(pintype "passive")
		)
		(pad "Y10" smd circle
			(at -5.75 6.485 270)
			(size 0.5 0.5)
			(layers "F.Cu" "F.Mask" "F.Paste")
			(net 3 "/X710-AT2 PCIe/RBIAS")
			(pinfunction "RBIAS")
			(pintype "passive")
		)
		(pad "Y12" smd circle
			(at -4.75 6.485 270)
			(size 0.5 0.5)
			(layers "F.Cu" "F.Mask" "F.Paste")
			(net 2 "/X710-AT2 PCIe/RSENSE")
			(pinfunction "RSENSE")
			(pintype "passive")
		)
		(pad "Y14" smd circle
			(at -3.75 6.485 270)
			(size 0.5 0.5)
			(layers "F.Cu" "F.Mask" "F.Paste")
			(net 23 "GND")
			(pinfunction "VSSA")
			(pintype "passive")
		)
		(pad "Y16" smd circle
			(at -2.75 6.485 270)
			(size 0.5 0.5)
			(layers "F.Cu" "F.Mask" "F.Paste")
			(net 91 "/X710-AT2 RSVD/DEBUG_Y16")
			(pinfunction "DEBUG_Y16")
			(pintype "passive")
		)
		(pad "Y18" smd circle
			(at -1.75 6.485 270)
			(size 0.5 0.5)
			(layers "F.Cu" "F.Mask" "F.Paste")
			(net 98 "/X710-AT2 RSVD/RSVDY18_VSS")
			(pinfunction "RSVDY18_VSS")
			(pintype "passive")
		)
		(pad "Y20" smd circle
			(at -0.75 6.485 270)
			(size 0.5 0.5)
			(layers "F.Cu" "F.Mask" "F.Paste")
			(net 89 "/X710-AT2 RSVD/DEBUG_Y20")
			(pinfunction "DEBUG_Y20")
			(pintype "passive")
		)
		(pad "Y22" smd circle
			(at 0.25 6.485 270)
			(size 0.5 0.5)
			(layers "F.Cu" "F.Mask" "F.Paste")
			(net 93 "/X710-AT2 RSVD/RSVDY22_VSS")
			(pinfunction "RSVDY22_VSS")
			(pintype "passive")
		)
		(pad "Y24" smd circle
			(at 1.25 6.485 270)
			(size 0.5 0.5)
			(layers "F.Cu" "F.Mask" "F.Paste")
			(net 92 "/X710-AT2 RSVD/RSVDY24_VSS")
			(pinfunction "RSVDY24_VSS")
			(pintype "passive")
		)
		(pad "Y26" smd circle
			(at 2.25 6.485 270)
			(size 0.5 0.5)
			(layers "F.Cu" "F.Mask" "F.Paste")
			(net 23 "GND")
			(pinfunction "VSSA")
			(pintype "passive")
		)
		(pad "Y28" smd circle
			(at 3.25 6.485 270)
			(size 0.5 0.5)
			(layers "F.Cu" "F.Mask" "F.Paste")
			(net 23 "GND")
			(pinfunction "VSSA")
			(pintype "passive")
		)
		(pad "Y30" smd circle
			(at 4.25 6.485 270)
			(size 0.5 0.5)
			(layers "F.Cu" "F.Mask" "F.Paste")
			(net 544 "unconnected-(U14A-PER_5_P-PadY30)")
			(pinfunction "PER_5_P")
			(pintype "input+no_connect")
		)
		(pad "Y32" smd circle
			(at 5.25 6.485 270)
			(size 0.5 0.5)
			(layers "F.Cu" "F.Mask" "F.Paste")
			(net 23 "GND")
			(pinfunction "VSSA")
			(pintype "passive")
		)
		(pad "Y34" smd circle
			(at 6.25 6.485 270)
			(size 0.5 0.5)
			(layers "F.Cu" "F.Mask" "F.Paste")
			(net 563 "unconnected-(U14A-PER_6_P-PadY34)")
			(pinfunction "PER_6_P")
			(pintype "input+no_connect")
		)
		(pad "Y36" smd circle
			(at 7.25 6.485 270)
			(size 0.5 0.5)
			(layers "F.Cu" "F.Mask" "F.Paste")
			(net 23 "GND")
			(pinfunction "VSSA")
			(pintype "passive")
		)
		(pad "Y38" smd circle
			(at 8.25 6.485 270)
			(size 0.5 0.5)
			(layers "F.Cu" "F.Mask" "F.Paste")
			(net 451 "unconnected-(U14A-PER_7_P-PadY38)")
			(pinfunction "PER_7_P")
			(pintype "input+no_connect")
		)
		(pad "Y40" smd circle
			(at 9.25 6.485 270)
			(size 0.5 0.5)
			(layers "F.Cu" "F.Mask" "F.Paste")
			(net 23 "GND")
			(pinfunction "VSSA")
			(pintype "passive")
		)
		(pad "Y42" smd circle
			(at 10.25 6.485 270)
			(size 0.5 0.5)
			(layers "F.Cu" "F.Mask" "F.Paste")
			(net 65 "/2xRJ45/~{P1_LINK_LESS_THAN_10G}")
			(pinfunction "GPIO_2")
			(pintype "tri_state")
		)
	)
	(footprint "antmicro-footprints:C_0402_1005Metric"
		(layer "F.Cu")
		(at 148.799999 109.850002 90)
		(descr "Capacitor SMD 0402")
		(tags "capacitor SMD 0402")
		(property "Reference" "C128"
			(at -17.049998 14.850002 90)
			(layer "F.SilkS")
			(effects
				(font
					(size 0.7 0.7)
					(thickness 0.15)
				)
			)
		)
		(property "Value" "C_100n_0402"
			(at -1.022927 2.155213 90)
			(layer "F.Fab")
			(effects
				(font
					(size 0.7 0.7)
					(thickness 0.15)
				)
				(justify left bottom)
			)
		)
		(property "Datasheet" "https://www.murata.com/products/productdetail?partno=GRM155R61H104KE14%23"
			(at 0 0 90)
			(layer "F.Fab")
			(hide yes)
			(effects
				(font
					(size 1.27 1.27)
					(thickness 0.15)
				)
			)
		)
		(property "Description" "SMD Multilayer Ceramic Capacitor, 0.1 µF, 50 V, 0402 [1005 Metric], ± 10%, X5R, GRM Series"
			(at 0 0 90)
			(layer "F.Fab")
			(hide yes)
			(effects
				(font
					(size 1.27 1.27)
					(thickness 0.15)
				)
			)
		)
		(property "MPN" "GRM155R61H104KE14D"
			(at 0 0 90)
			(unlocked yes)
			(layer "F.Fab")
			(hide yes)
			(effects
				(font
					(size 1 1)
					(thickness 0.15)
				)
			)
		)
		(property "Manufacturer" "Murata"
			(at 0 0 90)
			(unlocked yes)
			(layer "F.Fab")
			(hide yes)
			(effects
				(font
					(size 1 1)
					(thickness 0.15)
				)
			)
		)
		(property "License" "Apache-2.0"
			(at 0 0 90)
			(unlocked yes)
			(layer "F.Fab")
			(hide yes)
			(effects
				(font
					(size 1 1)
					(thickness 0.15)
				)
			)
		)
		(property "Author" "Antmicro"
			(at 0 0 90)
			(unlocked yes)
			(layer "F.Fab")
			(hide yes)
			(effects
				(font
					(size 1 1)
					(thickness 0.15)
				)
			)
		)
		(property "Val" "100n"
			(at 0 0 90)
			(unlocked yes)
			(layer "F.Fab")
			(hide yes)
			(effects
				(font
					(size 1 1)
					(thickness 0.15)
				)
			)
		)
		(property "Voltage" "50V"
			(at 0 0 90)
			(unlocked yes)
			(layer "F.Fab")
			(hide yes)
			(effects
				(font
					(size 1 1)
					(thickness 0.15)
				)
			)
		)
		(property "Dielectric" "X5R"
			(at 0 0 90)
			(unlocked yes)
			(layer "F.Fab")
			(hide yes)
			(effects
				(font
					(size 1 1)
					(thickness 0.15)
				)
			)
		)
		(sheetname "/X710 DCDC converters/")
		(sheetfile "DCDC_converters_X710.kicad_sch")
		(attr smd)
		(fp_rect
			(start -0.925 -0.47)
			(end 0.925 0.47)
			(stroke
				(width 0.05)
				(type default)
			)
			(fill no)
			(layer "F.CrtYd")
		)
		(fp_line
			(start 0.504 -0.25)
			(end 0.504 0.248)
			(stroke
				(width 0.15)
				(type solid)
			)
			(layer "F.Fab")
		)
		(fp_line
			(start -0.494 -0.25)
			(end 0.504 -0.25)
			(stroke
				(width 0.15)
				(type solid)
			)
			(layer "F.Fab")
		)
		(fp_line
			(start 0.504 0.248)
			(end -0.494 0.248)
			(stroke
				(width 0.15)
				(type solid)
			)
			(layer "F.Fab")
		)
		(fp_line
			(start -0.494 0.248)
			(end -0.494 -0.25)
			(stroke
				(width 0.15)
				(type solid)
			)
			(layer "F.Fab")
		)
		(fp_text user "${REFERENCE}"
			(at -0.939 4.599 90)
			(layer "F.Fab")
			(effects
				(font
					(size 0.7 0.7)
					(thickness 0.15)
				)
				(justify left bottom)
			)
		)
		(fp_text user "Author: Antmicro"
			(at -0.939 3.399 90)
			(layer "F.Fab")
			(effects
				(font
					(size 0.7 0.7)
					(thickness 0.15)
				)
				(justify left bottom)
			)
		)
		(fp_text user "License: Apache-2.0"
			(at -0.939 5.799 90)
			(layer "F.Fab")
			(effects
				(font
					(size 0.7 0.7)
					(thickness 0.15)
				)
				(justify left bottom)
			)
		)
		(pad "1" smd roundrect
			(at -0.48 0 90)
			(size 0.59 0.64)
			(layers "F.Cu" "F.Mask" "F.Paste")
			(roundrect_rratio 0.25)
			(net 332 "/X710 DCDC converters/DVDD_BST")
			(pintype "passive")
		)
		(pad "2" smd roundrect
			(at 0.48 0 90)
			(size 0.59 0.64)
			(layers "F.Cu" "F.Mask" "F.Paste")
			(roundrect_rratio 0.25)
			(net 313 "/X710 DCDC converters/DVDD_SW")
			(pintype "passive")
		)
	)
	(footprint "antmicro-footprints:IC_TPS65983BAZBHR"
		(layer "F.Cu")
		(at 135 136.5 -90)
		(property "Reference" "U3"
			(at -3.7 2.8 0)
			(unlocked yes)
			(layer "F.SilkS")
			(effects
				(font
					(size 0.7 0.7)
					(thickness 0.15)
				)
			)
		)
		(property "Value" "TPS65983BAZBHR"
			(at 0 4.1 270)
			(unlocked yes)
			(layer "F.Fab")
			(effects
				(font
					(size 0.7 0.7)
					(thickness 0.15)
				)
			)
		)
		(property "Datasheet" "https://www.ti.com/lit/ds/symlink/tps65983b.pdf?ts=1678712702533&ref_url=https%253A%252F%252Fwww.ti.com%252Fproduct%252FTPS65983B"
			(at 0 0 270)
			(layer "F.Fab")
			(hide yes)
			(effects
				(font
					(size 1.27 1.27)
					(thickness 0.15)
				)
			)
		)
		(property "Description" "USB Interface IC Universal USB Type-C and Power Delivery (PD) 3.0 controller 96-NFBGA -10°C to 85"
			(at 0 0 270)
			(layer "F.Fab")
			(hide yes)
			(effects
				(font
					(size 1.27 1.27)
					(thickness 0.15)
				)
			)
		)
		(property "MPN" "TPS65983BAZBHR"
			(at 0 0 270)
			(unlocked yes)
			(layer "F.Fab")
			(hide yes)
			(effects
				(font
					(size 1 1)
					(thickness 0.15)
				)
			)
		)
		(property "Manufacturer" "Texas Instruments"
			(at 0 0 270)
			(unlocked yes)
			(layer "F.Fab")
			(hide yes)
			(effects
				(font
					(size 1 1)
					(thickness 0.15)
				)
			)
		)
		(property "License" "Apache-2.0"
			(at 0 0 270)
			(unlocked yes)
			(layer "F.Fab")
			(hide yes)
			(effects
				(font
					(size 1 1)
					(thickness 0.15)
				)
			)
		)
		(property "Author" "Antmicro"
			(at 0 0 270)
			(unlocked yes)
			(layer "F.Fab")
			(hide yes)
			(effects
				(font
					(size 1 1)
					(thickness 0.15)
				)
			)
		)
		(sheetname "/PD and TB DC-DC/")
		(sheetfile "PD_and_TB_DC_DC.kicad_sch")
		(attr smd)
		(fp_line
			(start -3 3)
			(end -3 -3)
			(stroke
				(width 0.1)
				(type solid)
			)
			(layer "F.SilkS")
		)
		(fp_line
			(start 3 3)
			(end -3 3)
			(stroke
				(width 0.1)
				(type solid)
			)
			(layer "F.SilkS")
		)
		(fp_line
			(start -3 -2.7)
			(end -2.7 -3)
			(stroke
				(width 0.1)
				(type solid)
			)
			(layer "F.SilkS")
		)
		(fp_line
			(start -3 -2.8)
			(end -2.8 -3)
			(stroke
				(width 0.1)
				(type solid)
			)
			(layer "F.SilkS")
		)
		(fp_line
			(start -3 -2.9)
			(end -2.9 -3)
			(stroke
				(width 0.1)
				(type solid)
			)
			(layer "F.SilkS")
		)
		(fp_line
			(start -3 -3)
			(end 3 -3)
			(stroke
				(width 0.1)
				(type solid)
			)
			(layer "F.SilkS")
		)
		(fp_line
			(start 3 -3)
			(end 3 3)
			(stroke
				(width 0.1)
				(type solid)
			)
			(layer "F.SilkS")
		)
		(fp_circle
			(center -3.4 -2.9)
			(end -3.35 -2.9)
			(stroke
				(width 0.15)
				(type solid)
			)
			(fill no)
			(layer "F.SilkS")
		)
		(fp_poly
			(pts
				(xy -2.6 2.6) (xy -2.6 2.4) (xy -2.4 2.4) (xy -2.4 2.6)
			)
			(stroke
				(width 0.05)
				(type solid)
			)
			(fill yes)
			(layer "F.Paste")
		)
		(fp_poly
			(pts
				(xy 2.6 2.6) (xy 2.4 2.6) (xy 2.4 2.4) (xy 2.6 2.4)
			)
			(stroke
				(width 0.05)
				(type solid)
			)
			(fill yes)
			(layer "F.Paste")
		)
		(fp_poly
			(pts
				(xy -1.1 2.1) (xy -1.1 1.9) (xy -0.9 1.9) (xy -0.9 2.1)
			)
			(stroke
				(width 0.05)
				(type solid)
			)
			(fill yes)
			(layer "F.Paste")
		)
		(fp_poly
			(pts
				(xy -0.6 2.1) (xy -0.6 1.9) (xy -0.4 1.9) (xy -0.4 2.1)
			)
			(stroke
				(width 0.05)
				(type solid)
			)
			(fill yes)
			(layer "F.Paste")
		)
		(fp_poly
			(pts
				(xy 1.9 2.1) (xy 1.9 1.9) (xy 2.1 1.9) (xy 2.1 2.1)
			)
			(stroke
				(width 0.05)
				(type solid)
			)
			(fill yes)
			(layer "F.Paste")
		)
		(fp_poly
			(pts
				(xy -2.1 1.9) (xy -1.9 1.9) (xy -1.9 2.1) (xy -2.1 2.1)
			)
			(stroke
				(width 0.05)
				(type solid)
			)
			(fill yes)
			(layer "F.Paste")
		)
		(fp_poly
			(pts
				(xy -1.6 1.9) (xy -1.4 1.9) (xy -1.4 2.1) (xy -1.6 2.1)
			)
			(stroke
				(width 0.05)
				(type solid)
			)
			(fill yes)
			(layer "F.Paste")
		)
		(fp_poly
			(pts
				(xy -0.1 1.9) (xy 0.1 1.9) (xy 0.1 2.1) (xy -0.1 2.1)
			)
			(stroke
				(width 0.05)
				(type solid)
			)
			(fill yes)
			(layer "F.Paste")
		)
		(fp_poly
			(pts
				(xy 0.4 1.9) (xy 0.6 1.9) (xy 0.6 2.1) (xy 0.4 2.1)
			)
			(stroke
				(width 0.05)
				(type solid)
			)
			(fill yes)
			(layer "F.Paste")
		)
		(fp_poly
			(pts
				(xy 0.9 1.9) (xy 1.1 1.9) (xy 1.1 2.1) (xy 0.9 2.1)
			)
			(stroke
				(width 0.05)
				(type solid)
			)
			(fill yes)
			(layer "F.Paste")
		)
		(fp_poly
			(pts
				(xy 1.4 1.9) (xy 1.6 1.9) (xy 1.6 2.1) (xy 1.4 2.1)
			)
			(stroke
				(width 0.05)
				(type solid)
			)
			(fill yes)
			(layer "F.Paste")
		)
		(fp_poly
			(pts
				(xy -2.1 1.6) (xy -2.1 1.4) (xy -1.9 1.4) (xy -1.9 1.6)
			)
			(stroke
				(width 0.05)
				(type solid)
			)
			(fill yes)
			(layer "F.Paste")
		)
		(fp_poly
			(pts
				(xy 2.1 1.4) (xy 2.1 1.6) (xy 1.9 1.6) (xy 1.9 1.4)
			)
			(stroke
				(width 0.05)
				(type solid)
			)
			(fill yes)
			(layer "F.Paste")
		)
		(fp_poly
			(pts
				(xy -2.1 1.1) (xy -2.1 0.9) (xy -1.9 0.9) (xy -1.9 1.1)
			)
			(stroke
				(width 0.05)
				(type solid)
			)
			(fill yes)
			(layer "F.Paste")
		)
		(fp_poly
			(pts
				(xy -1.1 1.1) (xy -1.1 0.9) (xy -0.9 0.9) (xy -0.9 1.1)
			)
			(stroke
				(width 0.05)
				(type solid)
			)
			(fill yes)
			(layer "F.Paste")
		)
		(fp_poly
			(pts
				(xy -0.6 1.1) (xy -0.6 0.9) (xy -0.4 0.9) (xy -0.4 1.1)
			)
			(stroke
				(width 0.05)
				(type solid)
			)
			(fill yes)
			(layer "F.Paste")
		)
		(fp_poly
			(pts
				(xy 0.9 1.1) (xy 0.9 0.9) (xy 1.1 0.9) (xy 1.1 1.1)
			)
			(stroke
				(width 0.05)
				(type solid)
			)
			(fill yes)
			(layer "F.Paste")
		)
		(fp_poly
			(pts
				(xy -0.1 0.9) (xy 0.1 0.9) (xy 0.1 1.1) (xy -0.1 1.1)
			)
			(stroke
				(width 0.05)
				(type solid)
			)
			(fill yes)
			(layer "F.Paste")
		)
		(fp_poly
			(pts
				(xy 0.4 0.9) (xy 0.6 0.9) (xy 0.6 1.1) (xy 0.4 1.1)
			)
			(stroke
				(width 0.05)
				(type solid)
			)
			(fill yes)
			(layer "F.Paste")
		)
		(fp_poly
			(pts
				(xy 2.1 0.9) (xy 2.1 1.1) (xy 1.9 1.1) (xy 1.9 0.9)
			)
			(stroke
				(width 0.05)
				(type solid)
			)
			(fill yes)
			(layer "F.Paste")
		)
		(fp_poly
			(pts
				(xy -2.1 0.6) (xy -2.1 0.4) (xy -1.9 0.4) (xy -1.9 0.6)
			)
			(stroke
				(width 0.05)
				(type solid)
			)
			(fill yes)
			(layer "F.Paste")
		)
		(fp_poly
			(pts
				(xy -1.1 0.6) (xy -1.1 0.4) (xy -0.9 0.4) (xy -0.9 0.6)
			)
			(stroke
				(width 0.05)
				(type solid)
			)
			(fill yes)
			(layer "F.Paste")
		)
		(fp_poly
			(pts
				(xy -0.6 0.6) (xy -0.6 0.4) (xy -0.4 0.4) (xy -0.4 0.6)
			)
			(stroke
				(width 0.05)
				(type solid)
			)
			(fill yes)
			(layer "F.Paste")
		)
		(fp_poly
			(pts
				(xy 0.4 0.6) (xy 0.4 0.4) (xy 0.6 0.4) (xy 0.6 0.6)
			)
			(stroke
				(width 0.05)
				(type solid)
			)
			(fill yes)
			(layer "F.Paste")
		)
		(fp_poly
			(pts
				(xy 1.1 0.6) (xy 0.9 0.6) (xy 0.9 0.4) (xy 1.1 0.4)
			)
			(stroke
				(width 0.05)
				(type solid)
			)
			(fill yes)
			(layer "F.Paste")
		)
		(fp_poly
			(pts
				(xy -0.1 0.4) (xy 0.1 0.4) (xy 0.1 0.6) (xy -0.1 0.6)
			)
			(stroke
				(width 0.05)
				(type solid)
			)
			(fill yes)
			(layer "F.Paste")
		)
		(fp_poly
			(pts
				(xy 2.1 0.4) (xy 2.1 0.6) (xy 1.9 0.6) (xy 1.9 0.4)
			)
			(stroke
				(width 0.05)
				(type solid)
			)
			(fill yes)
			(layer "F.Paste")
		)
		(fp_poly
			(pts
				(xy -1.9 0.1) (xy -2.1 0.1) (xy -2.1 -0.1) (xy -1.9 -0.1)
			)
			(stroke
				(width 0.05)
				(type solid)
			)
			(fill yes)
			(layer "F.Paste")
		)
		(fp_poly
			(pts
				(xy -1.1 0.1) (xy -1.1 -0.1) (xy -0.9 -0.1) (xy -0.9 0.1)
			)
			(stroke
				(width 0.05)
				(type solid)
			)
			(fill yes)
			(layer "F.Paste")
		)
		(fp_poly
			(pts
				(xy -0.6 0.1) (xy -0.6 -0.1) (xy -0.4 -0.1) (xy -0.4 0.1)
			)
			(stroke
				(width 0.05)
				(type solid)
			)
			(fill yes)
			(layer "F.Paste")
		)
		(fp_poly
			(pts
				(xy 0.6 0.1) (xy 0.4 0.1) (xy 0.4 -0.1) (xy 0.6 -0.1)
			)
			(stroke
				(width 0.05)
				(type solid)
			)
			(fill yes)
			(layer "F.Paste")
		)
		(fp_poly
			(pts
				(xy 1.1 0.1) (xy 0.9 0.1) (xy 0.9 -0.1) (xy 1.1 -0.1)
			)
			(stroke
				(width 0.05)
				(type solid)
			)
			(fill yes)
			(layer "F.Paste")
		)
		(fp_poly
			(pts
				(xy -0.1 -0.1) (xy 0.1 -0.1) (xy 0.1 0.1) (xy -0.1 0.1)
			)
			(stroke
				(width 0.05)
				(type solid)
			)
			(fill yes)
			(layer "F.Paste")
		)
		(fp_poly
			(pts
				(xy 1.9 -0.1) (xy 2.1 -0.1) (xy 2.1 0.1) (xy 1.9 0.1)
			)
			(stroke
				(width 0.05)
				(type solid)
			)
			(fill yes)
			(layer "F.Paste")
		)
		(fp_poly
			(pts
				(xy -1.9 -0.4) (xy -2.1 -0.4) (xy -2.1 -0.6) (xy -1.9 -0.6)
			)
			(stroke
				(width 0.05)
				(type solid)
			)
			(fill yes)
			(layer "F.Paste")
		)
		(fp_poly
			(pts
				(xy -0.9 -0.4) (xy -1.1 -0.4) (xy -1.1 -0.6) (xy -0.9 -0.6)
			)
			(stroke
				(width 0.05)
				(type solid)
			)
			(fill yes)
			(layer "F.Paste")
		)
		(fp_poly
			(pts
				(xy -0.4 -0.4) (xy -0.6 -0.4) (xy -0.6 -0.6) (xy -0.4 -0.6)
			)
			(stroke
				(width 0.05)
				(type solid)
			)
			(fill yes)
			(layer "F.Paste")
		)
		(fp_poly
			(pts
				(xy -0.1 -0.6) (xy 0.1 -0.6) (xy 0.1 -0.4) (xy -0.1 -0.4)
			)
			(stroke
				(width 0.05)
				(type solid)
			)
			(fill yes)
			(layer "F.Paste")
		)
		(fp_poly
			(pts
				(xy 0.4 -0.6) (xy 0.6 -0.6) (xy 0.6 -0.4) (xy 0.4 -0.4)
			)
			(stroke
				(width 0.05)
				(type solid)
			)
			(fill yes)
			(layer "F.Paste")
		)
		(fp_poly
			(pts
				(xy 0.9 -0.6) (xy 1.1 -0.6) (xy 1.1 -0.4) (xy 0.9 -0.4)
			)
			(stroke
				(width 0.05)
				(type solid)
			)
			(fill yes)
			(layer "F.Paste")
		)
		(fp_poly
			(pts
				(xy 2.1 -0.6) (xy 2.1 -0.4) (xy 1.9 -0.4) (xy 1.9 -0.6)
			)
			(stroke
				(width 0.05)
				(type solid)
			)
			(fill yes)
			(layer "F.Paste")
		)
		(fp_poly
			(pts
				(xy -2.1 -0.9) (xy -2.1 -1.1) (xy -1.9 -1.1) (xy -1.9 -0.9)
			)
			(stroke
				(width 0.05)
				(type solid)
			)
			(fill yes)
			(layer "F.Paste")
		)
		(fp_poly
			(pts
				(xy -0.6 -1.1) (xy -0.4 -1.1) (xy -0.4 -0.9) (xy -0.6 -0.9)
			)
			(stroke
				(width 0.05)
				(type solid)
			)
			(fill yes)
			(layer "F.Paste")
		)
		(fp_poly
			(pts
				(xy -0.1 -1.1) (xy 0.1 -1.1) (xy 0.1 -0.9) (xy -0.1 -0.9)
			)
			(stroke
				(width 0.05)
				(type solid)
			)
			(fill yes)
			(layer "F.Paste")
		)
		(fp_poly
			(pts
				(xy 0.4 -1.1) (xy 0.6 -1.1) (xy 0.6 -0.9) (xy 0.4 -0.9)
			)
			(stroke
				(width 0.05)
				(type solid)
			)
			(fill yes)
			(layer "F.Paste")
		)
		(fp_poly
			(pts
				(xy 0.9 -1.1) (xy 1.1 -1.1) (xy 1.1 -0.9) (xy 0.9 -0.9)
			)
			(stroke
				(width 0.05)
				(type solid)
			)
			(fill yes)
			(layer "F.Paste")
		)
		(fp_poly
			(pts
				(xy 2.1 -1.1) (xy 2.1 -0.9) (xy 1.9 -0.9) (xy 1.9 -1.1)
			)
			(stroke
				(width 0.05)
				(type solid)
			)
			(fill yes)
			(layer "F.Paste")
		)
		(fp_poly
			(pts
				(xy -2.1 -1.4) (xy -2.1 -1.6) (xy -1.9 -1.6) (xy -1.9 -1.4)
			)
			(stroke
				(width 0.05)
				(type solid)
			)
			(fill yes)
			(layer "F.Paste")
		)
		(fp_poly
			(pts
				(xy 2.1 -1.6) (xy 2.1 -1.4) (xy 1.9 -1.4) (xy 1.9 -1.6)
			)
			(stroke
				(width 0.05)
				(type solid)
			)
			(fill yes)
			(layer "F.Paste")
		)
		(fp_poly
			(pts
				(xy -2.1 -1.9) (xy -2.1 -2.1) (xy -1.9 -2.1) (xy -1.9 -1.9)
			)
			(stroke
				(width 0.05)
				(type solid)
			)
			(fill yes)
			(layer "F.Paste")
		)
		(fp_poly
			(pts
				(xy -1.4 -1.9) (xy -1.6 -1.9) (xy -1.6 -2.1) (xy -1.4 -2.1)
			)
			(stroke
				(width 0.05)
				(type solid)
			)
			(fill yes)
			(layer "F.Paste")
		)
		(fp_poly
			(pts
				(xy -0.9 -1.9) (xy -1.1 -1.9) (xy -1.1 -2.1) (xy -0.9 -2.1)
			)
			(stroke
				(width 0.05)
				(type solid)
			)
			(fill yes)
			(layer "F.Paste")
		)
		(fp_poly
			(pts
				(xy 0.6 -1.9) (xy 0.4 -1.9) (xy 0.4 -2.1) (xy 0.6 -2.1)
			)
			(stroke
				(width 0.05)
				(type solid)
			)
			(fill yes)
			(layer "F.Paste")
		)
		(fp_poly
			(pts
				(xy 1.1 -1.9) (xy 0.9 -1.9) (xy 0.9 -2.1) (xy 1.1 -2.1)
			)
			(stroke
				(width 0.05)
				(type solid)
			)
			(fill yes)
			(layer "F.Paste")
		)
		(fp_poly
			(pts
				(xy 1.6 -1.9) (xy 1.4 -1.9) (xy 1.4 -2.1) (xy 1.6 -2.1)
			)
			(stroke
				(width 0.05)
				(type solid)
			)
			(fill yes)
			(layer "F.Paste")
		)
		(fp_poly
			(pts
				(xy 2.1 -1.9) (xy 1.9 -1.9) (xy 1.9 -2.1) (xy 2.1 -2.1)
			)
			(stroke
				(width 0.05)
				(type solid)
			)
			(fill yes)
			(layer "F.Paste")
		)
		(fp_poly
			(pts
				(xy -0.4 -2.1) (xy -0.4 -1.9) (xy -0.6 -1.9) (xy -0.6 -2.1)
			)
			(stroke
				(width 0.05)
				(type solid)
			)
			(fill yes)
			(layer "F.Paste")
		)
		(fp_poly
			(pts
				(xy 0.1 -2.1) (xy 0.1 -1.9) (xy -0.1 -1.9) (xy -0.1 -2.1)
			)
			(stroke
				(width 0.05)
				(type solid)
			)
			(fill yes)
			(layer "F.Paste")
		)
		(fp_poly
			(pts
				(xy -2.4 -2.4) (xy -2.6 -2.4) (xy -2.6 -2.6) (xy -2.4 -2.6)
			)
			(stroke
				(width 0.05)
				(type solid)
			)
			(fill yes)
			(layer "F.Paste")
		)
		(fp_poly
			(pts
				(xy 2.6 -2.4) (xy 2.4 -2.4) (xy 2.4 -2.6) (xy 2.6 -2.6)
			)
			(stroke
				(width 0.05)
				(type solid)
			)
			(fill yes)
			(layer "F.Paste")
		)
		(fp_line
			(start -3.25 3.25)
			(end 3.25 3.25)
			(stroke
				(width 0.05)
				(type solid)
			)
			(layer "F.CrtYd")
		)
		(fp_line
			(start -3.25 -3.25)
			(end -3.25 3.25)
			(stroke
				(width 0.05)
				(type solid)
			)
			(layer "F.CrtYd")
		)
		(fp_line
			(start 3.25 -3.25)
			(end 3.25 3.25)
			(stroke
				(width 0.05)
				(type solid)
			)
			(layer "F.CrtYd")
		)
		(fp_line
			(start 3.25 -3.25)
			(end -3.25 -3.25)
			(stroke
				(width 0.05)
				(type solid)
			)
			(layer "F.CrtYd")
		)
		(fp_line
			(start -3 3)
			(end -3 -2)
			(stroke
				(width 0.15)
				(type solid)
			)
			(layer "F.Fab")
		)
		(fp_line
			(start 3 3)
			(end -3 3)
			(stroke
				(width 0.15)
				(type solid)
			)
			(layer "F.Fab")
		)
		(fp_line
			(start -3 -2)
			(end -2 -3)
			(stroke
				(width 0.15)
				(type solid)
			)
			(layer "F.Fab")
		)
		(fp_line
			(start -2 -3)
			(end 3 -3)
			(stroke
				(width 0.15)
				(type solid)
			)
			(layer "F.Fab")
		)
		(fp_line
			(start 3 -3)
			(end 3 3)
			(stroke
				(width 0.15)
				(type solid)
			)
			(layer "F.Fab")
		)
		(fp_text user "Author: Antmicro"
			(at 0 6.2 270)
			(layer "F.Fab")
			(effects
				(font
					(size 0.7 0.7)
					(thickness 0.15)
				)
			)
		)
		(fp_text user "${REFERENCE}"
			(at 0 5.2 270)
			(unlocked yes)
			(layer "F.Fab")
			(effects
				(font
					(size 0.7 0.7)
					(thickness 0.15)
				)
			)
		)
		(fp_text user "License: Apache-2.0"
			(at 0 7.2 270)
			(layer "F.Fab")
			(effects
				(font
					(size 0.7 0.7)
					(thickness 0.15)
				)
			)
		)
		(pad "A1" smd circle
			(at -2.5 -2.5 180)
			(size 0.25 0.25)
			(layers "F.Cu" "F.Mask")
			(net 23 "GND")
			(pinfunction "GND")
			(pintype "power_in")
			(solder_paste_margin_ratio 0)
		)
		(pad "A2" smd oval
			(at -2 -2.5 270)
			(size 0.17 0.25)
			(layers "F.Cu" "F.Mask" "F.Paste")
			(net 175 "Net-(U3-LDO_1V8D)")
			(pinfunction "LDO_1V8D")
			(pintype "power_out")
			(solder_paste_margin_ratio 0)
		)
		(pad "A3" smd oval
			(at -1.5 -2.5 270)
			(size 0.17 0.25)
			(layers "F.Cu" "F.Mask" "F.Paste")
			(net 397 "/PD and TB DC-DC/TB_FLASH.CLK")
			(pinfunction "SPI_CLK")
			(pintype "output")
			(solder_paste_margin_ratio 0)
		)
		(pad "A4" smd oval
			(at -1 -2.5 270)
			(size 0.17 0.25)
			(layers "F.Cu" "F.Mask" "F.Paste")
			(net 357 "/PD and TB DC-DC/TB_FLASH.MISO")
			(pinfunction "SPI_POCI")
			(pintype "input")
			(solder_paste_margin_ratio 0)
		)
		(pad "A5" smd oval
			(at -0.5 -2.5 270)
			(size 0.17 0.25)
			(layers "F.Cu" "F.Mask" "F.Paste")
			(net 198 "Net-(U3-I2C_SDA2)")
			(pinfunction "I2C_SDA2")
			(pintype "bidirectional")
			(solder_paste_margin_ratio 0)
		)
		(pad "A6" smd oval
			(at 0 -2.5 270)
			(size 0.17 0.25)
			(layers "F.Cu" "F.Mask" "F.Paste")
			(net 170 "PP_HV")
			(pinfunction "PP_HV")
			(pintype "power_in")
			(solder_paste_margin_ratio 0)
		)
		(pad "A7" smd oval
			(at 0.5 -2.5 270)
			(size 0.17 0.25)
			(layers "F.Cu" "F.Mask" "F.Paste")
			(net 170 "PP_HV")
			(pinfunction "PP_HV")
			(pintype "power_in")
			(solder_paste_margin_ratio 0)
		)
		(pad "A8" smd oval
			(at 1 -2.5 270)
			(size 0.17 0.25)
			(layers "F.Cu" "F.Mask" "F.Paste")
			(net 170 "PP_HV")
			(pinfunction "PP_HV")
			(pintype "power_in")
			(solder_paste_margin_ratio 0)
		)
		(pad "A9" smd oval
			(at 1.5 -2.5 270)
			(size 0.17 0.25)
			(layers "F.Cu" "F.Mask" "F.Paste")
			(net 290 "unconnected-(U3-HV_GATE2-PadA9)")
			(pinfunction "HV_GATE2")
			(pintype "output+no_connect")
			(solder_paste_margin_ratio 0)
		)
		(pad "A10" smd oval
			(at 2 -2.5 270)
			(size 0.17 0.25)
			(layers "F.Cu" "F.Mask" "F.Paste")
			(net 291 "unconnected-(U3-SENSEN-PadA10)")
			(pinfunction "SENSEN")
			(pintype "input+no_connect")
			(solder_paste_margin_ratio 0)
		)
		(pad "A11" smd circle
			(at 2.5 -2.5 180)
			(size 0.25 0.25)
			(layers "F.Cu" "F.Mask")
			(net 173 "PP_5V0")
			(pinfunction "PP_5V0")
			(pintype "power_in")
			(solder_paste_margin_ratio 0)
		)
		(pad "B1" smd oval
			(at -2.5 -2 270)
			(size 0.25 0.17)
			(layers "F.Cu" "F.Mask" "F.Paste")
			(net 57 "+3V3_TB")
			(pinfunction "VDDIO")
			(pintype "power_in")
			(solder_paste_margin_ratio 0)
		)
		(pad "B2" smd circle
			(at -2 -2 180)
			(size 0.25 0.25)
			(layers "F.Cu" "F.Mask")
			(net 201 "Net-(U3-GPIO0(HD3_AMSEL))")
			(pinfunction "GPIO0(HD3_AMSEL)")
			(pintype "bidirectional")
			(solder_paste_margin_ratio 0)
		)
		(pad "B3" smd circle
			(at -1.5 -2 180)
			(size 0.25 0.25)
			(layers "F.Cu" "F.Mask")
			(net 359 "/PD and TB DC-DC/TB_FLASH.~{CE}")
			(pinfunction "SPI_CSZ")
			(pintype "output")
			(solder_paste_margin_ratio 0)
		)
		(pad "B4" smd circle
			(at -1 -2 180)
			(size 0.25 0.25)
			(layers "F.Cu" "F.Mask")
			(net 398 "/PD and TB DC-DC/TB_FLASH.MOSI")
			(pinfunction "SPI_PICO")
			(pintype "output")
			(solder_paste_margin_ratio 0)
		)
		(pad "B5" smd circle
			(at -0.5 -2 180)
			(size 0.25 0.25)
			(layers "F.Cu" "F.Mask")
			(net 199 "Net-(U3-I2C_SCL2)")
			(pinfunction "I2C_SCL2")
			(pintype "bidirectional")
			(solder_paste_margin_ratio 0)
		)
		(pad "B6" smd circle
			(at 0 -2 180)
			(size 0.25 0.25)
			(layers "F.Cu" "F.Mask")
			(net 200 "Net-(U3-I2C_IRQ2Z)")
			(pinfunction "I2C_IRQ2Z")
			(pintype "output")
			(solder_paste_margin_ratio 0)
		)
		(pad "B7" smd circle
			(at 0.5 -2 180)
			(size 0.25 0.25)
			(layers "F.Cu" "F.Mask")
			(net 170 "PP_HV")
			(pinfunction "PP_HV")
			(pintype "power_in")
			(solder_paste_margin_ratio 0)
		)
		(pad "B8" smd circle
			(at 1 -2 180)
			(size 0.25 0.25)
			(layers "F.Cu" "F.Mask")
			(net 23 "GND")
			(pinfunction "GND")
			(pintype "power_in")
			(solder_paste_margin_ratio 0)
		)
		(pad "B9" smd circle
			(at 1.5 -2 180)
			(size 0.25 0.25)
			(layers "F.Cu" "F.Mask")
			(net 292 "unconnected-(U3-HV_GATE1-PadB9)")
			(pinfunction "HV_GATE1")
			(pintype "output+no_connect")
			(solder_paste_margin_ratio 0)
		)
		(pad "B10" smd circle
			(at 2 -2 180)
			(size 0.25 0.25)
			(layers "F.Cu" "F.Mask")
			(net 293 "unconnected-(U3-SENSEP-PadB10)")
			(pinfunction "SENSEP")
			(pintype "input+no_connect")
			(solder_paste_margin_ratio 0)
		)
		(pad "B11" smd oval
			(at 2.5 -2 270)
			(size 0.25 0.17)
			(layers "F.Cu" "F.Mask" "F.Paste")
			(net 173 "PP_5V0")
			(pinfunction "PP_5V0")
			(pintype "power_in")
			(solder_paste_margin_ratio 0)
		)
		(pad "C1" smd oval
			(at -2.5 -1.5 270)
			(size 0.25 0.17)
			(layers "F.Cu" "F.Mask" "F.Paste")
			(net 372 "/PD and TB DC-DC/I2C1.IRQ")
			(pinfunction "I2C_IRQ1Z")
			(pintype "output")
			(solder_paste_margin_ratio 0)
		)
		(pad "C2" smd circle
			(at -2 -1.5 180)
			(size 0.25 0.25)
			(layers "F.Cu" "F.Mask")
			(net 294 "unconnected-(U3-GPIO1(CONFIG0)-PadC2)")
			(pinfunction "GPIO1(CONFIG0)")
			(pintype "bidirectional+no_connect")
			(solder_paste_margin_ratio 0)
		)
		(pad "C10" smd circle
			(at 2 -1.5 180)
			(size 0.25 0.25)
			(layers "F.Cu" "F.Mask")
			(net 202 "Net-(U3-GPIO4(HPD_TXRX))")
			(pinfunction "GPIO4(HPD_TXRX)")
			(pintype "bidirectional")
			(solder_paste_margin_ratio 0)
		)
		(pad "C11" smd oval
			(at 2.5 -1.5 270)
			(size 0.25 0.17)
			(layers "F.Cu" "F.Mask" "F.Paste")
			(net 173 "PP_5V0")
			(pinfunction "PP_5V0")
			(pintype "power_in")
			(solder_paste_margin_ratio 0)
		)
		(pad "D1" smd oval
			(at -2.5 -1 270)
			(size 0.25 0.17)
			(layers "F.Cu" "F.Mask" "F.Paste")
			(net 375 "/PD and TB DC-DC/I2C1.SDA")
			(pinfunction "I2C_SDA1")
			(pintype "bidirectional")
			(solder_paste_margin_ratio 0)
		)
		(pad "D2" smd circle
			(at -2 -1 180)
			(size 0.25 0.25)
			(layers "F.Cu" "F.Mask")
			(net 373 "/PD and TB DC-DC/I2C1.SCL")
			(pinfunction "I2C_SCL1")
			(pintype "bidirectional")
			(solder_paste_margin_ratio 0)
		)
		(pad "D5" smd circle
			(at -0.5 -1 180)
			(size 0.25 0.25)
			(layers "F.Cu" "F.Mask")
			(net 206 "Net-(U3-DEBUG_CTL2(GPIO17,_I2CADDR_B5))")
			(pinfunction "DEBUG_CTL2(GPIO17,_I2CADDR_B5)")
			(pintype "bidirectional")
			(solder_paste_margin_ratio 0)
		)
		(pad "D6" smd circle
			(at 0 -1 180)
			(size 0.25 0.25)
			(layers "F.Cu" "F.Mask")
			(net 210 "Net-(U3-HRESET)")
			(pinfunction "HRESET")
			(pintype "input")
			(solder_paste_margin_ratio 0)
		)
		(pad "D7" smd circle
			(at 0.5 -1 180)
			(size 0.25 0.25)
			(layers "F.Cu" "F.Mask")
			(net 204 "Net-(U3-GPIO7)")
			(pinfunction "GPIO7")
			(pintype "bidirectional")
			(solder_paste_margin_ratio 0)
		)
		(pad "D8" smd circle
			(at 1 -1 180)
			(size 0.25 0.25)
			(layers "F.Cu" "F.Mask")
			(net 23 "GND")
			(pinfunction "GND")
			(pintype "power_in")
			(solder_paste_margin_ratio 0)
		)
		(pad "D10" smd circle
			(at 2 -1 180)
			(size 0.25 0.25)
			(layers "F.Cu" "F.Mask")
			(net 295 "unconnected-(U3-GPIO2-PadD10)")
			(pinfunction "GPIO2")
			(pintype "bidirectional+no_connect")
			(solder_paste_margin_ratio 0)
		)
		(pad "D11" smd oval
			(at 2.5 -1 270)
			(size 0.25 0.17)
			(layers "F.Cu" "F.Mask" "F.Paste")
			(net 173 "PP_5V0")
			(pinfunction "PP_5V0")
			(pintype "power_in")
			(solder_paste_margin_ratio 0)
		)
		(pad "E1" smd oval
			(at -2.5 -0.5 270)
			(size 0.25 0.17)
			(layers "F.Cu" "F.Mask" "F.Paste")
			(net 176 "Net-(U3-LDO_BMC)")
			(pinfunction "LDO_BMC")
			(pintype "power_out")
			(solder_paste_margin_ratio 0)
		)
		(pad "E2" smd circle
			(at -2 -0.5 180)
			(size 0.25 0.25)
			(layers "F.Cu" "F.Mask")
			(net 205 "Net-(U3-UART_RX)")
			(pinfunction "UART_TX")
			(pintype "output")
			(solder_paste_margin_ratio 0)
		)
		(pad "E4" smd circle
			(at -1 -0.5 180)
			(size 0.25 0.25)
			(layers "F.Cu" "F.Mask")
			(net 207 "Net-(U3-DEBUG_CTL1(GPIO16,_I2CADDR_B4))")
			(pinfunction "DEBUG_CTL1(GPIO16,_I2CADDR_B4)")
			(pintype "bidirectional")
			(solder_paste_margin_ratio 0)
		)
		(pad "E5" smd circle
			(at -0.5 -0.5 180)
			(size 0.25 0.25)
			(layers "F.Cu" "F.Mask")
			(net 23 "GND")
			(pinfunction "GND")
			(pintype "power_in")
			(solder_paste_margin_ratio 0)
		)
		(pad "E6" smd circle
			(at 0 -0.5 180)
			(size 0.25 0.25)
			(layers "F.Cu" "F.Mask")
			(net 23 "GND")
			(pinfunction "GND")
			(pintype "power_in")
			(solder_paste_margin_ratio 0)
		)
		(pad "E7" smd circle
			(at 0.5 -0.5 180)
			(size 0.25 0.25)
			(layers "F.Cu" "F.Mask")
			(net 23 "GND")
			(pinfunction "GND")
			(pintype "power_in")
			(solder_paste_margin_ratio 0)
		)
		(pad "E8" smd circle
			(at 1 -0.5 180)
			(size 0.25 0.25)
			(layers "F.Cu" "F.Mask")
			(net 23 "GND")
			(pinfunction "GND")
			(pintype "power_in")
			(solder_paste_margin_ratio 0)
		)
		(pad "E10" smd circle
			(at 2 -0.5 180)
			(size 0.25 0.25)
			(layers "F.Cu" "F.Mask")
			(net 296 "unconnected-(U3-GPIO5(HPD_RX)-PadE10)")
			(pinfunction "GPIO5(HPD_RX)")
			(pintype "bidirectional+no_connect")
			(solder_paste_margin_ratio 0)
		)
		(pad "E11" smd oval
			(at 2.5 -0.5 270)
			(size 0.25 0.17)
			(layers "F.Cu" "F.Mask" "F.Paste")
			(net 209 "Net-(U3-MRESET(GPIO11))")
			(pinfunction "MRESET(GPIO11)")
			(pintype "bidirectional")
			(solder_paste_margin_ratio 0)
		)
		(pad "F1" smd oval
			(at -2.5 0 270)
			(size 0.25 0.17)
			(layers "F.Cu" "F.Mask" "F.Paste")
			(net 208 "Net-(U3-I2C_ADDR)")
			(pinfunction "I2C_ADDR")
			(pintype "bidirectional")
			(solder_paste_margin_ratio 0)
		)
		(pad "F2" smd circle
			(at -2 0 180)
			(size 0.25 0.25)
			(layers "F.Cu" "F.Mask")
			(net 205 "Net-(U3-UART_RX)")
			(pinfunction "UART_RX")
			(pintype "input")
			(solder_paste_margin_ratio 0)
		)
		(pad "F4" smd circle
			(at -1 0 180)
			(size 0.25 0.25)
			(layers "F.Cu" "F.Mask")
			(net 297 "unconnected-(U3-SWD_DATA-PadF4)")
			(pinfunction "SWD_DATA")
			(pintype "bidirectional+no_connect")
			(solder_paste_margin_ratio 0)
		)
		(pad "F5" smd circle
			(at -0.5 0 180)
			(size 0.25 0.25)
			(layers "F.Cu" "F.Mask")
			(net 23 "GND")
			(pinfunction "GND")
			(pintype "power_in")
			(solder_paste_margin_ratio 0)
		)
		(pad "F6" smd circle
			(at 0 0 180)
			(size 0.25 0.25)
			(layers "F.Cu" "F.Mask")
			(net 23 "GND")
			(pinfunction "GND")
			(pintype "power_in")
			(solder_paste_margin_ratio 0)
		)
		(pad "F7" smd circle
			(at 0.5 0 180)
			(size 0.25 0.25)
			(layers "F.Cu" "F.Mask")
			(net 23 "GND")
			(pinfunction "GND")
			(pintype "power_in")
			(solder_paste_margin_ratio 0)
		)
		(pad "F8" smd circle
			(at 1 0 180)
			(size 0.25 0.25)
			(layers "F.Cu" "F.Mask")
			(net 23 "GND")
			(pinfunction "GND")
			(pintype "power_in")
			(solder_paste_margin_ratio 0)
		)
		(pad "F10" smd circle
			(at 2 0 180)
			(size 0.25 0.25)
			(layers "F.Cu" "F.Mask")
			(net 211 "Net-(U3-BUSPOWERZ(GPIO10))")
			(pinfunction "BUSPOWERZ(GPIO10)")
			(pintype "bidirectional")
			(solder_paste_margin_ratio 0)
		)
		(pad "F11" smd oval
			(at 2.5 0 270)
			(size 0.25 0.17)
			(layers "F.Cu" "F.Mask" "F.Paste")
			(net 377 "/PD and TB DC-DC/RESET_N")
			(pinfunction "RESETZ(GPIO9)")
			(pintype "bidirectional")
			(solder_paste_margin_ratio 0)
		)
		(pad "G1" smd oval
			(at -2.5 0.5 270)
			(size 0.25 0.17)
			(layers "F.Cu" "F.Mask" "F.Paste")
			(net 304 "/PD and TB DC-DC/TPS_3V3")
			(pinfunction "LDO_3V3")
			(pintype "power_out")
			(solder_paste_margin_ratio 0)
		)
		(pad "G2" smd circle
			(at -2 0.5 180)
			(size 0.25 0.25)
			(layers "F.Cu" "F.Mask")
			(net 212 "Net-(U3-R_OSC)")
			(pinfunction "R_OSC")
			(pintype "bidirectional")
			(solder_paste_margin_ratio 0)
		)
		(pad "G4" smd circle
			(at -1 0.5 180)
			(size 0.25 0.25)
			(layers "F.Cu" "F.Mask")
			(net 298 "unconnected-(U3-SWD_CLK-PadG4)")
			(pinfunction "SWD_CLK")
			(pintype "input+no_connect")
			(solder_paste_margin_ratio 0)
		)
		(pad "G5" smd circle
			(at -0.5 0.5 180)
			(size 0.25 0.25)
			(layers "F.Cu" "F.Mask")
			(net 23 "GND")
			(pinfunction "GND")
			(pintype "power_in")
			(solder_paste_margin_ratio 0)
		)
		(pad "G6" smd circle
			(at 0 0.5 180)
			(size 0.25 0.25)
			(layers "F.Cu" "F.Mask")
			(net 23 "GND")
			(pinfunction "GND")
			(pintype "power_in")
			(solder_paste_margin_ratio 0)
		)
		(pad "G7" smd circle
			(at 0.5 0.5 180)
			(size 0.25 0.25)
			(layers "F.Cu" "F.Mask")
			(net 23 "GND")
			(pinfunction "GND")
			(pintype "power_in")
			(solder_paste_margin_ratio 0)
		)
		(pad "G8" smd circle
			(at 1 0.5 180)
			(size 0.25 0.25)
			(layers "F.Cu" "F.Mask")
			(net 23 "GND")
			(pinfunction "GND")
			(pintype "power_in")
			(solder_paste_margin_ratio 0)
		)
		(pad "G10" smd circle
			(at 2 0.5 180)
			(size 0.25 0.25)
			(layers "F.Cu" "F.Mask")
			(net 203 "Net-(U3-GPIO6)")
			(pinfunction "GPIO6")
			(pintype "bidirectional")
			(solder_paste_margin_ratio 0)
		)
		(pad "G11" smd oval
			(at 2.5 0.5 270)
			(size 0.25 0.17)
			(layers "F.Cu" "F.Mask" "F.Paste")
			(net 299 "unconnected-(U3-GPIO3(HD3_EN)-PadG11)")
			(pinfunction "GPIO3(HD3_EN)")
			(pintype "bidirectional+no_connect")
			(solder_paste_margin_ratio 0)
		)
		(pad "H1" smd oval
			(at -2.5 1 270)
			(size 0.25 0.17)
			(layers "F.Cu" "F.Mask" "F.Paste")
			(net 57 "+3V3_TB")
			(pinfunction "VIN_3V3")
			(pintype "power_in")
			(solder_paste_margin_ratio 0)
		)
		(pad "H2" smd circle
			(at -2 1 180)
			(size 0.25 0.25)
			(layers "F.Cu" "F.Mask")
			(net 171 "Net-(U3-VOUT_3V3)")
			(pinfunction "VOUT_3V3")
			(pintype "power_out")
			(solder_paste_margin_ratio 0)
		)
		(pad "H4" smd circle
			(at -1 1 180)
			(size 0.25 0.25)
			(layers "F.Cu" "F.Mask")
			(net 23 "GND")
			(pinfunction "GND")
			(pintype "power_in")
			(solder_paste_margin_ratio 0)
		)
		(pad "H5" smd circle
			(at -0.5 1 180)
			(size 0.25 0.25)
			(layers "F.Cu" "F.Mask")
			(net 23 "GND")
			(pinfunction "GND")
			(pintype "power_in")
			(solder_paste_margin_ratio 0)
		)
		(pad "H6" smd circle
			(at 0 1 180)
			(size 0.25 0.25)
			(layers "F.Cu" "F.Mask")
			(net 300 "unconnected-(U3-GPIO8-PadH6)")
			(pinfunction "GPIO8")
			(pintype "bidirectional+no_connect")
			(solder_paste_margin_ratio 0)
		)
		(pad "H7" smd circle
			(at 0.5 1 180)
			(size 0.25 0.25)
			(layers "F.Cu" "F.Mask")
			(net 165 "Net-(U3-SS)")
			(pinfunction "SS")
			(pintype "output")
			(solder_paste_margin_ratio 0)
		)
		(pad "H8" smd circle
			(at 1 1 180)
			(size 0.25 0.25)
			(layers "F.Cu" "F.Mask")
			(net 23 "GND")
			(pinfunction "GND")
			(pintype "power_in")
			(solder_paste_margin_ratio 0)
		)
		(pad "H10" smd circle
			(at 2 1 180)
			(size 0.25 0.25)
			(layers "F.Cu" "F.Mask")
			(net 173 "PP_5V0")
			(pinfunction "PP_CABLE")
			(pintype "power_in")
			(solder_paste_margin_ratio 0)
		)
		(pad "H11" smd oval
			(at 2.5 1 270)
			(size 0.25 0.17)
			(layers "F.Cu" "F.Mask" "F.Paste")
			(net 182 "VBUS")
			(pinfunction "VBUS")
			(pintype "power_in")
			(solder_paste_margin_ratio 0)
		)
		(pad "J1" smd oval
			(at -2.5 1.5 270)
			(size 0.25 0.17)
			(layers "F.Cu" "F.Mask" "F.Paste")
			(net 69 "/PD and TB DC-DC/AUX.+")
			(pinfunction "AUX_P")
			(pintype "bidirectional")
			(solder_paste_margin_ratio 0)
		)
		(pad "J2" smd circle
			(at -2 1.5 180)
			(size 0.25 0.25)
			(layers "F.Cu" "F.Mask")
			(net 79 "/PD and TB DC-DC/AUX.-")
			(pinfunction "AUX_N")
			(pintype "bidirectional")
			(solder_paste_margin_ratio 0)
		)
		(pad "J10" smd circle
			(at 2 1.5 180)
			(size 0.25 0.25)
			(layers "F.Cu" "F.Mask")
			(net 182 "VBUS")
			(pinfunction "VBUS")
			(pintype "power_in")
			(solder_paste_margin_ratio 0)
		)
		(pad "J11" smd oval
			(at 2.5 1.5 270)
			(size 0.25 0.17)
			(layers "F.Cu" "F.Mask" "F.Paste")
			(net 182 "VBUS")
			(pinfunction "VBUS")
			(pintype "power_in")
			(solder_paste_margin_ratio 0)
		)
		(pad "K1" smd oval
			(at -2.5 2 270)
			(size 0.25 0.17)
			(layers "F.Cu" "F.Mask" "F.Paste")
			(net 172 "Net-(U3-LDO_1V8A)")
			(pinfunction "LDO_1V8A")
			(pintype "power_out")
			(solder_paste_margin_ratio 0)
		)
		(pad "K2" smd circle
			(at -2 2 180)
			(size 0.25 0.25)
			(layers "F.Cu" "F.Mask")
			(net 23 "GND")
			(pinfunction "DEBUG2(GPIO14,HD3POL)")
			(pintype "bidirectional")
			(solder_paste_margin_ratio 0)
		)
		(pad "K3" smd circle
			(at -1.5 2 180)
			(size 0.25 0.25)
			(layers "F.Cu" "F.Mask")
			(net 23 "GND")
			(pinfunction "DEBUG4(GPIO12,CONFIG2)")
			(pintype "bidirectional")
			(solder_paste_margin_ratio 0)
		)
		(pad "K4" smd circle
			(at -1 2 180)
			(size 0.25 0.25)
			(layers "F.Cu" "F.Mask")
			(net 376 "/PD and TB DC-DC/LSX_1.LSX_P2R")
			(pinfunction "LSX_P2R")
			(pintype "output")
			(solder_paste_margin_ratio 0)
		)
		(pad "K5" smd circle
			(at -0.5 2 180)
			(size 0.25 0.25)
			(layers "F.Cu" "F.Mask")
			(net 395 "/PD and TB DC-DC/USB_RP.D-")
			(pinfunction "USB_RP_N")
			(pintype "bidirectional")
			(solder_paste_margin_ratio 0)
		)
		(pad "K6" smd circle
			(at 0 2 180)
			(size 0.25 0.25)
			(layers "F.Cu" "F.Mask")
			(net 368 "/PD and TB DC-DC/USB3.D_A_P")
			(pinfunction "C_USB_TP")
			(pintype "bidirectional")
			(solder_paste_margin_ratio 0)
		)
		(pad "K7" smd circle
			(at 0.5 2 180)
			(size 0.25 0.25)
			(layers "F.Cu" "F.Mask")
			(net 365 "/PD and TB DC-DC/USB3.D_B_P")
			(pinfunction "C_USB_BP")
			(pintype "bidirectional")
			(solder_paste_margin_ratio 0)
		)
		(pad "K8" smd circle
			(at 1 2 180)
			(size 0.25 0.25)
			(layers "F.Cu" "F.Mask")
			(net 369 "/PD and TB DC-DC/USB3.SBU1")
			(pinfunction "C_SBU1")
			(pintype "bidirectional")
			(solder_paste_margin_ratio 0)
		)
		(pad "K9" smd circle
			(at 1.5 2 180)
			(size 0.25 0.25)
			(layers "F.Cu" "F.Mask")
			(net 23 "GND")
			(pinfunction "RPD_G1")
			(pintype "bidirectional")
			(solder_paste_margin_ratio 0)
		)
		(pad "K10" smd circle
			(at 2 2 180)
			(size 0.25 0.25)
			(layers "F.Cu" "F.Mask")
			(net 23 "GND")
			(pinfunction "RPD_G2")
			(pintype "bidirectional")
			(solder_paste_margin_ratio 0)
		)
		(pad "K11" smd oval
			(at 2.5 2 270)
			(size 0.25 0.17)
			(layers "F.Cu" "F.Mask" "F.Paste")
			(net 182 "VBUS")
			(pinfunction "VBUS")
			(pintype "power_in")
			(solder_paste_margin_ratio 0)
		)
		(pad "L1" smd circle
			(at -2.5 2.5 180)
			(size 0.25 0.25)
			(layers "F.Cu" "F.Mask")
			(net 23 "GND")
			(pinfunction "GND")
			(pintype "power_in")
			(solder_paste_margin_ratio 0)
		)
		(pad "L2" smd oval
			(at -2 2.5 270)
			(size 0.17 0.25)
			(layers "F.Cu" "F.Mask" "F.Paste")
			(net 23 "GND")
			(pinfunction "DEBUG1(GPIO15)")
			(pintype "bidirectional")
			(solder_paste_margin_ratio 0)
		)
		(pad "L3" smd oval
			(at -1.5 2.5 270)
			(size 0.17 0.25)
			(layers "F.Cu" "F.Mask" "F.Paste")
			(net 23 "GND")
			(pinfunction "DEBUG3(GPIO13,CONFIG1)")
			(pintype "bidirectional")
			(solder_paste_margin_ratio 0)
		)
		(pad "L4" smd oval
			(at -1 2.5 270)
			(size 0.17 0.25)
			(layers "F.Cu" "F.Mask" "F.Paste")
			(net 383 "/PD and TB DC-DC/LSX_1.LSX_R2P")
			(pinfunction "LSX_R2P")
			(pintype "input")
			(solder_paste_margin_ratio 0)
		)
		(pad "L5" smd oval
			(at -0.5 2.5 270)
			(size 0.17 0.25)
			(layers "F.Cu" "F.Mask" "F.Paste")
			(net 396 "/PD and TB DC-DC/USB_RP.D+")
			(pinfunction "USB_RP_P")
			(pintype "bidirectional")
			(solder_paste_margin_ratio 0)
		)
		(pad "L6" smd oval
			(at 0 2.5 270)
			(size 0.17 0.25)
			(layers "F.Cu" "F.Mask" "F.Paste")
			(net 366 "/PD and TB DC-DC/USB3.D_A_N")
			(pinfunction "C_USB_TN")
			(pintype "bidirectional")
			(solder_paste_margin_ratio 0)
		)
		(pad "L7" smd oval
			(at 0.5 2.5 270)
			(size 0.17 0.25)
			(layers "F.Cu" "F.Mask" "F.Paste")
			(net 367 "/PD and TB DC-DC/USB3.D_B_N")
			(pinfunction "C_USB_BN")
			(pintype "bidirectional")
			(solder_paste_margin_ratio 0)
		)
		(pad "L8" smd oval
			(at 1 2.5 270)
			(size 0.17 0.25)
			(layers "F.Cu" "F.Mask" "F.Paste")
			(net 361 "/PD and TB DC-DC/USB3.SBU2")
			(pinfunction "C_SBU2")
			(pintype "bidirectional")
			(solder_paste_margin_ratio 0)
		)
		(pad "L9" smd oval
			(at 1.5 2.5 270)
			(size 0.17 0.25)
			(layers "F.Cu" "F.Mask" "F.Paste")
			(net 306 "/PD and TB DC-DC/USB3.CC1")
			(pinfunction "C_CC1")
			(pintype "bidirectional")
			(solder_paste_margin_ratio 0)
		)
		(pad "L10" smd oval
			(at 2 2.5 270)
			(size 0.17 0.25)
			(layers "F.Cu" "F.Mask" "F.Paste")
			(net 305 "/PD and TB DC-DC/USB3.CC2")
			(pinfunction "C_CC2")
			(pintype "bidirectional")
			(solder_paste_margin_ratio 0)
		)
		(pad "L11" smd circle
			(at 2.5 2.5 180)
			(size 0.25 0.25)
			(layers "F.Cu" "F.Mask")
			(net 301 "unconnected-(U3-NC-PadL11)")
			(pinfunction "NC")
			(pintype "no_connect")
			(solder_paste_margin_ratio 0)
		)
	)
	(footprint "antmicro-footprints:C_0402_1005Metric"
		(layer "F.Cu")
		(at 133 130.2)
		(descr "Capacitor SMD 0402")
		(tags "capacitor SMD 0402")
		(property "Reference" "C86"
			(at -3.2 0.4 0)
			(layer "F.SilkS")
			(effects
				(font
					(size 0.7 0.7)
					(thickness 0.15)
				)
				(justify left bottom)
			)
		)
		(property "Value" "C_100n_0402"
			(at -1.022927 2.155213 0)
			(layer "F.Fab")
			(effects
				(font
					(size 0.7 0.7)
					(thickness 0.15)
				)
				(justify left bottom)
			)
		)
		(property "Datasheet" "https://www.murata.com/products/productdetail?partno=GRM155R61H104KE14%23"
			(at 0 0 0)
			(layer "F.Fab")
			(hide yes)
			(effects
				(font
					(size 1.27 1.27)
					(thickness 0.15)
				)
			)
		)
		(property "Description" "SMD Multilayer Ceramic Capacitor, 0.1 µF, 50 V, 0402 [1005 Metric], ± 10%, X5R, GRM Series"
			(at 0 0 0)
			(layer "F.Fab")
			(hide yes)
			(effects
				(font
					(size 1.27 1.27)
					(thickness 0.15)
				)
			)
		)
		(property "MPN" "GRM155R61H104KE14D"
			(at 0 0 0)
			(unlocked yes)
			(layer "F.Fab")
			(hide yes)
			(effects
				(font
					(size 1 1)
					(thickness 0.15)
				)
			)
		)
		(property "Manufacturer" "Murata"
			(at 0 0 0)
			(unlocked yes)
			(layer "F.Fab")
			(hide yes)
			(effects
				(font
					(size 1 1)
					(thickness 0.15)
				)
			)
		)
		(property "License" "Apache-2.0"
			(at 0 0 0)
			(unlocked yes)
			(layer "F.Fab")
			(hide yes)
			(effects
				(font
					(size 1 1)
					(thickness 0.15)
				)
			)
		)
		(property "Val" "100n"
			(at 0 0 0)
			(unlocked yes)
			(layer "F.Fab")
			(hide yes)
			(effects
				(font
					(size 1 1)
					(thickness 0.15)
				)
			)
		)
		(property "Voltage" "50V"
			(at 0 0 0)
			(unlocked yes)
			(layer "F.Fab")
			(hide yes)
			(effects
				(font
					(size 1 1)
					(thickness 0.15)
				)
			)
		)
		(property "Dielectric" "X5R"
			(at 0 0 0)
			(unlocked yes)
			(layer "F.Fab")
			(hide yes)
			(effects
				(font
					(size 1 1)
					(thickness 0.15)
				)
			)
		)
		(property "Author" "Antmicro"
			(at 0 0 0)
			(unlocked yes)
			(layer "F.Fab")
			(hide yes)
			(effects
				(font
					(size 1 1)
					(thickness 0.15)
				)
			)
		)
		(sheetname "/TB Controller - Power/")
		(sheetfile "tb-power.kicad_sch")
		(attr smd)
		(fp_rect
			(start -0.925 -0.47)
			(end 0.925 0.47)
			(stroke
				(width 0.05)
				(type default)
			)
			(fill no)
			(layer "F.CrtYd")
		)
		(fp_line
			(start -0.494 -0.25)
			(end 0.504 -0.25)
			(stroke
				(width 0.15)
				(type solid)
			)
			(layer "F.Fab")
		)
		(fp_line
			(start -0.494 0.248)
			(end -0.494 -0.25)
			(stroke
				(width 0.15)
				(type solid)
			)
			(layer "F.Fab")
		)
		(fp_line
			(start 0.504 -0.25)
			(end 0.504 0.248)
			(stroke
				(width 0.15)
				(type solid)
			)
			(layer "F.Fab")
		)
		(fp_line
			(start 0.504 0.248)
			(end -0.494 0.248)
			(stroke
				(width 0.15)
				(type solid)
			)
			(layer "F.Fab")
		)
		(fp_text user "Author: Antmicro"
			(at -0.939 3.399 0)
			(layer "F.Fab")
			(effects
				(font
					(size 0.7 0.7)
					(thickness 0.15)
				)
				(justify left bottom)
			)
		)
		(fp_text user "${REFERENCE}"
			(at -0.939 4.599 0)
			(layer "F.Fab")
			(effects
				(font
					(size 0.7 0.7)
					(thickness 0.15)
				)
				(justify left bottom)
			)
		)
		(fp_text user "License: Apache-2.0"
			(at -0.939 5.799 0)
			(layer "F.Fab")
			(effects
				(font
					(size 0.7 0.7)
					(thickness 0.15)
				)
				(justify left bottom)
			)
		)
		(pad "1" smd roundrect
			(at -0.48 0)
			(size 0.59 0.64)
			(layers "F.Cu" "F.Mask" "F.Paste")
			(roundrect_rratio 0.25)
			(net 23 "GND")
			(pintype "passive")
		)
		(pad "2" smd roundrect
			(at 0.48 0)
			(size 0.59 0.64)
			(layers "F.Cu" "F.Mask" "F.Paste")
			(roundrect_rratio 0.25)
			(net 57 "+3V3_TB")
			(pintype "passive")
		)
	)
	(footprint "antmicro-footprints:Vishay_PowerPAK_1212-8_Single"
		(layer "F.Cu")
		(at 136 62.8 180)
		(descr "PowerPAK 1212-8 Single")
		(tags "Vishay PowerPAK 1212-8 Single")
		(property "Reference" "Q8"
			(at 1.8 -2.8 180)
			(layer "F.SilkS")
			(effects
				(font
					(size 0.7 0.7)
					(thickness 0.15)
				)
				(justify left bottom)
			)
		)
		(property "Value" "SQS401EN-T1_BE3"
			(at 0 2.7 180)
			(layer "F.Fab")
			(effects
				(font
					(size 0.7 0.7)
					(thickness 0.15)
				)
				(justify left bottom)
			)
		)
		(property "Datasheet" "https://www.vishay.com/docs/65529/sqs401en.pdf"
			(at 0 0 180)
			(layer "F.Fab")
			(hide yes)
			(effects
				(font
					(size 1.27 1.27)
					(thickness 0.15)
				)
			)
		)
		(property "Description" "MOSFET, P Channel, 40 V, 16A, 0.047 ohm, PowerPAK 1212-8, Surface Mount"
			(at 0 0 180)
			(layer "F.Fab")
			(hide yes)
			(effects
				(font
					(size 1.27 1.27)
					(thickness 0.15)
				)
			)
		)
		(property "MPN" "SQS401EN-T1_BE3"
			(at 0 0 180)
			(unlocked yes)
			(layer "F.Fab")
			(hide yes)
			(effects
				(font
					(size 1 1)
					(thickness 0.15)
				)
			)
		)
		(property "Manufacturer" "Vishay"
			(at 0 0 180)
			(unlocked yes)
			(layer "F.Fab")
			(hide yes)
			(effects
				(font
					(size 1 1)
					(thickness 0.15)
				)
			)
		)
		(property "Author" "Antmicro"
			(at 0 0 180)
			(unlocked yes)
			(layer "F.Fab")
			(hide yes)
			(effects
				(font
					(size 1 1)
					(thickness 0.15)
				)
			)
		)
		(property "License" "Apache-2.0"
			(at 0 0 180)
			(unlocked yes)
			(layer "F.Fab")
			(hide yes)
			(effects
				(font
					(size 1 1)
					(thickness 0.15)
				)
			)
		)
		(sheetname "/Power input/")
		(sheetfile "power_input.kicad_sch")
		(attr smd)
		(fp_line
			(start 1.648 -1.651)
			(end 1.648 -1.317)
			(stroke
				(width 0.15)
				(type solid)
			)
			(layer "F.SilkS")
		)
		(fp_line
			(start 1.634 1.3)
			(end 1.634 1.634)
			(stroke
				(width 0.15)
				(type solid)
			)
			(layer "F.SilkS")
		)
		(fp_line
			(start -1.635 1.634)
			(end 1.634 1.634)
			(stroke
				(width 0.15)
				(type solid)
			)
			(layer "F.SilkS")
		)
		(fp_line
			(start -1.635 1.3)
			(end -1.635 1.634)
			(stroke
				(width 0.15)
				(type solid)
			)
			(layer "F.SilkS")
		)
		(fp_line
			(start -1.651 -1.651)
			(end 1.648 -1.651)
			(stroke
				(width 0.15)
				(type solid)
			)
			(layer "F.SilkS")
		)
		(fp_line
			(start -1.651 -1.651)
			(end -1.651 -1.317)
			(stroke
				(width 0.15)
				(type solid)
			)
			(layer "F.SilkS")
		)
		(fp_circle
			(center -1.9 -1.4)
			(end -1.85 -1.4)
			(stroke
				(width 0.15)
				(type solid)
			)
			(fill yes)
			(layer "F.SilkS")
		)
		(fp_rect
			(start -2 -1.8)
			(end 2 1.798)
			(stroke
				(width 0.05)
				(type solid)
			)
			(fill no)
			(layer "F.CrtYd")
		)
		(fp_line
			(start -1.6425 -1.4175)
			(end -1.4175 -1.6425)
			(stroke
				(width 0.15)
				(type solid)
			)
			(layer "F.Fab")
		)
		(fp_rect
			(start -1.651 -1.651)
			(end 1.648 1.648)
			(stroke
				(width 0.15)
				(type solid)
			)
			(fill no)
			(layer "F.Fab")
		)
		(fp_text user "Author: Antmicro"
			(at -8 5.9 180)
			(layer "F.Fab")
			(effects
				(font
					(size 0.7 0.7)
					(thickness 0.15)
				)
				(justify left bottom)
			)
		)
		(fp_text user "${REFERENCE}"
			(at -8 4.7 180)
			(layer "F.Fab")
			(effects
				(font
					(size 0.7 0.7)
					(thickness 0.15)
				)
				(justify left bottom)
			)
		)
		(fp_text user "License: Apache-2.0"
			(at -8 7.1 180)
			(layer "F.Fab")
			(effects
				(font
					(size 0.7 0.7)
					(thickness 0.15)
				)
				(justify left bottom)
			)
		)
		(pad "1" smd rect
			(at -1.436 -0.99 180)
			(size 0.99 0.405)
			(layers "F.Cu" "F.Mask" "F.Paste")
			(net 40 "+5V")
			(pinfunction "S")
			(pintype "passive")
		)
		(pad "2" smd rect
			(at -1.436 -0.332 180)
			(size 0.99 0.405)
			(layers "F.Cu" "F.Mask" "F.Paste")
			(net 40 "+5V")
			(pinfunction "S")
			(pintype "passive")
		)
		(pad "3" smd rect
			(at -1.436 0.33 180)
			(size 0.99 0.405)
			(layers "F.Cu" "F.Mask" "F.Paste")
			(net 40 "+5V")
			(pinfunction "S")
			(pintype "passive")
		)
		(pad "4" smd rect
			(at -1.436 0.988 180)
			(size 0.99 0.405)
			(layers "F.Cu" "F.Mask" "F.Paste")
			(net 433 "Net-(Q8-G)")
			(pinfunction "G")
			(pintype "passive")
		)
		(pad "5" smd custom
			(at 0.557 0 180)
			(size 1.725 2.235)
			(layers "F.Cu" "F.Mask" "F.Paste")
			(net 53 "+5V_USB")
			(pinfunction "D")
			(pintype "passive")
			(zone_connect 2)
			(options
				(clearance outline)
				(anchor rect)
			)
			(primitives
				(gr_poly
					(pts
						(xy 0.8625 0.1275) (xy 0.8625 -0.1275) (xy 1.3725 -0.1275) (xy 1.3725 -0.5325) (xy 0.8625 -0.5325)
						(xy 0.8625 -0.7875) (xy 1.3725 -0.7875) (xy 1.3725 -1.195) (xy 0.6125 -1.195) (xy 0.6125 1.195)
						(xy 1.3725 1.195) (xy 1.3725 0.7875) (xy 0.8625 0.7875) (xy 0.8625 0.5325) (xy 1.3725 0.5325)
						(xy 1.3725 0.1275)
					)
					(width 0)
					(fill yes)
				)
			)
		)
	)
	(footprint "antmicro-footprints:C_0603_1608Metric_EIA"
		(layer "F.Cu")
		(at 154.900002 113)
		(descr "Capacitor SMD 0603, IPC-7351 Density Level A")
		(tags "Capacitor 0603")
		(property "Reference" "C111"
			(at 13.650003 16.799998 0)
			(layer "F.SilkS")
			(effects
				(font
					(size 0.7 0.7)
					(thickness 0.15)
				)
			)
		)
		(property "Value" "C_22u_16V_0603"
			(at -1.42757 1.770288 0)
			(layer "F.Fab")
			(effects
				(font
					(size 0.7 0.7)
					(thickness 0.15)
				)
				(justify left bottom)
			)
		)
		(property "Datasheet" "https://product.samsungsem.com/mlcc/CL10A226MO7JZN.do"
			(at 0 0 0)
			(layer "F.Fab")
			(hide yes)
			(effects
				(font
					(size 1.27 1.27)
					(thickness 0.15)
				)
			)
		)
		(property "Description" "SMD Multilayer Ceramic Capacitor"
			(at 0 0 0)
			(layer "F.Fab")
			(hide yes)
			(effects
				(font
					(size 1.27 1.27)
					(thickness 0.15)
				)
			)
		)
		(property "MPN" "CL10A226MO7JZNC"
			(at 0 0 0)
			(unlocked yes)
			(layer "F.Fab")
			(hide yes)
			(effects
				(font
					(size 1 1)
					(thickness 0.15)
				)
			)
		)
		(property "Manufacturer" "Samsung Electro-Mechanics"
			(at 0 0 0)
			(unlocked yes)
			(layer "F.Fab")
			(hide yes)
			(effects
				(font
					(size 1 1)
					(thickness 0.15)
				)
			)
		)
		(property "License" "Apache-2.0"
			(at 0 0 0)
			(unlocked yes)
			(layer "F.Fab")
			(hide yes)
			(effects
				(font
					(size 1 1)
					(thickness 0.15)
				)
			)
		)
		(property "Author" "Antmicro"
			(at 0 0 0)
			(unlocked yes)
			(layer "F.Fab")
			(hide yes)
			(effects
				(font
					(size 1 1)
					(thickness 0.15)
				)
			)
		)
		(property "Val" "22u"
			(at 0 0 0)
			(unlocked yes)
			(layer "F.Fab")
			(hide yes)
			(effects
				(font
					(size 1 1)
					(thickness 0.15)
				)
			)
		)
		(property "Voltage" "16V"
			(at 0 0 0)
			(unlocked yes)
			(layer "F.Fab")
			(hide yes)
			(effects
				(font
					(size 1 1)
					(thickness 0.15)
				)
			)
		)
		(property "Dielectric" ""
			(at 0 0 0)
			(unlocked yes)
			(layer "F.Fab")
			(hide yes)
			(effects
				(font
					(size 1 1)
					(thickness 0.15)
				)
			)
		)
		(sheetname "/X710 DCDC converters/")
		(sheetfile "DCDC_converters_X710.kicad_sch")
		(attr smd)
		(fp_line
			(start -0.15 -0.55)
			(end 0.15 -0.55)
			(stroke
				(width 0.15)
				(type solid)
			)
			(layer "F.SilkS")
		)
		(fp_line
			(start -0.15 0.55)
			(end 0.15 0.55)
			(stroke
				(width 0.15)
				(type solid)
			)
			(layer "F.SilkS")
		)
		(fp_rect
			(start -1.25 -0.65)
			(end 1.25 0.65)
			(stroke
				(width 0.05)
				(type solid)
			)
			(fill no)
			(layer "F.CrtYd")
		)
		(fp_rect
			(start -0.8 -0.45)
			(end 0.8 0.45)
			(stroke
				(width 0.15)
				(type solid)
			)
			(fill no)
			(layer "F.Fab")
		)
		(fp_text user "Author: Antmicro"
			(at -1.682 4.894 0)
			(layer "F.Fab")
			(effects
				(font
					(size 0.7 0.7)
					(thickness 0.15)
				)
				(justify left bottom)
			)
		)
		(fp_text user "License: Apache-2.0"
			(at -1.682 5.895 0)
			(layer "F.Fab")
			(effects
				(font
					(size 0.7 0.7)
					(thickness 0.15)
				)
				(justify left bottom)
			)
		)
		(fp_text user "${REFERENCE}"
			(at -1.682 3.895 0)
			(layer "F.Fab")
			(effects
				(font
					(size 0.7 0.7)
					(thickness 0.15)
				)
				(justify left bottom)
			)
		)
		(pad "1" smd roundrect
			(at -0.7 0)
			(size 0.8 1.1)
			(layers "F.Cu" "F.Mask" "F.Paste")
			(roundrect_rratio 0.2)
			(net 23 "GND")
			(pintype "passive")
		)
		(pad "2" smd roundrect
			(at 0.7 0)
			(size 0.8 1.1)
			(layers "F.Cu" "F.Mask" "F.Paste")
			(roundrect_rratio 0.2)
			(net 40 "+5V")
			(pintype "passive")
		)
	)
	(footprint "antmicro-footprints:R_0402_1005Metric"
		(layer "F.Cu")
		(at 139.5 145.5 180)
		(descr "Resistor SMD 0402")
		(tags "resistor SMD 0402")
		(property "Reference" "R74"
			(at 0.1 3.7 180)
			(layer "F.SilkS")
			(effects
				(font
					(size 0.7 0.7)
					(thickness 0.15)
				)
				(justify left bottom)
			)
		)
		(property "Value" "R_330R_0402"
			(at -1.011843 1.772047 180)
			(layer "F.Fab")
			(effects
				(font
					(size 0.7 0.7)
					(thickness 0.15)
				)
				(justify left bottom)
			)
		)
		(property "Datasheet" "https://www.bourns.com/docs/product-datasheets/cr.pdf"
			(at 0 0 180)
			(layer "F.Fab")
			(hide yes)
			(effects
				(font
					(size 1.27 1.27)
					(thickness 0.15)
				)
			)
		)
		(property "Description" "SMD Chip Resistor, 330 ohm, ± 1%, 62.5 mW, 0402 [1005 Metric], Thick Film, General Purpose"
			(at 0 0 180)
			(layer "F.Fab")
			(hide yes)
			(effects
				(font
					(size 1.27 1.27)
					(thickness 0.15)
				)
			)
		)
		(property "MPN" "CR0402-FX-3300GLF"
			(at 0 0 180)
			(unlocked yes)
			(layer "F.Fab")
			(hide yes)
			(effects
				(font
					(size 1 1)
					(thickness 0.15)
				)
			)
		)
		(property "Manufacturer" "Bourns"
			(at 0 0 180)
			(unlocked yes)
			(layer "F.Fab")
			(hide yes)
			(effects
				(font
					(size 1 1)
					(thickness 0.15)
				)
			)
		)
		(property "License" "Apache-2.0"
			(at 0 0 180)
			(unlocked yes)
			(layer "F.Fab")
			(hide yes)
			(effects
				(font
					(size 1 1)
					(thickness 0.15)
				)
			)
		)
		(property "Val" "330R"
			(at 0 0 180)
			(unlocked yes)
			(layer "F.Fab")
			(hide yes)
			(effects
				(font
					(size 1 1)
					(thickness 0.15)
				)
			)
		)
		(property "Tolerance" "1%"
			(at 0 0 180)
			(unlocked yes)
			(layer "F.Fab")
			(hide yes)
			(effects
				(font
					(size 1 1)
					(thickness 0.15)
				)
			)
		)
		(property "Author" "Antmicro"
			(at 0 0 180)
			(unlocked yes)
			(layer "F.Fab")
			(hide yes)
			(effects
				(font
					(size 1 1)
					(thickness 0.15)
				)
			)
		)
		(sheetname "/TB Controller - Power/")
		(sheetfile "tb-power.kicad_sch")
		(attr smd)
		(fp_rect
			(start -0.925 -0.47)
			(end 0.925 0.47)
			(stroke
				(width 0.05)
				(type default)
			)
			(fill no)
			(layer "F.CrtYd")
		)
		(fp_rect
			(start -0.5 -0.25)
			(end 0.5 0.25)
			(stroke
				(width 0.15)
				(type solid)
			)
			(fill no)
			(layer "F.Fab")
		)
		(fp_text user "Author: Antmicro"
			(at -0.95 4.169 180)
			(layer "F.Fab")
			(effects
				(font
					(size 0.7 0.7)
					(thickness 0.15)
				)
				(justify left bottom)
			)
		)
		(fp_text user "${REFERENCE}"
			(at -0.95 3.168 180)
			(layer "F.Fab")
			(effects
				(font
					(size 0.7 0.7)
					(thickness 0.15)
				)
				(justify left bottom)
			)
		)
		(fp_text user "License: Apache-2.0"
			(at -0.95 5.169 180)
			(layer "F.Fab")
			(effects
				(font
					(size 0.7 0.7)
					(thickness 0.15)
				)
				(justify left bottom)
			)
		)
		(pad "1" smd roundrect
			(at -0.48 0 180)
			(size 0.59 0.64)
			(layers "F.Cu" "F.Mask" "F.Paste")
			(roundrect_rratio 0.25)
			(net 197 "Net-(Q1-C)")
			(pintype "passive")
		)
		(pad "2" smd roundrect
			(at 0.48 0 180)
			(size 0.59 0.64)
			(layers "F.Cu" "F.Mask" "F.Paste")
			(roundrect_rratio 0.25)
			(net 19 "Net-(D5-C)")
			(pintype "passive")
		)
	)
	(footprint "antmicro-footprints:C_0402_1005Metric"
		(layer "F.Cu")
		(at 145.8 116.4 -90)
		(descr "Capacitor SMD 0402")
		(tags "capacitor SMD 0402")
		(property "Reference" "C103"
			(at 0.4 1.5 270)
			(layer "F.SilkS")
			(effects
				(font
					(size 0.7 0.7)
					(thickness 0.15)
				)
			)
		)
		(property "Value" "C_100n_0402"
			(at -1.022927 2.155213 270)
			(layer "F.Fab")
			(effects
				(font
					(size 0.7 0.7)
					(thickness 0.15)
				)
				(justify left bottom)
			)
		)
		(property "Datasheet" "https://www.murata.com/products/productdetail?partno=GRM155R61H104KE14%23"
			(at 0 0 270)
			(layer "F.Fab")
			(hide yes)
			(effects
				(font
					(size 1.27 1.27)
					(thickness 0.15)
				)
			)
		)
		(property "Description" "SMD Multilayer Ceramic Capacitor, 0.1 µF, 50 V, 0402 [1005 Metric], ± 10%, X5R, GRM Series"
			(at 0 0 270)
			(layer "F.Fab")
			(hide yes)
			(effects
				(font
					(size 1.27 1.27)
					(thickness 0.15)
				)
			)
		)
		(property "MPN" "GRM155R61H104KE14D"
			(at 0 0 270)
			(unlocked yes)
			(layer "F.Fab")
			(hide yes)
			(effects
				(font
					(size 1 1)
					(thickness 0.15)
				)
			)
		)
		(property "Manufacturer" "Murata"
			(at 0 0 270)
			(unlocked yes)
			(layer "F.Fab")
			(hide yes)
			(effects
				(font
					(size 1 1)
					(thickness 0.15)
				)
			)
		)
		(property "License" "Apache-2.0"
			(at 0 0 270)
			(unlocked yes)
			(layer "F.Fab")
			(hide yes)
			(effects
				(font
					(size 1 1)
					(thickness 0.15)
				)
			)
		)
		(property "Val" "100n"
			(at 0 0 270)
			(unlocked yes)
			(layer "F.Fab")
			(hide yes)
			(effects
				(font
					(size 1 1)
					(thickness 0.15)
				)
			)
		)
		(property "Voltage" "50V"
			(at 0 0 270)
			(unlocked yes)
			(layer "F.Fab")
			(hide yes)
			(effects
				(font
					(size 1 1)
					(thickness 0.15)
				)
			)
		)
		(property "Dielectric" "X5R"
			(at 0 0 270)
			(unlocked yes)
			(layer "F.Fab")
			(hide yes)
			(effects
				(font
					(size 1 1)
					(thickness 0.15)
				)
			)
		)
		(property "Author" "Antmicro"
			(at 0 0 270)
			(unlocked yes)
			(layer "F.Fab")
			(hide yes)
			(effects
				(font
					(size 1 1)
					(thickness 0.15)
				)
			)
		)
		(sheetname "/TB flash memory/")
		(sheetfile "flash-memory.kicad_sch")
		(attr smd)
		(fp_rect
			(start -0.925 -0.47)
			(end 0.925 0.47)
			(stroke
				(width 0.05)
				(type default)
			)
			(fill no)
			(layer "F.CrtYd")
		)
		(fp_line
			(start -0.494 0.248)
			(end -0.494 -0.25)
			(stroke
				(width 0.15)
				(type solid)
			)
			(layer "F.Fab")
		)
		(fp_line
			(start 0.504 0.248)
			(end -0.494 0.248)
			(stroke
				(width 0.15)
				(type solid)
			)
			(layer "F.Fab")
		)
		(fp_line
			(start -0.494 -0.25)
			(end 0.504 -0.25)
			(stroke
				(width 0.15)
				(type solid)
			)
			(layer "F.Fab")
		)
		(fp_line
			(start 0.504 -0.25)
			(end 0.504 0.248)
			(stroke
				(width 0.15)
				(type solid)
			)
			(layer "F.Fab")
		)
		(fp_text user "${REFERENCE}"
			(at -0.939 4.599 270)
			(layer "F.Fab")
			(effects
				(font
					(size 0.7 0.7)
					(thickness 0.15)
				)
				(justify left bottom)
			)
		)
		(fp_text user "Author: Antmicro"
			(at -0.939 3.399 270)
			(layer "F.Fab")
			(effects
				(font
					(size 0.7 0.7)
					(thickness 0.15)
				)
				(justify left bottom)
			)
		)
		(fp_text user "License: Apache-2.0"
			(at -0.939 5.799 270)
			(layer "F.Fab")
			(effects
				(font
					(size 0.7 0.7)
					(thickness 0.15)
				)
				(justify left bottom)
			)
		)
		(pad "1" smd roundrect
			(at -0.48 0 270)
			(size 0.59 0.64)
			(layers "F.Cu" "F.Mask" "F.Paste")
			(roundrect_rratio 0.25)
			(net 23 "GND")
			(pintype "passive")
		)
		(pad "2" smd roundrect
			(at 0.48 0 270)
			(size 0.59 0.64)
			(layers "F.Cu" "F.Mask" "F.Paste")
			(roundrect_rratio 0.25)
			(net 57 "+3V3_TB")
			(pintype "passive")
		)
	)
	(footprint "antmicro-footprints:L_Bourns-SRP7028A"
		(layer "F.Cu")
		(at 158.6 56.2 180)
		(property "Reference" "L14"
			(at 6.6 2.4 180)
			(layer "F.SilkS")
			(effects
				(font
					(size 0.7 0.7)
					(thickness 0.15)
				)
				(justify left bottom)
			)
		)
		(property "Value" "L_3u3_6A_Bourns-SRP7028A"
			(at -4.81 4.65 180)
			(layer "F.Fab")
			(effects
				(font
					(size 0.7 0.7)
					(thickness 0.15)
				)
				(justify left bottom)
			)
		)
		(property "Datasheet" "https://www.bourns.com/docs/Product-Datasheets/SRP7028A.pdf"
			(at -0.003 -0.299 180)
			(layer "F.Fab")
			(effects
				(font
					(size 0.7 0.7)
					(thickness 0.15)
				)
				(justify left bottom)
			)
		)
		(property "Description" "Power Inductor (SMD), 3.3 µH, 6 A, 28 mOhm, Shielded, 12 A, SRP7028A Series"
			(at -0.003 -0.299 180)
			(layer "F.Fab")
			(effects
				(font
					(size 0.7 0.7)
					(thickness 0.15)
				)
				(justify left bottom)
			)
		)
		(property "Val" "3u3/6A"
			(at 0 0 180)
			(unlocked yes)
			(layer "F.Fab")
			(hide yes)
			(effects
				(font
					(size 1 1)
					(thickness 0.15)
				)
			)
		)
		(property "Manufacturer" "Bourns"
			(at 0 0 180)
			(unlocked yes)
			(layer "F.Fab")
			(hide yes)
			(effects
				(font
					(size 1 1)
					(thickness 0.15)
				)
			)
		)
		(property "MPN" "SRP7028A-3R3M"
			(at 0 0 180)
			(unlocked yes)
			(layer "F.Fab")
			(hide yes)
			(effects
				(font
					(size 1 1)
					(thickness 0.15)
				)
			)
		)
		(property "ISat" "12 A"
			(at 0 0 180)
			(unlocked yes)
			(layer "F.Fab")
			(hide yes)
			(effects
				(font
					(size 1 1)
					(thickness 0.15)
				)
			)
		)
		(property "IMax" "6 A"
			(at 0 0 180)
			(unlocked yes)
			(layer "F.Fab")
			(hide yes)
			(effects
				(font
					(size 1 1)
					(thickness 0.15)
				)
			)
		)
		(property "Size" "7.3x6.6x2.8"
			(at 0 0 180)
			(unlocked yes)
			(layer "F.Fab")
			(hide yes)
			(effects
				(font
					(size 1 1)
					(thickness 0.15)
				)
			)
		)
		(property "Author" "Antmicro"
			(at 0 0 180)
			(unlocked yes)
			(layer "F.Fab")
			(hide yes)
			(effects
				(font
					(size 1 1)
					(thickness 0.15)
				)
			)
		)
		(property "License" "Apache-2.0"
			(at 0 0 180)
			(unlocked yes)
			(layer "F.Fab")
			(hide yes)
			(effects
				(font
					(size 1 1)
					(thickness 0.15)
				)
			)
		)
		(sheetname "/Power input/")
		(sheetfile "power_input.kicad_sch")
		(attr smd)
		(fp_line
			(start 3.44 2.115)
			(end 3.44 3.39)
			(stroke
				(width 0.15)
				(type solid)
			)
			(layer "F.SilkS")
		)
		(fp_line
			(start 3.44 -2.115)
			(end 3.44 -3.39)
			(stroke
				(width 0.15)
				(type solid)
			)
			(layer "F.SilkS")
		)
		(fp_line
			(start 3.44 -3.39)
			(end -3.44 -3.39)
			(stroke
				(width 0.15)
				(type solid)
			)
			(layer "F.SilkS")
		)
		(fp_line
			(start -3.44 3.39)
			(end 3.44 3.39)
			(stroke
				(width 0.15)
				(type solid)
			)
			(layer "F.SilkS")
		)
		(fp_line
			(start -3.44 2.115)
			(end -3.44 3.39)
			(stroke
				(width 0.15)
				(type solid)
			)
			(layer "F.SilkS")
		)
		(fp_line
			(start -3.44 -2.115)
			(end -3.44 -3.39)
			(stroke
				(width 0.15)
				(type solid)
			)
			(layer "F.SilkS")
		)
		(fp_circle
			(center -4.39 0)
			(end -4.34 0)
			(stroke
				(width 0.15)
				(type solid)
			)
			(fill yes)
			(layer "F.SilkS")
		)
		(fp_rect
			(start -4.5 -3.6)
			(end 4.5 3.6)
			(stroke
				(width 0.05)
				(type solid)
			)
			(fill no)
			(layer "F.CrtYd")
		)
		(fp_text user "License: Apache-2.0"
			(at -4.81 8.25 180)
			(layer "F.Fab")
			(effects
				(font
					(size 0.7 0.7)
					(thickness 0.15)
				)
				(justify left bottom)
			)
		)
		(fp_text user "Author: Antmicro"
			(at -4.81 5.85 180)
			(layer "F.Fab")
			(effects
				(font
					(size 0.7 0.7)
					(thickness 0.15)
				)
				(justify left bottom)
			)
		)
		(fp_text user "${REFERENCE}"
			(at -4.81 7.05 180)
			(layer "F.Fab")
			(effects
				(font
					(size 0.7 0.7)
					(thickness 0.15)
				)
				(justify left bottom)
			)
		)
		(pad "1" smd roundrect
			(at -2.725 0 180)
			(size 2.95 3.5)
			(layers "F.Cu" "F.Mask" "F.Paste")
			(roundrect_rratio 0.05)
			(net 354 "/Power input/5V_SW")
			(pintype "passive")
		)
		(pad "2" smd roundrect
			(at 2.725 0 180)
			(size 2.95 3.5)
			(layers "F.Cu" "F.Mask" "F.Paste")
			(roundrect_rratio 0.05)
			(net 349 "/Power input/5V_OUT")
			(pintype "passive")
		)
	)
	(footprint "antmicro-footprints:C_0402_1005Metric"
		(layer "F.Cu")
		(at 117 73.9)
		(descr "Capacitor SMD 0402")
		(tags "capacitor SMD 0402")
		(property "Reference" "C308"
			(at 3.6 -10.5 0)
			(layer "F.SilkS")
			(effects
				(font
					(size 0.7 0.7)
					(thickness 0.15)
				)
				(justify left bottom)
			)
		)
		(property "Value" "C_1u_0402"
			(at -1.022927 2.155213 0)
			(layer "F.Fab")
			(effects
				(font
					(size 0.7 0.7)
					(thickness 0.15)
				)
				(justify left bottom)
			)
		)
		(property "Datasheet" "https://product.tdk.com/en/search/capacitor/ceramic/mlcc/info?part_no=C1005X6S1A105K050BC"
			(at 0 0 0)
			(layer "F.Fab")
			(hide yes)
			(effects
				(font
					(size 1.27 1.27)
					(thickness 0.15)
				)
			)
		)
		(property "Description" "SMD Multilayer Ceramic Capacitor, 1 µF, 10 V, 0402 [1005 Metric], ± 10%, X6S, C"
			(at 0 0 0)
			(layer "F.Fab")
			(hide yes)
			(effects
				(font
					(size 1.27 1.27)
					(thickness 0.15)
				)
			)
		)
		(property "MPN" "C1005X6S1A105K050BC"
			(at 0 0 0)
			(unlocked yes)
			(layer "F.Fab")
			(hide yes)
			(effects
				(font
					(size 1 1)
					(thickness 0.15)
				)
			)
		)
		(property "Manufacturer" "TDK"
			(at 0 0 0)
			(unlocked yes)
			(layer "F.Fab")
			(hide yes)
			(effects
				(font
					(size 1 1)
					(thickness 0.15)
				)
			)
		)
		(property "License" "Apache-2.0"
			(at 0 0 0)
			(unlocked yes)
			(layer "F.Fab")
			(hide yes)
			(effects
				(font
					(size 1 1)
					(thickness 0.15)
				)
			)
		)
		(property "Author" "Antmicro"
			(at 0 0 0)
			(unlocked yes)
			(layer "F.Fab")
			(hide yes)
			(effects
				(font
					(size 1 1)
					(thickness 0.15)
				)
			)
		)
		(property "Val" "1u"
			(at 0 0 0)
			(unlocked yes)
			(layer "F.Fab")
			(hide yes)
			(effects
				(font
					(size 1 1)
					(thickness 0.15)
				)
			)
		)
		(property "Voltage" ""
			(at 0 0 0)
			(unlocked yes)
			(layer "F.Fab")
			(hide yes)
			(effects
				(font
					(size 1 1)
					(thickness 0.15)
				)
			)
		)
		(property "Dielectric" ""
			(at 0 0 0)
			(unlocked yes)
			(layer "F.Fab")
			(hide yes)
			(effects
				(font
					(size 1 1)
					(thickness 0.15)
				)
			)
		)
		(sheetname "/Fan controller/")
		(sheetfile "fan-controller.kicad_sch")
		(attr smd)
		(fp_rect
			(start -0.925 -0.47)
			(end 0.925 0.47)
			(stroke
				(width 0.05)
				(type default)
			)
			(fill no)
			(layer "F.CrtYd")
		)
		(fp_line
			(start -0.494 -0.25)
			(end 0.504 -0.25)
			(stroke
				(width 0.15)
				(type solid)
			)
			(layer "F.Fab")
		)
		(fp_line
			(start -0.494 0.248)
			(end -0.494 -0.25)
			(stroke
				(width 0.15)
				(type solid)
			)
			(layer "F.Fab")
		)
		(fp_line
			(start 0.504 -0.25)
			(end 0.504 0.248)
			(stroke
				(width 0.15)
				(type solid)
			)
			(layer "F.Fab")
		)
		(fp_line
			(start 0.504 0.248)
			(end -0.494 0.248)
			(stroke
				(width 0.15)
				(type solid)
			)
			(layer "F.Fab")
		)
		(fp_text user "License: Apache-2.0"
			(at -0.939 5.799 0)
			(layer "F.Fab")
			(effects
				(font
					(size 0.7 0.7)
					(thickness 0.15)
				)
				(justify left bottom)
			)
		)
		(fp_text user "${REFERENCE}"
			(at -0.939 4.599 0)
			(layer "F.Fab")
			(effects
				(font
					(size 0.7 0.7)
					(thickness 0.15)
				)
				(justify left bottom)
			)
		)
		(fp_text user "Author: Antmicro"
			(at -0.939 3.399 0)
			(layer "F.Fab")
			(effects
				(font
					(size 0.7 0.7)
					(thickness 0.15)
				)
				(justify left bottom)
			)
		)
		(pad "1" smd roundrect
			(at -0.48 0)
			(size 0.59 0.64)
			(layers "F.Cu" "F.Mask" "F.Paste")
			(roundrect_rratio 0.25)
			(net 23 "GND")
			(pintype "passive")
		)
		(pad "2" smd roundrect
			(at 0.48 0)
			(size 0.59 0.64)
			(layers "F.Cu" "F.Mask" "F.Paste")
			(roundrect_rratio 0.25)
			(net 151 "/Fan controller/SENSE")
			(pintype "passive")
		)
	)
	(footprint "antmicro-footprints:C_0402_1005Metric"
		(layer "F.Cu")
		(at 165.265 62 90)
		(descr "Capacitor SMD 0402")
		(tags "capacitor SMD 0402")
		(property "Reference" "C282"
			(at 5.8 -0.065 90)
			(layer "F.SilkS")
			(effects
				(font
					(size 0.7 0.7)
					(thickness 0.15)
				)
				(justify left bottom)
			)
		)
		(property "Value" "C_100n_0402"
			(at -1.022927 2.155213 90)
			(layer "F.Fab")
			(effects
				(font
					(size 0.7 0.7)
					(thickness 0.15)
				)
				(justify left bottom)
			)
		)
		(property "Datasheet" "https://www.murata.com/products/productdetail?partno=GRM155R61H104KE14%23"
			(at 0 0 90)
			(layer "F.Fab")
			(hide yes)
			(effects
				(font
					(size 1.27 1.27)
					(thickness 0.15)
				)
			)
		)
		(property "Description" "SMD Multilayer Ceramic Capacitor, 0.1 µF, 50 V, 0402 [1005 Metric], ± 10%, X5R, GRM Series"
			(at 0 0 90)
			(layer "F.Fab")
			(hide yes)
			(effects
				(font
					(size 1.27 1.27)
					(thickness 0.15)
				)
			)
		)
		(property "MPN" "GRM155R61H104KE14D"
			(at 0 0 90)
			(unlocked yes)
			(layer "F.Fab")
			(hide yes)
			(effects
				(font
					(size 1 1)
					(thickness 0.15)
				)
			)
		)
		(property "Val" "100n"
			(at 0 0 90)
			(unlocked yes)
			(layer "F.Fab")
			(hide yes)
			(effects
				(font
					(size 1 1)
					(thickness 0.15)
				)
			)
		)
		(property "Voltage" "50V"
			(at 0 0 90)
			(unlocked yes)
			(layer "F.Fab")
			(hide yes)
			(effects
				(font
					(size 1 1)
					(thickness 0.15)
				)
			)
		)
		(property "Dielectric" "X5R"
			(at 0 0 90)
			(unlocked yes)
			(layer "F.Fab")
			(hide yes)
			(effects
				(font
					(size 1 1)
					(thickness 0.15)
				)
			)
		)
		(property "Manufacturer" "Murata"
			(at 0 0 90)
			(unlocked yes)
			(layer "F.Fab")
			(hide yes)
			(effects
				(font
					(size 1 1)
					(thickness 0.15)
				)
			)
		)
		(property "License" "Apache-2.0"
			(at 0 0 90)
			(unlocked yes)
			(layer "F.Fab")
			(hide yes)
			(effects
				(font
					(size 1 1)
					(thickness 0.15)
				)
			)
		)
		(property "Author" "Antmicro"
			(at 0 0 90)
			(unlocked yes)
			(layer "F.Fab")
			(hide yes)
			(effects
				(font
					(size 1 1)
					(thickness 0.15)
				)
			)
		)
		(sheetname "/X710-AT2 10GbE/")
		(sheetfile "x710-at2-10gbe.kicad_sch")
		(attr smd)
		(fp_rect
			(start -0.925 -0.47)
			(end 0.925 0.47)
			(stroke
				(width 0.05)
				(type default)
			)
			(fill no)
			(layer "F.CrtYd")
		)
		(fp_line
			(start 0.504 -0.25)
			(end 0.504 0.248)
			(stroke
				(width 0.15)
				(type solid)
			)
			(layer "F.Fab")
		)
		(fp_line
			(start -0.494 -0.25)
			(end 0.504 -0.25)
			(stroke
				(width 0.15)
				(type solid)
			)
			(layer "F.Fab")
		)
		(fp_line
			(start 0.504 0.248)
			(end -0.494 0.248)
			(stroke
				(width 0.15)
				(type solid)
			)
			(layer "F.Fab")
		)
		(fp_line
			(start -0.494 0.248)
			(end -0.494 -0.25)
			(stroke
				(width 0.15)
				(type solid)
			)
			(layer "F.Fab")
		)
		(fp_text user "License: Apache-2.0"
			(at -0.939 5.799 90)
			(layer "F.Fab")
			(effects
				(font
					(size 0.7 0.7)
					(thickness 0.15)
				)
				(justify left bottom)
			)
		)
		(fp_text user "${REFERENCE}"
			(at -0.939 4.599 90)
			(layer "F.Fab")
			(effects
				(font
					(size 0.7 0.7)
					(thickness 0.15)
				)
				(justify left bottom)
			)
		)
		(fp_text user "Author: Antmicro"
			(at -0.939 3.399 90)
			(layer "F.Fab")
			(effects
				(font
					(size 0.7 0.7)
					(thickness 0.15)
				)
				(justify left bottom)
			)
		)
		(pad "1" smd roundrect
			(at -0.48 0 90)
			(size 0.59 0.64)
			(layers "F.Cu" "F.Mask" "F.Paste")
			(roundrect_rratio 0.25)
			(net 23 "GND")
			(pintype "passive")
		)
		(pad "2" smd roundrect
			(at 0.48 0 90)
			(size 0.59 0.64)
			(layers "F.Cu" "F.Mask" "F.Paste")
			(roundrect_rratio 0.25)
			(net 7 "+3V3")
			(pintype "passive")
		)
	)
	(footprint "antmicro-footprints:R_0402_1005Metric"
		(layer "F.Cu")
		(at 124 72)
		(descr "Resistor SMD 0402")
		(tags "resistor SMD 0402")
		(property "Reference" "R220"
			(at 1 -0.3 0)
			(layer "F.SilkS")
			(effects
				(font
					(size 0.7 0.7)
					(thickness 0.15)
				)
				(justify left bottom)
			)
		)
		(property "Value" "R_0R_0402"
			(at -1.011843 1.772047 0)
			(layer "F.Fab")
			(effects
				(font
					(size 0.7 0.7)
					(thickness 0.15)
				)
				(justify left bottom)
			)
		)
		(property "Datasheet" "https://industrial.panasonic.com/cdbs/www-data/pdf/RDA0000/AOA0000C301.pdf"
			(at 0 0 0)
			(layer "F.Fab")
			(hide yes)
			(effects
				(font
					(size 1.27 1.27)
					(thickness 0.15)
				)
			)
		)
		(property "Description" "SMD Chip Resistor, Jumper, 0 ohm, 100 mW, 0402 [1005 Metric], Thick Film, General Purpose"
			(at 0 0 0)
			(layer "F.Fab")
			(hide yes)
			(effects
				(font
					(size 1.27 1.27)
					(thickness 0.15)
				)
			)
		)
		(property "MPN" "ERJ2GE0R00X"
			(at 0 0 0)
			(unlocked yes)
			(layer "F.Fab")
			(hide yes)
			(effects
				(font
					(size 1 1)
					(thickness 0.15)
				)
			)
		)
		(property "Manufacturer" "Panasonic"
			(at 0 0 0)
			(unlocked yes)
			(layer "F.Fab")
			(hide yes)
			(effects
				(font
					(size 1 1)
					(thickness 0.15)
				)
			)
		)
		(property "License" "Apache-2.0"
			(at 0 0 0)
			(unlocked yes)
			(layer "F.Fab")
			(hide yes)
			(effects
				(font
					(size 1 1)
					(thickness 0.15)
				)
			)
		)
		(property "Author" "Antmicro"
			(at 0 0 0)
			(unlocked yes)
			(layer "F.Fab")
			(hide yes)
			(effects
				(font
					(size 1 1)
					(thickness 0.15)
				)
			)
		)
		(property "Val" "0R"
			(at 0 0 0)
			(unlocked yes)
			(layer "F.Fab")
			(hide yes)
			(effects
				(font
					(size 1 1)
					(thickness 0.15)
				)
			)
		)
		(property "Tolerance" "~"
			(at 0 0 0)
			(unlocked yes)
			(layer "F.Fab")
			(hide yes)
			(effects
				(font
					(size 1 1)
					(thickness 0.15)
				)
			)
		)
		(property "Current" "1A"
			(at 0 0 0)
			(unlocked yes)
			(layer "F.Fab")
			(hide yes)
			(effects
				(font
					(size 1 1)
					(thickness 0.15)
				)
			)
		)
		(sheetname "/Fan controller/")
		(sheetfile "fan-controller.kicad_sch")
		(attr smd dnp)
		(fp_rect
			(start -0.925 -0.47)
			(end 0.925 0.47)
			(stroke
				(width 0.05)
				(type default)
			)
			(fill no)
			(layer "F.CrtYd")
		)
		(fp_rect
			(start -0.5 -0.25)
			(end 0.5 0.25)
			(stroke
				(width 0.15)
				(type solid)
			)
			(fill no)
			(layer "F.Fab")
		)
		(fp_text user "${REFERENCE}"
			(at -0.95 3.168 0)
			(layer "F.Fab")
			(effects
				(font
					(size 0.7 0.7)
					(thickness 0.15)
				)
				(justify left bottom)
			)
		)
		(fp_text user "Author: Antmicro"
			(at -0.95 4.169 0)
			(layer "F.Fab")
			(effects
				(font
					(size 0.7 0.7)
					(thickness 0.15)
				)
				(justify left bottom)
			)
		)
		(fp_text user "License: Apache-2.0"
			(at -0.95 5.169 0)
			(layer "F.Fab")
			(effects
				(font
					(size 0.7 0.7)
					(thickness 0.15)
				)
				(justify left bottom)
			)
		)
		(pad "1" smd roundrect
			(at -0.48 0)
			(size 0.59 0.64)
			(layers "F.Cu" "F.Mask" "F.Paste")
			(roundrect_rratio 0.25)
			(net 156 "/Fan controller/D0")
			(pintype "passive")
		)
		(pad "2" smd roundrect
			(at 0.48 0)
			(size 0.59 0.64)
			(layers "F.Cu" "F.Mask" "F.Paste")
			(roundrect_rratio 0.25)
			(net 40 "+5V")
			(pintype "passive")
		)
	)
	(footprint "antmicro-footprints:C_0402_1005Metric"
		(layer "F.Cu")
		(at 165.5 67.8 180)
		(descr "Capacitor SMD 0402")
		(tags "capacitor SMD 0402")
		(property "Reference" "C277"
			(at 0.9 0.6 180)
			(layer "F.SilkS")
			(effects
				(font
					(size 0.7 0.7)
					(thickness 0.15)
				)
				(justify left bottom)
			)
		)
		(property "Value" "C_100n_0402"
			(at -1.022927 2.155213 180)
			(layer "F.Fab")
			(effects
				(font
					(size 0.7 0.7)
					(thickness 0.15)
				)
				(justify left bottom)
			)
		)
		(property "Datasheet" "https://www.murata.com/products/productdetail?partno=GRM155R61H104KE14%23"
			(at 0 0 180)
			(layer "F.Fab")
			(hide yes)
			(effects
				(font
					(size 1.27 1.27)
					(thickness 0.15)
				)
			)
		)
		(property "Description" "SMD Multilayer Ceramic Capacitor, 0.1 µF, 50 V, 0402 [1005 Metric], ± 10%, X5R, GRM Series"
			(at 0 0 180)
			(layer "F.Fab")
			(hide yes)
			(effects
				(font
					(size 1.27 1.27)
					(thickness 0.15)
				)
			)
		)
		(property "MPN" "GRM155R61H104KE14D"
			(at 0 0 180)
			(unlocked yes)
			(layer "F.Fab")
			(hide yes)
			(effects
				(font
					(size 1 1)
					(thickness 0.15)
				)
			)
		)
		(property "Val" "100n"
			(at 0 0 180)
			(unlocked yes)
			(layer "F.Fab")
			(hide yes)
			(effects
				(font
					(size 1 1)
					(thickness 0.15)
				)
			)
		)
		(property "Voltage" "50V"
			(at 0 0 180)
			(unlocked yes)
			(layer "F.Fab")
			(hide yes)
			(effects
				(font
					(size 1 1)
					(thickness 0.15)
				)
			)
		)
		(property "Dielectric" "X5R"
			(at 0 0 180)
			(unlocked yes)
			(layer "F.Fab")
			(hide yes)
			(effects
				(font
					(size 1 1)
					(thickness 0.15)
				)
			)
		)
		(property "Manufacturer" "Murata"
			(at 0 0 180)
			(unlocked yes)
			(layer "F.Fab")
			(hide yes)
			(effects
				(font
					(size 1 1)
					(thickness 0.15)
				)
			)
		)
		(property "License" "Apache-2.0"
			(at 0 0 180)
			(unlocked yes)
			(layer "F.Fab")
			(hide yes)
			(effects
				(font
					(size 1 1)
					(thickness 0.15)
				)
			)
		)
		(property "Author" "Antmicro"
			(at 0 0 180)
			(unlocked yes)
			(layer "F.Fab")
			(hide yes)
			(effects
				(font
					(size 1 1)
					(thickness 0.15)
				)
			)
		)
		(sheetname "/X710-AT2 Misc/")
		(sheetfile "x710-at2-mics.kicad_sch")
		(attr smd)
		(fp_rect
			(start -0.925 -0.47)
			(end 0.925 0.47)
			(stroke
				(width 0.05)
				(type default)
			)
			(fill no)
			(layer "F.CrtYd")
		)
		(fp_line
			(start 0.504 0.248)
			(end -0.494 0.248)
			(stroke
				(width 0.15)
				(type solid)
			)
			(layer "F.Fab")
		)
		(fp_line
			(start 0.504 -0.25)
			(end 0.504 0.248)
			(stroke
				(width 0.15)
				(type solid)
			)
			(layer "F.Fab")
		)
		(fp_line
			(start -0.494 0.248)
			(end -0.494 -0.25)
			(stroke
				(width 0.15)
				(type solid)
			)
			(layer "F.Fab")
		)
		(fp_line
			(start -0.494 -0.25)
			(end 0.504 -0.25)
			(stroke
				(width 0.15)
				(type solid)
			)
			(layer "F.Fab")
		)
		(fp_text user "${REFERENCE}"
			(at -0.939 4.599 180)
			(layer "F.Fab")
			(effects
				(font
					(size 0.7 0.7)
					(thickness 0.15)
				)
				(justify left bottom)
			)
		)
		(fp_text user "License: Apache-2.0"
			(at -0.939 5.799 180)
			(layer "F.Fab")
			(effects
				(font
					(size 0.7 0.7)
					(thickness 0.15)
				)
				(justify left bottom)
			)
		)
		(fp_text user "Author: Antmicro"
			(at -0.939 3.399 180)
			(layer "F.Fab")
			(effects
				(font
					(size 0.7 0.7)
					(thickness 0.15)
				)
				(justify left bottom)
			)
		)
		(pad "1" smd roundrect
			(at -0.48 0 180)
			(size 0.59 0.64)
			(layers "F.Cu" "F.Mask" "F.Paste")
			(roundrect_rratio 0.25)
			(net 23 "GND")
			(pintype "passive")
		)
		(pad "2" smd roundrect
			(at 0.48 0 180)
			(size 0.59 0.64)
			(layers "F.Cu" "F.Mask" "F.Paste")
			(roundrect_rratio 0.25)
			(net 18 "+1V88")
			(pintype "passive")
		)
	)
	(footprint "antmicro-footprints:C_0805_2012Metric"
		(layer "F.Cu")
		(at 119.65 111.75 180)
		(descr "Capacitor SMD 0805")
		(tags "capacitor SMD 0805")
		(property "Reference" "C9"
			(at -6.55 -4.45 180)
			(layer "F.SilkS")
			(effects
				(font
					(size 0.7 0.7)
					(thickness 0.15)
				)
			)
		)
		(property "Value" "C_22u_25V_0805"
			(at -2.055717 1.963152 180)
			(layer "F.Fab")
			(effects
				(font
					(size 0.7 0.7)
					(thickness 0.15)
				)
				(justify left bottom)
			)
		)
		(property "Datasheet" "https://product.samsungsem.com/mlcc/CL21A226MAYNNN.do"
			(at 0 0 180)
			(layer "F.Fab")
			(hide yes)
			(effects
				(font
					(size 1.27 1.27)
					(thickness 0.15)
				)
			)
		)
		(property "Description" "SMT Multilayer Ceramic Capacitor, 22uF, +/-20%, 25V, X5R, 0805 [2012 Metric]"
			(at 0 0 180)
			(layer "F.Fab")
			(hide yes)
			(effects
				(font
					(size 1.27 1.27)
					(thickness 0.15)
				)
			)
		)
		(property "MPN" "CL21A226MAYNNNE"
			(at 0 0 180)
			(unlocked yes)
			(layer "F.Fab")
			(hide yes)
			(effects
				(font
					(size 1 1)
					(thickness 0.15)
				)
			)
		)
		(property "Manufacturer" "Samsung Electro-Mechanics"
			(at 0 0 180)
			(unlocked yes)
			(layer "F.Fab")
			(hide yes)
			(effects
				(font
					(size 1 1)
					(thickness 0.15)
				)
			)
		)
		(property "License" "Apache-2.0"
			(at 0 0 180)
			(unlocked yes)
			(layer "F.Fab")
			(hide yes)
			(effects
				(font
					(size 1 1)
					(thickness 0.15)
				)
			)
		)
		(property "Author" "Antmicro"
			(at 0 0 180)
			(unlocked yes)
			(layer "F.Fab")
			(hide yes)
			(effects
				(font
					(size 1 1)
					(thickness 0.15)
				)
			)
		)
		(property "Val" "22u"
			(at 0 0 180)
			(unlocked yes)
			(layer "F.Fab")
			(hide yes)
			(effects
				(font
					(size 1 1)
					(thickness 0.15)
				)
			)
		)
		(property "Voltage" "25V"
			(at 0 0 180)
			(unlocked yes)
			(layer "F.Fab")
			(hide yes)
			(effects
				(font
					(size 1 1)
					(thickness 0.15)
				)
			)
		)
		(property "Dielectric" "X5R"
			(at 0 0 180)
			(unlocked yes)
			(layer "F.Fab")
			(hide yes)
			(effects
				(font
					(size 1 1)
					(thickness 0.15)
				)
			)
		)
		(property "Public" "False"
			(at 0 0 180)
			(unlocked yes)
			(layer "F.Fab")
			(hide yes)
			(effects
				(font
					(size 1 1)
					(thickness 0.15)
				)
			)
		)
		(sheetname "/PD and TB DC-DC/")
		(sheetfile "PD_and_TB_DC_DC.kicad_sch")
		(attr smd)
		(fp_line
			(start -0.3 0.7)
			(end 0.3 0.7)
			(stroke
				(width 0.15)
				(type solid)
			)
			(layer "F.SilkS")
		)
		(fp_line
			(start -0.3 -0.7)
			(end 0.3 -0.7)
			(stroke
				(width 0.15)
				(type solid)
			)
			(layer "F.SilkS")
		)
		(fp_rect
			(start 1.95 -0.9)
			(end -1.95 0.9)
			(stroke
				(width 0.05)
				(type default)
			)
			(fill no)
			(layer "F.CrtYd")
		)
		(fp_rect
			(start -0.95 -0.675)
			(end 0.95 0.675)
			(stroke
				(width 0.15)
				(type solid)
			)
			(fill no)
			(layer "F.Fab")
		)
		(fp_text user "${REFERENCE}"
			(at -1.9 3.947 180)
			(layer "F.Fab")
			(effects
				(font
					(size 0.7 0.7)
					(thickness 0.15)
				)
				(justify left bottom)
			)
		)
		(fp_text user "License: Apache-2.0"
			(at -1.9 4.947 180)
			(layer "F.Fab")
			(effects
				(font
					(size 0.7 0.7)
					(thickness 0.15)
				)
				(justify left bottom)
			)
		)
		(fp_text user "Author: Antmicro"
			(at -1.9 5.947 180)
			(layer "F.Fab")
			(effects
				(font
					(size 0.7 0.7)
					(thickness 0.15)
				)
				(justify left bottom)
			)
		)
		(pad "1" smd roundrect
			(at -1.1 0 180)
			(size 1.2 1.3)
			(layers "F.Cu" "F.Mask" "F.Paste")
			(roundrect_rratio 0.25)
			(net 23 "GND")
			(pintype "passive")
		)
		(pad "2" smd roundrect
			(at 1.1 0 180)
			(size 1.2 1.3)
			(layers "F.Cu" "F.Mask" "F.Paste")
			(roundrect_rratio 0.25)
			(net 161 "Net-(U2-VIN)")
			(pintype "passive")
		)
	)
	(footprint "antmicro-footprints:TSOT23-6"
		(layer "F.Cu")
		(at 117.55 142.825 -90)
		(property "Reference" "U1"
			(at -0.225 -2.85 270)
			(layer "F.SilkS")
			(effects
				(font
					(size 0.7 0.7)
					(thickness 0.15)
				)
				(justify left bottom)
			)
		)
		(property "Value" "AP22615A_TSOT26"
			(at 0 2.6 270)
			(layer "F.Fab")
			(effects
				(font
					(size 0.7 0.7)
					(thickness 0.15)
				)
				(justify left bottom)
			)
		)
		(property "Datasheet" "https://www.mouser.com/datasheet/2/115/DIOD_S_A0008958405_1-2543193.pdf"
			(at 0 0 270)
			(layer "F.Fab")
			(hide yes)
			(effects
				(font
					(size 1.27 1.27)
					(thickness 0.15)
				)
			)
		)
		(property "Description" "Power Load Distribution Switch, High Side, Active High, 1 Output, 5.5 V, 3.6 A, 0.04 ohm, TSOT-26-6"
			(at 0 0 270)
			(layer "F.Fab")
			(hide yes)
			(effects
				(font
					(size 1.27 1.27)
					(thickness 0.15)
				)
			)
		)
		(property "MPN" "AP22615AWU-7"
			(at 0 0 270)
			(unlocked yes)
			(layer "F.Fab")
			(hide yes)
			(effects
				(font
					(size 1 1)
					(thickness 0.15)
				)
			)
		)
		(property "Manufacturer" "Diodes Incorporated"
			(at 0 0 270)
			(unlocked yes)
			(layer "F.Fab")
			(hide yes)
			(effects
				(font
					(size 1 1)
					(thickness 0.15)
				)
			)
		)
		(property "Author" "Antmicro"
			(at 0 0 270)
			(unlocked yes)
			(layer "F.Fab")
			(hide yes)
			(effects
				(font
					(size 1 1)
					(thickness 0.15)
				)
			)
		)
		(property "License" "Apache-2.0"
			(at 0 0 270)
			(unlocked yes)
			(layer "F.Fab")
			(hide yes)
			(effects
				(font
					(size 1 1)
					(thickness 0.15)
				)
			)
		)
		(sheetname "/USB-C connector/")
		(sheetfile "USB-C_connector.kicad_sch")
		(attr smd)
		(fp_line
			(start -1 1.55)
			(end -1 1.4)
			(stroke
				(width 0.15)
				(type solid)
			)
			(layer "F.SilkS")
		)
		(fp_line
			(start 1 1.55)
			(end -1 1.55)
			(stroke
				(width 0.15)
				(type solid)
			)
			(layer "F.SilkS")
		)
		(fp_line
			(start 1 1.55)
			(end 1 1.4)
			(stroke
				(width 0.15)
				(type solid)
			)
			(layer "F.SilkS")
		)
		(fp_line
			(start 1 -1.497)
			(end 1 -1.375)
			(stroke
				(width 0.15)
				(type solid)
			)
			(layer "F.SilkS")
		)
		(fp_line
			(start 1 -1.497)
			(end -1 -1.5)
			(stroke
				(width 0.15)
				(type solid)
			)
			(layer "F.SilkS")
		)
		(fp_line
			(start -1 -1.5)
			(end -1 -1.375)
			(stroke
				(width 0.15)
				(type solid)
			)
			(layer "F.SilkS")
		)
		(fp_circle
			(center -1.44 -1.5)
			(end -1.39 -1.5)
			(stroke
				(width 0.15)
				(type solid)
			)
			(fill yes)
			(layer "F.SilkS")
		)
		(fp_rect
			(start 1.93 -1.7)
			(end -1.93 1.7)
			(stroke
				(width 0.05)
				(type solid)
			)
			(fill no)
			(layer "F.CrtYd")
		)
		(fp_line
			(start -0.45 -1.521)
			(end -0.876 -1.096)
			(stroke
				(width 0.15)
				(type solid)
			)
			(layer "F.Fab")
		)
		(fp_rect
			(start 0.875 1.528)
			(end -0.875 -1.525)
			(stroke
				(width 0.15)
				(type solid)
			)
			(fill no)
			(layer "F.Fab")
		)
		(fp_text user "${REFERENCE}"
			(at -1.93 3.8 270)
			(layer "F.Fab")
			(effects
				(font
					(size 0.7 0.7)
					(thickness 0.15)
				)
				(justify left bottom)
			)
		)
		(fp_text user "Author: Antmicro"
			(at -1.93 5 270)
			(layer "F.Fab")
			(effects
				(font
					(size 0.7 0.7)
					(thickness 0.15)
				)
				(justify left bottom)
			)
		)
		(fp_text user "License: Apache-2.0"
			(at -1.93 6.199 270)
			(layer "F.Fab")
			(effects
				(font
					(size 0.7 0.7)
					(thickness 0.15)
				)
				(justify left bottom)
			)
		)
		(pad "1" smd rect
			(at -1.301 -0.947 180)
			(size 0.7 1.2)
			(layers "F.Cu" "F.Mask" "F.Paste")
			(net 53 "+5V_USB")
			(pinfunction "OUT")
			(pintype "power_out")
		)
		(pad "2" smd rect
			(at -1.301 0.004 180)
			(size 0.7 1.2)
			(layers "F.Cu" "F.Mask" "F.Paste")
			(net 23 "GND")
			(pinfunction "GND")
			(pintype "power_in")
		)
		(pad "3" smd rect
			(at -1.301 0.954 180)
			(size 0.7 1.2)
			(layers "F.Cu" "F.Mask" "F.Paste")
			(net 447 "unconnected-(U1-FLG-Pad3)")
			(pinfunction "FLG")
			(pintype "output+no_connect")
		)
		(pad "4" smd rect
			(at 1.299 0.954 180)
			(size 0.7 1.2)
			(layers "F.Cu" "F.Mask" "F.Paste")
			(net 215 "/USB-C connector/VBUS")
			(pinfunction "EN")
			(pintype "input")
		)
		(pad "5" smd rect
			(at 1.299 0.004 180)
			(size 0.7 1.2)
			(layers "F.Cu" "F.Mask" "F.Paste")
			(net 434 "Net-(U1-ISET)")
			(pinfunction "ISET")
			(pintype "passive")
		)
		(pad "6" smd rect
			(at 1.299 -0.947 180)
			(size 0.7 1.2)
			(layers "F.Cu" "F.Mask" "F.Paste")
			(net 215 "/USB-C connector/VBUS")
			(pinfunction "IN")
			(pintype "power_in")
		)
	)
	(footprint "antmicro-footprints:R_0402_1005Metric"
		(layer "F.Cu")
		(at 155.255 65.174999 90)
		(descr "Resistor SMD 0402")
		(tags "resistor SMD 0402")
		(property "Reference" "R157"
			(at 2.374999 0.095001 90)
			(layer "F.SilkS")
			(effects
				(font
					(size 0.7 0.7)
					(thickness 0.15)
				)
			)
		)
		(property "Value" "R_100k_0402"
			(at -1.011843 1.772047 90)
			(layer "F.Fab")
			(effects
				(font
					(size 0.7 0.7)
					(thickness 0.15)
				)
				(justify left bottom)
			)
		)
		(property "Datasheet" "https://www.bourns.com/docs/product-datasheets/cr.pdf"
			(at 0 0 90)
			(layer "F.Fab")
			(hide yes)
			(effects
				(font
					(size 1.27 1.27)
					(thickness 0.15)
				)
			)
		)
		(property "Description" "SMD Chip Resistor, 100 kohm, ± 1%, 62.5 mW, 0402 [1005 Metric], Thick Film, General Purpose"
			(at 0 0 90)
			(layer "F.Fab")
			(hide yes)
			(effects
				(font
					(size 1.27 1.27)
					(thickness 0.15)
				)
			)
		)
		(property "MPN" "CR0402-FX-1003GLF"
			(at 0 0 90)
			(unlocked yes)
			(layer "F.Fab")
			(hide yes)
			(effects
				(font
					(size 1 1)
					(thickness 0.15)
				)
			)
		)
		(property "Manufacturer" "Bourns"
			(at 0 0 90)
			(unlocked yes)
			(layer "F.Fab")
			(hide yes)
			(effects
				(font
					(size 1 1)
					(thickness 0.15)
				)
			)
		)
		(property "License" "Apache-2.0"
			(at 0 0 90)
			(unlocked yes)
			(layer "F.Fab")
			(hide yes)
			(effects
				(font
					(size 1 1)
					(thickness 0.15)
				)
			)
		)
		(property "Author" "Antmicro"
			(at 0 0 90)
			(unlocked yes)
			(layer "F.Fab")
			(hide yes)
			(effects
				(font
					(size 1 1)
					(thickness 0.15)
				)
			)
		)
		(property "Val" "100k"
			(at 0 0 90)
			(unlocked yes)
			(layer "F.Fab")
			(hide yes)
			(effects
				(font
					(size 1 1)
					(thickness 0.15)
				)
			)
		)
		(property "Tolerance" "1%"
			(at 0 0 90)
			(unlocked yes)
			(layer "F.Fab")
			(hide yes)
			(effects
				(font
					(size 1 1)
					(thickness 0.15)
				)
			)
		)
		(sheetname "/X710-AT2 Misc/")
		(sheetfile "x710-at2-mics.kicad_sch")
		(attr smd)
		(fp_rect
			(start -0.925 -0.47)
			(end 0.925 0.47)
			(stroke
				(width 0.05)
				(type default)
			)
			(fill no)
			(layer "F.CrtYd")
		)
		(fp_rect
			(start -0.5 -0.25)
			(end 0.5 0.25)
			(stroke
				(width 0.15)
				(type solid)
			)
			(fill no)
			(layer "F.Fab")
		)
		(fp_text user "License: Apache-2.0"
			(at -0.95 5.169 90)
			(layer "F.Fab")
			(effects
				(font
					(size 0.7 0.7)
					(thickness 0.15)
				)
				(justify left bottom)
			)
		)
		(fp_text user "${REFERENCE}"
			(at -0.95 3.168 90)
			(layer "F.Fab")
			(effects
				(font
					(size 0.7 0.7)
					(thickness 0.15)
				)
				(justify left bottom)
			)
		)
		(fp_text user "Author: Antmicro"
			(at -0.95 4.169 90)
			(layer "F.Fab")
			(effects
				(font
					(size 0.7 0.7)
					(thickness 0.15)
				)
				(justify left bottom)
			)
		)
		(pad "1" smd roundrect
			(at -0.48 0 90)
			(size 0.59 0.64)
			(layers "F.Cu" "F.Mask" "F.Paste")
			(roundrect_rratio 0.25)
			(net 23 "GND")
			(pintype "passive")
		)
		(pad "2" smd roundrect
			(at 0.48 0 90)
			(size 0.59 0.64)
			(layers "F.Cu" "F.Mask" "F.Paste")
			(roundrect_rratio 0.25)
			(net 144 "/X710-AT2 Misc/NCSI.REF_CLK")
			(pintype "passive")
		)
	)
	(footprint "antmicro-footprints:C_0402_1005Metric"
		(layer "F.Cu")
		(at 147.2 111.85)
		(descr "Capacitor SMD 0402")
		(tags "capacitor SMD 0402")
		(property "Reference" "C118"
			(at 14.850002 16.75 0)
			(layer "F.SilkS")
			(effects
				(font
					(size 0.7 0.7)
					(thickness 0.15)
				)
			)
		)
		(property "Value" "C_100n_0402"
			(at -1.022927 2.155213 0)
			(layer "F.Fab")
			(effects
				(font
					(size 0.7 0.7)
					(thickness 0.15)
				)
				(justify left bottom)
			)
		)
		(property "Datasheet" "https://www.murata.com/products/productdetail?partno=GRM155R61H104KE14%23"
			(at 0 0 0)
			(layer "F.Fab")
			(hide yes)
			(effects
				(font
					(size 1.27 1.27)
					(thickness 0.15)
				)
			)
		)
		(property "Description" "SMD Multilayer Ceramic Capacitor, 0.1 µF, 50 V, 0402 [1005 Metric], ± 10%, X5R, GRM Series"
			(at 0 0 0)
			(layer "F.Fab")
			(hide yes)
			(effects
				(font
					(size 1.27 1.27)
					(thickness 0.15)
				)
			)
		)
		(property "MPN" "GRM155R61H104KE14D"
			(at 0 0 0)
			(unlocked yes)
			(layer "F.Fab")
			(hide yes)
			(effects
				(font
					(size 1 1)
					(thickness 0.15)
				)
			)
		)
		(property "Manufacturer" "Murata"
			(at 0 0 0)
			(unlocked yes)
			(layer "F.Fab")
			(hide yes)
			(effects
				(font
					(size 1 1)
					(thickness 0.15)
				)
			)
		)
		(property "License" "Apache-2.0"
			(at 0 0 0)
			(unlocked yes)
			(layer "F.Fab")
			(hide yes)
			(effects
				(font
					(size 1 1)
					(thickness 0.15)
				)
			)
		)
		(property "Author" "Antmicro"
			(at 0 0 0)
			(unlocked yes)
			(layer "F.Fab")
			(hide yes)
			(effects
				(font
					(size 1 1)
					(thickness 0.15)
				)
			)
		)
		(property "Val" "100n"
			(at 0 0 0)
			(unlocked yes)
			(layer "F.Fab")
			(hide yes)
			(effects
				(font
					(size 1 1)
					(thickness 0.15)
				)
			)
		)
		(property "Voltage" "50V"
			(at 0 0 0)
			(unlocked yes)
			(layer "F.Fab")
			(hide yes)
			(effects
				(font
					(size 1 1)
					(thickness 0.15)
				)
			)
		)
		(property "Dielectric" "X5R"
			(at 0 0 0)
			(unlocked yes)
			(layer "F.Fab")
			(hide yes)
			(effects
				(font
					(size 1 1)
					(thickness 0.15)
				)
			)
		)
		(sheetname "/X710 DCDC converters/")
		(sheetfile "DCDC_converters_X710.kicad_sch")
		(attr smd)
		(fp_rect
			(start -0.925 -0.47)
			(end 0.925 0.47)
			(stroke
				(width 0.05)
				(type default)
			)
			(fill no)
			(layer "F.CrtYd")
		)
		(fp_line
			(start -0.494 -0.25)
			(end 0.504 -0.25)
			(stroke
				(width 0.15)
				(type solid)
			)
			(layer "F.Fab")
		)
		(fp_line
			(start -0.494 0.248)
			(end -0.494 -0.25)
			(stroke
				(width 0.15)
				(type solid)
			)
			(layer "F.Fab")
		)
		(fp_line
			(start 0.504 -0.25)
			(end 0.504 0.248)
			(stroke
				(width 0.15)
				(type solid)
			)
			(layer "F.Fab")
		)
		(fp_line
			(start 0.504 0.248)
			(end -0.494 0.248)
			(stroke
				(width 0.15)
				(type solid)
			)
			(layer "F.Fab")
		)
		(fp_text user "License: Apache-2.0"
			(at -0.939 5.799 0)
			(layer "F.Fab")
			(effects
				(font
					(size 0.7 0.7)
					(thickness 0.15)
				)
				(justify left bottom)
			)
		)
		(fp_text user "${REFERENCE}"
			(at -0.939 4.599 0)
			(layer "F.Fab")
			(effects
				(font
					(size 0.7 0.7)
					(thickness 0.15)
				)
				(justify left bottom)
			)
		)
		(fp_text user "Author: Antmicro"
			(at -0.939 3.399 0)
			(layer "F.Fab")
			(effects
				(font
					(size 0.7 0.7)
					(thickness 0.15)
				)
				(justify left bottom)
			)
		)
		(pad "1" smd roundrect
			(at -0.48 0)
			(size 0.59 0.64)
			(layers "F.Cu" "F.Mask" "F.Paste")
			(roundrect_rratio 0.25)
			(net 23 "GND")
			(pintype "passive")
		)
		(pad "2" smd roundrect
			(at 0.48 0)
			(size 0.59 0.64)
			(layers "F.Cu" "F.Mask" "F.Paste")
			(roundrect_rratio 0.25)
			(net 40 "+5V")
			(pintype "passive")
		)
	)
	(footprint "antmicro-footprints:R_0402_1005Metric"
		(layer "F.Cu")
		(at 125 54.5)
		(descr "Resistor SMD 0402")
		(tags "resistor SMD 0402")
		(property "Reference" "R233"
			(at -5.75 0.5 0)
			(layer "F.SilkS")
			(effects
				(font
					(size 0.7 0.7)
					(thickness 0.15)
				)
				(justify left bottom)
			)
		)
		(property "Value" "R_470R_0402"
			(at -1.011843 1.772047 0)
			(layer "F.Fab")
			(effects
				(font
					(size 0.7 0.7)
					(thickness 0.15)
				)
				(justify left bottom)
			)
		)
		(property "Datasheet" "https://www.bourns.com/docs/product-datasheets/cr.pdf"
			(at 0 0 0)
			(layer "F.Fab")
			(hide yes)
			(effects
				(font
					(size 1.27 1.27)
					(thickness 0.15)
				)
			)
		)
		(property "Description" "SMD Chip Resistor, 470 ohm, ± 1%, 62.5 mW, 0402 [1005 Metric], Thick Film, General Purpose"
			(at 0 0 0)
			(layer "F.Fab")
			(hide yes)
			(effects
				(font
					(size 1.27 1.27)
					(thickness 0.15)
				)
			)
		)
		(property "MPN" "CR0402-FX-4700GLF"
			(at 0 0 0)
			(unlocked yes)
			(layer "F.Fab")
			(hide yes)
			(effects
				(font
					(size 1 1)
					(thickness 0.15)
				)
			)
		)
		(property "Manufacturer" "Bourns"
			(at 0 0 0)
			(unlocked yes)
			(layer "F.Fab")
			(hide yes)
			(effects
				(font
					(size 1 1)
					(thickness 0.15)
				)
			)
		)
		(property "License" "Apache-2.0"
			(at 0 0 0)
			(unlocked yes)
			(layer "F.Fab")
			(hide yes)
			(effects
				(font
					(size 1 1)
					(thickness 0.15)
				)
			)
		)
		(property "Author" "Antmicro"
			(at 0 0 0)
			(unlocked yes)
			(layer "F.Fab")
			(hide yes)
			(effects
				(font
					(size 1 1)
					(thickness 0.15)
				)
			)
		)
		(property "Val" "470R"
			(at 0 0 0)
			(unlocked yes)
			(layer "F.Fab")
			(hide yes)
			(effects
				(font
					(size 1 1)
					(thickness 0.15)
				)
			)
		)
		(property "Tolerance" "1%"
			(at 0 0 0)
			(unlocked yes)
			(layer "F.Fab")
			(hide yes)
			(effects
				(font
					(size 1 1)
					(thickness 0.15)
				)
			)
		)
		(sheetname "/Power input/")
		(sheetfile "power_input.kicad_sch")
		(attr smd)
		(fp_rect
			(start -0.925 -0.47)
			(end 0.925 0.47)
			(stroke
				(width 0.05)
				(type default)
			)
			(fill no)
			(layer "F.CrtYd")
		)
		(fp_rect
			(start -0.5 -0.25)
			(end 0.5 0.25)
			(stroke
				(width 0.15)
				(type solid)
			)
			(fill no)
			(layer "F.Fab")
		)
		(fp_text user "${REFERENCE}"
			(at -0.95 3.168 0)
			(layer "F.Fab")
			(effects
				(font
					(size 0.7 0.7)
					(thickness 0.15)
				)
				(justify left bottom)
			)
		)
		(fp_text user "Author: Antmicro"
			(at -0.95 4.169 0)
			(layer "F.Fab")
			(effects
				(font
					(size 0.7 0.7)
					(thickness 0.15)
				)
				(justify left bottom)
			)
		)
		(fp_text user "License: Apache-2.0"
			(at -0.95 5.169 0)
			(layer "F.Fab")
			(effects
				(font
					(size 0.7 0.7)
					(thickness 0.15)
				)
				(justify left bottom)
			)
		)
		(pad "1" smd roundrect
			(at -0.48 0)
			(size 0.59 0.64)
			(layers "F.Cu" "F.Mask" "F.Paste")
			(roundrect_rratio 0.25)
			(net 420 "Net-(D16-A)")
			(pintype "passive")
		)
		(pad "2" smd roundrect
			(at 0.48 0)
			(size 0.59 0.64)
			(layers "F.Cu" "F.Mask" "F.Paste")
			(roundrect_rratio 0.25)
			(net 349 "/Power input/5V_OUT")
			(pintype "passive")
		)
	)
	(footprint "antmicro-footprints:C_0603_1608Metric_EIA"
		(layer "F.Cu")
		(at 144.15 103.050002 -90)
		(descr "Capacitor SMD 0603, IPC-7351 Density Level A")
		(tags "Capacitor 0603")
		(property "Reference" "C148"
			(at 17.649996 -15.649999 270)
			(layer "F.SilkS")
			(effects
				(font
					(size 0.7 0.7)
					(thickness 0.15)
				)
			)
		)
		(property "Value" "C_22u_16V_0603"
			(at -1.42757 1.770288 270)
			(layer "F.Fab")
			(effects
				(font
					(size 0.7 0.7)
					(thickness 0.15)
				)
				(justify left bottom)
			)
		)
		(property "Datasheet" "https://product.samsungsem.com/mlcc/CL10A226MO7JZN.do"
			(at 0 0 270)
			(layer "F.Fab")
			(hide yes)
			(effects
				(font
					(size 1.27 1.27)
					(thickness 0.15)
				)
			)
		)
		(property "Description" "SMD Multilayer Ceramic Capacitor"
			(at 0 0 270)
			(layer "F.Fab")
			(hide yes)
			(effects
				(font
					(size 1.27 1.27)
					(thickness 0.15)
				)
			)
		)
		(property "MPN" "CL10A226MO7JZNC"
			(at 0 0 270)
			(unlocked yes)
			(layer "F.Fab")
			(hide yes)
			(effects
				(font
					(size 1 1)
					(thickness 0.15)
				)
			)
		)
		(property "Manufacturer" "Samsung Electro-Mechanics"
			(at 0 0 270)
			(unlocked yes)
			(layer "F.Fab")
			(hide yes)
			(effects
				(font
					(size 1 1)
					(thickness 0.15)
				)
			)
		)
		(property "License" "Apache-2.0"
			(at 0 0 270)
			(unlocked yes)
			(layer "F.Fab")
			(hide yes)
			(effects
				(font
					(size 1 1)
					(thickness 0.15)
				)
			)
		)
		(property "Author" "Antmicro"
			(at 0 0 270)
			(unlocked yes)
			(layer "F.Fab")
			(hide yes)
			(effects
				(font
					(size 1 1)
					(thickness 0.15)
				)
			)
		)
		(property "Val" "22u"
			(at 0 0 270)
			(unlocked yes)
			(layer "F.Fab")
			(hide yes)
			(effects
				(font
					(size 1 1)
					(thickness 0.15)
				)
			)
		)
		(property "Voltage" "16V"
			(at 0 0 270)
			(unlocked yes)
			(layer "F.Fab")
			(hide yes)
			(effects
				(font
					(size 1 1)
					(thickness 0.15)
				)
			)
		)
		(property "Dielectric" ""
			(at 0 0 270)
			(unlocked yes)
			(layer "F.Fab")
			(hide yes)
			(effects
				(font
					(size 1 1)
					(thickness 0.15)
				)
			)
		)
		(sheetname "/X710 DCDC converters/")
		(sheetfile "DCDC_converters_X710.kicad_sch")
		(attr smd)
		(fp_line
			(start -0.15 0.55)
			(end 0.15 0.55)
			(stroke
				(width 0.15)
				(type solid)
			)
			(layer "F.SilkS")
		)
		(fp_line
			(start -0.15 -0.55)
			(end 0.15 -0.55)
			(stroke
				(width 0.15)
				(type solid)
			)
			(layer "F.SilkS")
		)
		(fp_rect
			(start -1.25 -0.65)
			(end 1.25 0.65)
			(stroke
				(width 0.05)
				(type solid)
			)
			(fill no)
			(layer "F.CrtYd")
		)
		(fp_rect
			(start -0.8 -0.45)
			(end 0.8 0.45)
			(stroke
				(width 0.15)
				(type solid)
			)
			(fill no)
			(layer "F.Fab")
		)
		(fp_text user "${REFERENCE}"
			(at -1.682 3.895 270)
			(layer "F.Fab")
			(effects
				(font
					(size 0.7 0.7)
					(thickness 0.15)
				)
				(justify left bottom)
			)
		)
		(fp_text user "Author: Antmicro"
			(at -1.682 4.894 270)
			(layer "F.Fab")
			(effects
				(font
					(size 0.7 0.7)
					(thickness 0.15)
				)
				(justify left bottom)
			)
		)
		(fp_text user "License: Apache-2.0"
			(at -1.682 5.895 270)
			(layer "F.Fab")
			(effects
				(font
					(size 0.7 0.7)
					(thickness 0.15)
				)
				(justify left bottom)
			)
		)
		(pad "1" smd roundrect
			(at -0.7 0 270)
			(size 0.8 1.1)
			(layers "F.Cu" "F.Mask" "F.Paste")
			(roundrect_rratio 0.2)
			(net 23 "GND")
			(pintype "passive")
		)
		(pad "2" smd roundrect
			(at 0.7 0 270)
			(size 0.8 1.1)
			(layers "F.Cu" "F.Mask" "F.Paste")
			(roundrect_rratio 0.2)
			(net 341 "/X710 DCDC converters/+DVDD_OUT")
			(pintype "passive")
		)
	)
	(footprint "antmicro-footprints:Resonator_SMD_Murata_XRCGB_2x1.6x0.65mm"
		(layer "F.Cu")
		(at 157.225 97.080499 -90)
		(property "Reference" "Y3"
			(at 19.625001 -23.299999 90)
			(layer "F.SilkS")
			(effects
				(font
					(size 0.7 0.7)
					(thickness 0.15)
				)
			)
		)
		(property "Value" "Resonator_50MHz_XRCGE"
			(at 0 2.2 270)
			(layer "F.Fab")
			(effects
				(font
					(size 0.7 0.7)
					(thickness 0.15)
				)
				(justify left bottom)
			)
		)
		(property "Datasheet" "https://www.murata.com/products/productdata/8813268205598/SPEC-XRCGE50M000F5A2AR0.pdf"
			(at 0 0 270)
			(layer "F.Fab")
			(hide yes)
			(effects
				(font
					(size 1.27 1.27)
					(thickness 0.15)
				)
			)
		)
		(property "Description" "Crystal, 50 MHz, 2mm x 1.6mm, 50 ppm, 4.7 pF, 50 ppm, XRCGE Series"
			(at 0 0 270)
			(layer "F.Fab")
			(hide yes)
			(effects
				(font
					(size 1.27 1.27)
					(thickness 0.15)
				)
			)
		)
		(property "Manufacturer" "Murata"
			(at 0 0 270)
			(unlocked yes)
			(layer "F.Fab")
			(hide yes)
			(effects
				(font
					(size 1 1)
					(thickness 0.15)
				)
			)
		)
		(property "MPN" "XRCGE50M000F5A2AR0"
			(at 0 0 270)
			(unlocked yes)
			(layer "F.Fab")
			(hide yes)
			(effects
				(font
					(size 1 1)
					(thickness 0.15)
				)
			)
		)
		(property "Val" "50MHz"
			(at 0 0 270)
			(unlocked yes)
			(layer "F.Fab")
			(hide yes)
			(effects
				(font
					(size 1 1)
					(thickness 0.15)
				)
			)
		)
		(property "CLoad" "4.7pF"
			(at 0 0 270)
			(unlocked yes)
			(layer "F.Fab")
			(hide yes)
			(effects
				(font
					(size 1 1)
					(thickness 0.15)
				)
			)
		)
		(property "Author" "Antmicro"
			(at 0 0 270)
			(unlocked yes)
			(layer "F.Fab")
			(hide yes)
			(effects
				(font
					(size 1 1)
					(thickness 0.15)
				)
			)
		)
		(property "License" "Apache-2.0"
			(at 0 0 270)
			(unlocked yes)
			(layer "F.Fab")
			(hide yes)
			(effects
				(font
					(size 1 1)
					(thickness 0.15)
				)
			)
		)
		(sheetname "/X710-AT2 Misc/")
		(sheetfile "x710-at2-mics.kicad_sch")
		(attr smd)
		(fp_line
			(start -0.4 1.15)
			(end 0.4 1.15)
			(stroke
				(width 0.15)
				(type solid)
			)
			(layer "F.SilkS")
		)
		(fp_line
			(start -0.95 0.4)
			(end -0.95 -0.4)
			(stroke
				(width 0.15)
				(type solid)
			)
			(layer "F.SilkS")
		)
		(fp_line
			(start 0.95 0.4)
			(end 0.95 -0.4)
			(stroke
				(width 0.15)
				(type solid)
			)
			(layer "F.SilkS")
		)
		(fp_line
			(start -0.4 -1.15)
			(end 0.4 -1.15)
			(stroke
				(width 0.15)
				(type solid)
			)
			(layer "F.SilkS")
		)
		(fp_circle
			(center -0.95 -1.15)
			(end -0.9 -1.15)
			(stroke
				(width 0.15)
				(type solid)
			)
			(fill yes)
			(layer "F.SilkS")
		)
		(fp_rect
			(start -1.05 -1.25)
			(end 1.05 1.24)
			(stroke
				(width 0.05)
				(type solid)
			)
			(fill no)
			(layer "F.CrtYd")
		)
		(fp_rect
			(start -0.85 -1.054)
			(end 0.852 1.054)
			(stroke
				(width 0.15)
				(type solid)
			)
			(fill no)
			(layer "F.Fab")
		)
		(fp_text user "License: Apache-2.0"
			(at -1.05 5.8 270)
			(layer "F.Fab")
			(effects
				(font
					(size 0.7 0.7)
					(thickness 0.15)
				)
				(justify left bottom)
			)
		)
		(fp_text user "${REFERENCE}"
			(at -1.05 3.4 270)
			(layer "F.Fab")
			(effects
				(font
					(size 0.7 0.7)
					(thickness 0.15)
				)
				(justify left bottom)
			)
		)
		(fp_text user "Author: Antmicro"
			(at -1.05 4.6 270)
			(layer "F.Fab")
			(effects
				(font
					(size 0.7 0.7)
					(thickness 0.15)
				)
				(justify left bottom)
			)
		)
		(pad "1" smd rect
			(at -0.5 -0.675 270)
			(size 0.7 0.75)
			(layers "F.Cu" "F.Mask" "F.Paste")
			(net 58 "/X710-AT2 Misc/50MHZ_XTAL_R.+")
			(pintype "passive")
		)
		(pad "2" smd rect
			(at -0.5 0.675 270)
			(size 0.7 0.75)
			(layers "F.Cu" "F.Mask" "F.Paste")
			(net 23 "GND")
			(pinfunction "SH")
			(pintype "passive")
		)
		(pad "3" smd rect
			(at 0.5 0.675 270)
			(size 0.7 0.75)
			(layers "F.Cu" "F.Mask" "F.Paste")
			(net 59 "/X710-AT2 Misc/50MHZ_XTAL_R.-")
			(pintype "passive")
		)
		(pad "4" smd rect
			(at 0.5 -0.675 270)
			(size 0.7 0.75)
			(layers "F.Cu" "F.Mask" "F.Paste")
			(net 23 "GND")
			(pinfunction "SH")
			(pintype "passive")
		)
	)
	(footprint "antmicro-footprints:R_0402_1005Metric"
		(layer "F.Cu")
		(at 142.310001 94.674999 180)
		(descr "Resistor SMD 0402")
		(tags "resistor SMD 0402")
		(property "Reference" "R182"
			(at -2.190001 -0.025001 180)
			(layer "F.SilkS")
			(effects
				(font
					(size 0.7 0.7)
					(thickness 0.15)
				)
			)
		)
		(property "Value" "R_10k_0402"
			(at -1.011843 1.772047 180)
			(layer "F.Fab")
			(effects
				(font
					(size 0.7 0.7)
					(thickness 0.15)
				)
				(justify left bottom)
			)
		)
		(property "Datasheet" "https://www.bourns.com/docs/product-datasheets/cr.pdf"
			(at 0 0 180)
			(layer "F.Fab")
			(hide yes)
			(effects
				(font
					(size 1.27 1.27)
					(thickness 0.15)
				)
			)
		)
		(property "Description" "SMD Chip Resistor, 10 kohm, ± 1%, 62.5 mW, 0402 [1005 Metric], Thick Film, General Purpose"
			(at 0 0 180)
			(layer "F.Fab")
			(hide yes)
			(effects
				(font
					(size 1.27 1.27)
					(thickness 0.15)
				)
			)
		)
		(property "MPN" "CR0402-FX-1002GLF"
			(at 0 0 180)
			(unlocked yes)
			(layer "F.Fab")
			(hide yes)
			(effects
				(font
					(size 1 1)
					(thickness 0.15)
				)
			)
		)
		(property "Manufacturer" "Bourns"
			(at 0 0 180)
			(unlocked yes)
			(layer "F.Fab")
			(hide yes)
			(effects
				(font
					(size 1 1)
					(thickness 0.15)
				)
			)
		)
		(property "License" "Apache-2.0"
			(at 0 0 180)
			(unlocked yes)
			(layer "F.Fab")
			(hide yes)
			(effects
				(font
					(size 1 1)
					(thickness 0.15)
				)
			)
		)
		(property "Author" "Antmicro"
			(at 0 0 180)
			(unlocked yes)
			(layer "F.Fab")
			(hide yes)
			(effects
				(font
					(size 1 1)
					(thickness 0.15)
				)
			)
		)
		(property "Val" "10k"
			(at 0 0 180)
			(unlocked yes)
			(layer "F.Fab")
			(hide yes)
			(effects
				(font
					(size 1 1)
					(thickness 0.15)
				)
			)
		)
		(property "Tolerance" "1%"
			(at 0 0 180)
			(unlocked yes)
			(layer "F.Fab")
			(hide yes)
			(effects
				(font
					(size 1 1)
					(thickness 0.15)
				)
			)
		)
		(sheetname "/X710-AT2 Misc/")
		(sheetfile "x710-at2-mics.kicad_sch")
		(attr smd)
		(fp_rect
			(start -0.925 -0.47)
			(end 0.925 0.47)
			(stroke
				(width 0.05)
				(type default)
			)
			(fill no)
			(layer "F.CrtYd")
		)
		(fp_rect
			(start -0.5 -0.25)
			(end 0.5 0.25)
			(stroke
				(width 0.15)
				(type solid)
			)
			(fill no)
			(layer "F.Fab")
		)
		(fp_text user "${REFERENCE}"
			(at -0.95 3.168 180)
			(layer "F.Fab")
			(effects
				(font
					(size 0.7 0.7)
					(thickness 0.15)
				)
				(justify left bottom)
			)
		)
		(fp_text user "License: Apache-2.0"
			(at -0.95 5.169 180)
			(layer "F.Fab")
			(effects
				(font
					(size 0.7 0.7)
					(thickness 0.15)
				)
				(justify left bottom)
			)
		)
		(fp_text user "Author: Antmicro"
			(at -0.95 4.169 180)
			(layer "F.Fab")
			(effects
				(font
					(size 0.7 0.7)
					(thickness 0.15)
				)
				(justify left bottom)
			)
		)
		(pad "1" smd roundrect
			(at -0.48 0 180)
			(size 0.59 0.64)
			(layers "F.Cu" "F.Mask" "F.Paste")
			(roundrect_rratio 0.25)
			(net 350 "/X710 flash memory/FLASH.~{CE}")
			(pintype "passive")
		)
		(pad "2" smd roundrect
			(at 0.48 0 180)
			(size 0.59 0.64)
			(layers "F.Cu" "F.Mask" "F.Paste")
			(roundrect_rratio 0.25)
			(net 7 "+3V3")
			(pintype "passive")
		)
	)
	(footprint "antmicro-footprints:LED_0603_1608Metric_G"
		(layer "F.Cu")
		(at 116 139 90)
		(descr "LED SMD 0603 Green")
		(tags "LED SMD 0603 Green")
		(property "Reference" "D2"
			(at -0.75 3 90)
			(layer "F.SilkS")
			(effects
				(font
					(size 0.7 0.7)
					(thickness 0.15)
				)
				(justify left bottom)
			)
		)
		(property "Value" "LED_G_0603_LTST-C190GKT"
			(at -0.001 1.599 90)
			(layer "F.Fab")
			(effects
				(font
					(size 0.7 0.7)
					(thickness 0.15)
				)
				(justify left bottom)
			)
		)
		(property "Datasheet" "https://media.digikey.com/pdf/Data%20Sheets/Lite-On%20PDFs/LTST-C190GKT.pdf"
			(at 0 0 90)
			(layer "F.Fab")
			(hide yes)
			(effects
				(font
					(size 1.27 1.27)
					(thickness 0.15)
				)
			)
		)
		(property "Description" "LED, Green, SMD, 0603, 20 mA, 2.1 V, 569 nm"
			(at 0 0 90)
			(layer "F.Fab")
			(hide yes)
			(effects
				(font
					(size 1.27 1.27)
					(thickness 0.15)
				)
			)
		)
		(property "MPN" "LTST-C190GKT"
			(at 0 0 90)
			(unlocked yes)
			(layer "F.Fab")
			(hide yes)
			(effects
				(font
					(size 1 1)
					(thickness 0.15)
				)
			)
		)
		(property "Manufacturer" "Lite-On"
			(at 0 0 90)
			(unlocked yes)
			(layer "F.Fab")
			(hide yes)
			(effects
				(font
					(size 1 1)
					(thickness 0.15)
				)
			)
		)
		(property "Author" "Antmicro"
			(at 0 0 90)
			(unlocked yes)
			(layer "F.Fab")
			(hide yes)
			(effects
				(font
					(size 1 1)
					(thickness 0.15)
				)
			)
		)
		(property "License" "Apache-2.0"
			(at 0 0 90)
			(unlocked yes)
			(layer "F.Fab")
			(hide yes)
			(effects
				(font
					(size 1 1)
					(thickness 0.15)
				)
			)
		)
		(property "Color" "Green"
			(at 0 0 90)
			(unlocked yes)
			(layer "F.Fab")
			(hide yes)
			(effects
				(font
					(size 1 1)
					(thickness 0.15)
				)
			)
		)
		(sheetname "/USB-C connector/")
		(sheetfile "USB-C_connector.kicad_sch")
		(attr smd)
		(fp_line
			(start 0.22 -0.35)
			(end -0.22 -0.35)
			(stroke
				(width 0.15)
				(type solid)
			)
			(layer "F.SilkS")
		)
		(fp_line
			(start -1.18 -0.319)
			(end -1.18 0.321)
			(stroke
				(width 0.15)
				(type solid)
			)
			(layer "F.SilkS")
		)
		(fp_line
			(start 0.105328 0.001008)
			(end 0.24 0.001)
			(stroke
				(width 0.1)
				(type solid)
			)
			(layer "F.SilkS")
		)
		(fp_line
			(start -0.094672 0.001008)
			(end 0.105328 -0.198992)
			(stroke
				(width 0.1)
				(type solid)
			)
			(layer "F.SilkS")
		)
		(fp_line
			(start -0.094672 0.001008)
			(end -0.24 0.001008)
			(stroke
				(width 0.1)
				(type solid)
			)
			(layer "F.SilkS")
		)
		(fp_line
			(start 0.105328 0.201008)
			(end 0.105328 -0.198992)
			(stroke
				(width 0.1)
				(type solid)
			)
			(layer "F.SilkS")
		)
		(fp_line
			(start 0.105328 0.201008)
			(end -0.094672 0.001008)
			(stroke
				(width 0.1)
				(type solid)
			)
			(layer "F.SilkS")
		)
		(fp_line
			(start -0.094672 0.201008)
			(end -0.094672 -0.198992)
			(stroke
				(width 0.1)
				(type solid)
			)
			(layer "F.SilkS")
		)
		(fp_line
			(start 0.22 0.35)
			(end -0.22 0.35)
			(stroke
				(width 0.15)
				(type solid)
			)
			(layer "F.SilkS")
		)
		(fp_rect
			(start 1.25 0.65)
			(end -1.25 -0.65)
			(stroke
				(width 0.05)
				(type solid)
			)
			(fill no)
			(layer "F.CrtYd")
		)
		(fp_line
			(start 0.201 -0.202)
			(end -0.101 0)
			(stroke
				(width 0.15)
				(type solid)
			)
			(layer "F.Fab")
		)
		(fp_line
			(start -0.199 -0.202)
			(end -0.199 0.1)
			(stroke
				(width 0.15)
				(type solid)
			)
			(layer "F.Fab")
		)
		(fp_line
			(start 0.599 0)
			(end 0.201 0)
			(stroke
				(width 0.15)
				(type solid)
			)
			(layer "F.Fab")
		)
		(fp_line
			(start 0.201 0)
			(end 0.201 -0.202)
			(stroke
				(width 0.15)
				(type solid)
			)
			(layer "F.Fab")
		)
		(fp_line
			(start -0.101 0)
			(end 0.201 0.2)
			(stroke
				(width 0.15)
				(type solid)
			)
			(layer "F.Fab")
		)
		(fp_line
			(start -0.199 0)
			(end -0.597 0)
			(stroke
				(width 0.15)
				(type solid)
			)
			(layer "F.Fab")
		)
		(fp_line
			(start 0.201 0.2)
			(end 0.201 0)
			(stroke
				(width 0.15)
				(type solid)
			)
			(layer "F.Fab")
		)
		(fp_line
			(start -0.199 0.2)
			(end -0.199 0.1)
			(stroke
				(width 0.15)
				(type solid)
			)
			(layer "F.Fab")
		)
		(fp_rect
			(start 0.848 0.4)
			(end -0.85 -0.402)
			(stroke
				(width 0.15)
				(type solid)
			)
			(fill no)
			(layer "F.Fab")
		)
		(fp_text user "License: Apache-2.0"
			(at -1.4224 3.599 90)
			(layer "F.Fab")
			(effects
				(font
					(size 0.7 0.7)
					(thickness 0.15)
				)
				(justify left bottom)
			)
		)
		(fp_text user "Author: Antmicro"
			(at -1.4224 4.799 90)
			(layer "F.Fab")
			(effects
				(font
					(size 0.7 0.7)
					(thickness 0.15)
				)
				(justify left bottom)
			)
		)
		(fp_text user "${REFERENCE}"
			(at -1.4224 5.999 90)
			(layer "F.Fab")
			(effects
				(font
					(size 0.7 0.7)
					(thickness 0.15)
				)
				(justify left bottom)
			)
		)
		(pad "1" smd roundrect
			(at -0.7 0 270)
			(size 0.8 1)
			(layers "F.Cu" "F.Mask" "F.Paste")
			(roundrect_rratio 0.2)
			(net 23 "GND")
			(pinfunction "C")
			(pintype "passive")
		)
		(pad "2" smd roundrect
			(at 0.7 0 270)
			(size 0.8 1)
			(layers "F.Cu" "F.Mask" "F.Paste")
			(roundrect_rratio 0.2)
			(net 164 "Net-(D2-A)")
			(pinfunction "A")
			(pintype "passive")
		)
	)
	(footprint "antmicro-footprints:R_0402_1005Metric"
		(layer "F.Cu")
		(at 164 79.4 180)
		(descr "Resistor SMD 0402")
		(tags "resistor SMD 0402")
		(property "Reference" "R205"
			(at 1 -6.4 180)
			(layer "F.SilkS")
			(effects
				(font
					(size 0.7 0.7)
					(thickness 0.15)
				)
				(justify left bottom)
			)
		)
		(property "Value" "R_0R_0402"
			(at -1.011843 1.772047 180)
			(layer "F.Fab")
			(effects
				(font
					(size 0.7 0.7)
					(thickness 0.15)
				)
				(justify left bottom)
			)
		)
		(property "Datasheet" "https://industrial.panasonic.com/cdbs/www-data/pdf/RDA0000/AOA0000C301.pdf"
			(at 0 0 180)
			(layer "F.Fab")
			(hide yes)
			(effects
				(font
					(size 1.27 1.27)
					(thickness 0.15)
				)
			)
		)
		(property "Description" "SMD Chip Resistor, Jumper, 0 ohm, 100 mW, 0402 [1005 Metric], Thick Film, General Purpose"
			(at 0 0 180)
			(layer "F.Fab")
			(hide yes)
			(effects
				(font
					(size 1.27 1.27)
					(thickness 0.15)
				)
			)
		)
		(property "MPN" "ERJ2GE0R00X"
			(at 0 0 180)
			(unlocked yes)
			(layer "F.Fab")
			(hide yes)
			(effects
				(font
					(size 1 1)
					(thickness 0.15)
				)
			)
		)
		(property "Manufacturer" "Panasonic"
			(at 0 0 180)
			(unlocked yes)
			(layer "F.Fab")
			(hide yes)
			(effects
				(font
					(size 1 1)
					(thickness 0.15)
				)
			)
		)
		(property "License" "Apache-2.0"
			(at 0 0 180)
			(unlocked yes)
			(layer "F.Fab")
			(hide yes)
			(effects
				(font
					(size 1 1)
					(thickness 0.15)
				)
			)
		)
		(property "Author" "Antmicro"
			(at 0 0 180)
			(unlocked yes)
			(layer "F.Fab")
			(hide yes)
			(effects
				(font
					(size 1 1)
					(thickness 0.15)
				)
			)
		)
		(property "Val" "0R"
			(at 0 0 180)
			(unlocked yes)
			(layer "F.Fab")
			(hide yes)
			(effects
				(font
					(size 1 1)
					(thickness 0.15)
				)
			)
		)
		(property "Tolerance" "~"
			(at 0 0 180)
			(unlocked yes)
			(layer "F.Fab")
			(hide yes)
			(effects
				(font
					(size 1 1)
					(thickness 0.15)
				)
			)
		)
		(property "Current" "1A"
			(at 0 0 180)
			(unlocked yes)
			(layer "F.Fab")
			(hide yes)
			(effects
				(font
					(size 1 1)
					(thickness 0.15)
				)
			)
		)
		(sheetname "/X710-AT2 10GbE/")
		(sheetfile "x710-at2-10gbe.kicad_sch")
		(attr smd)
		(fp_rect
			(start -0.925 -0.47)
			(end 0.925 0.47)
			(stroke
				(width 0.05)
				(type default)
			)
			(fill no)
			(layer "F.CrtYd")
		)
		(fp_rect
			(start -0.5 -0.25)
			(end 0.5 0.25)
			(stroke
				(width 0.15)
				(type solid)
			)
			(fill no)
			(layer "F.Fab")
		)
		(fp_text user "License: Apache-2.0"
			(at -0.95 5.169 180)
			(layer "F.Fab")
			(effects
				(font
					(size 0.7 0.7)
					(thickness 0.15)
				)
				(justify left bottom)
			)
		)
		(fp_text user "${REFERENCE}"
			(at -0.95 3.168 180)
			(layer "F.Fab")
			(effects
				(font
					(size 0.7 0.7)
					(thickness 0.15)
				)
				(justify left bottom)
			)
		)
		(fp_text user "Author: Antmicro"
			(at -0.95 4.169 180)
			(layer "F.Fab")
			(effects
				(font
					(size 0.7 0.7)
					(thickness 0.15)
				)
				(justify left bottom)
			)
		)
		(pad "1" smd roundrect
			(at -0.48 0 180)
			(size 0.59 0.64)
			(layers "F.Cu" "F.Mask" "F.Paste")
			(roundrect_rratio 0.25)
			(net 23 "GND")
			(pintype "passive")
		)
		(pad "2" smd roundrect
			(at 0.48 0 180)
			(size 0.59 0.64)
			(layers "F.Cu" "F.Mask" "F.Paste")
			(roundrect_rratio 0.25)
			(net 130 "/X710-AT2 10GbE/TPIN_3")
			(pintype "passive")
		)
	)
	(footprint "antmicro-footprints:C_0603_1608Metric"
		(layer "F.Cu")
		(at 138.45 120.15 -90)
		(descr "Capacitor SMD 0603")
		(tags "capacitor 0603")
		(property "Reference" "C94"
			(at -1.35 -0.55 270)
			(layer "F.SilkS")
			(effects
				(font
					(size 0.7 0.7)
					(thickness 0.15)
				)
				(justify left bottom)
			)
		)
		(property "Value" "C_22u_0603"
			(at -1.42757 1.770288 270)
			(layer "F.Fab")
			(effects
				(font
					(size 0.7 0.7)
					(thickness 0.15)
				)
				(justify left bottom)
			)
		)
		(property "Datasheet" "https://www.murata.com/products/productdetail?partno=GRM188R60J226MEA0%23"
			(at 0 0 270)
			(layer "F.Fab")
			(hide yes)
			(effects
				(font
					(size 1.27 1.27)
					(thickness 0.15)
				)
			)
		)
		(property "Description" "SMD Multilayer Ceramic Capacitor, 22 µF, 6.3 V, 0603 [1608 Metric], ± 20%, X5R, GRM Series"
			(at 0 0 270)
			(layer "F.Fab")
			(hide yes)
			(effects
				(font
					(size 1.27 1.27)
					(thickness 0.15)
				)
			)
		)
		(property "MPN" "GRM188R60J226MEA0D"
			(at 0 0 270)
			(unlocked yes)
			(layer "F.Fab")
			(hide yes)
			(effects
				(font
					(size 1 1)
					(thickness 0.15)
				)
			)
		)
		(property "Manufacturer" "Murata"
			(at 0 0 270)
			(unlocked yes)
			(layer "F.Fab")
			(hide yes)
			(effects
				(font
					(size 1 1)
					(thickness 0.15)
				)
			)
		)
		(property "License" "Apache-2.0"
			(at 0 0 270)
			(unlocked yes)
			(layer "F.Fab")
			(hide yes)
			(effects
				(font
					(size 1 1)
					(thickness 0.15)
				)
			)
		)
		(property "Val" "22u"
			(at 0 0 270)
			(unlocked yes)
			(layer "F.Fab")
			(hide yes)
			(effects
				(font
					(size 1 1)
					(thickness 0.15)
				)
			)
		)
		(property "Voltage" ""
			(at 0 0 270)
			(unlocked yes)
			(layer "F.Fab")
			(hide yes)
			(effects
				(font
					(size 1 1)
					(thickness 0.15)
				)
			)
		)
		(property "Dielectric" ""
			(at 0 0 270)
			(unlocked yes)
			(layer "F.Fab")
			(hide yes)
			(effects
				(font
					(size 1 1)
					(thickness 0.15)
				)
			)
		)
		(property "Author" "Antmicro"
			(at 0 0 270)
			(unlocked yes)
			(layer "F.Fab")
			(hide yes)
			(effects
				(font
					(size 1 1)
					(thickness 0.15)
				)
			)
		)
		(sheetname "/TB Controller - Power/")
		(sheetfile "tb-power.kicad_sch")
		(attr smd)
		(fp_line
			(start -0.15 0.4)
			(end 0.15 0.4)
			(stroke
				(width 0.15)
				(type solid)
			)
			(layer "F.SilkS")
		)
		(fp_line
			(start -0.15 -0.4)
			(end 0.15 -0.4)
			(stroke
				(width 0.15)
				(type solid)
			)
			(layer "F.SilkS")
		)
		(fp_rect
			(start -1.25 -0.65)
			(end 1.25 0.65)
			(stroke
				(width 0.05)
				(type solid)
			)
			(fill no)
			(layer "F.CrtYd")
		)
		(fp_rect
			(start -0.8 -0.4)
			(end 0.8 0.4)
			(stroke
				(width 0.15)
				(type solid)
			)
			(fill no)
			(layer "F.Fab")
		)
		(fp_text user "License: Apache-2.0"
			(at -1.682 5.895 270)
			(layer "F.Fab")
			(effects
				(font
					(size 0.7 0.7)
					(thickness 0.15)
				)
				(justify left bottom)
			)
		)
		(fp_text user "Author: Antmicro"
			(at -1.682 4.894 270)
			(layer "F.Fab")
			(effects
				(font
					(size 0.7 0.7)
					(thickness 0.15)
				)
				(justify left bottom)
			)
		)
		(fp_text user "${REFERENCE}"
			(at -1.682 3.895 270)
			(layer "F.Fab")
			(effects
				(font
					(size 0.7 0.7)
					(thickness 0.15)
				)
				(justify left bottom)
			)
		)
		(pad "1" smd roundrect
			(at -0.7 0 270)
			(size 0.8 1)
			(layers "F.Cu" "F.Mask" "F.Paste")
			(roundrect_rratio 0.2)
			(net 23 "GND")
			(pintype "passive")
		)
		(pad "2" smd roundrect
			(at 0.7 0 270)
			(size 0.8 1)
			(layers "F.Cu" "F.Mask" "F.Paste")
			(roundrect_rratio 0.2)
			(net 68 "/TB Controller - Power/VCC_0P9")
			(pintype "passive")
		)
	)
	(footprint "antmicro-footprints:C_0603_1608Metric"
		(layer "F.Cu")
		(at 165.305 93.575 180)
		(descr "Capacitor SMD 0603")
		(tags "capacitor 0603")
		(property "Reference" "C181"
			(at -7.695 0 180)
			(layer "F.SilkS")
			(effects
				(font
					(size 0.7 0.7)
					(thickness 0.15)
				)
			)
		)
		(property "Value" "C_10u_10V_X7R_0603"
			(at -1.42757 1.770288 180)
			(layer "F.Fab")
			(effects
				(font
					(size 0.7 0.7)
					(thickness 0.15)
				)
				(justify left bottom)
			)
		)
		(property "Datasheet" "https://www.murata.com/products/productdetail?partno=GRM188Z71A106KA73%23"
			(at 0 0 180)
			(layer "F.Fab")
			(hide yes)
			(effects
				(font
					(size 1.27 1.27)
					(thickness 0.15)
				)
			)
		)
		(property "Description" "SMD Multilayer Ceramic Capacitor,  10µF, 10V, 0603, ±10%, X7R"
			(at 0 0 180)
			(layer "F.Fab")
			(hide yes)
			(effects
				(font
					(size 1.27 1.27)
					(thickness 0.15)
				)
			)
		)
		(property "MPN" "GRM188Z71A106KA73D"
			(at 0 0 180)
			(unlocked yes)
			(layer "F.Fab")
			(hide yes)
			(effects
				(font
					(size 1 1)
					(thickness 0.15)
				)
			)
		)
		(property "Val" "10u"
			(at 0 0 180)
			(unlocked yes)
			(layer "F.Fab")
			(hide yes)
			(effects
				(font
					(size 1 1)
					(thickness 0.15)
				)
			)
		)
		(property "Voltage" "10V"
			(at 0 0 180)
			(unlocked yes)
			(layer "F.Fab")
			(hide yes)
			(effects
				(font
					(size 1 1)
					(thickness 0.15)
				)
			)
		)
		(property "Dielectric" "X7R"
			(at 0 0 180)
			(unlocked yes)
			(layer "F.Fab")
			(hide yes)
			(effects
				(font
					(size 1 1)
					(thickness 0.15)
				)
			)
		)
		(property "Manufacturer" "Murata"
			(at 0 0 180)
			(unlocked yes)
			(layer "F.Fab")
			(hide yes)
			(effects
				(font
					(size 1 1)
					(thickness 0.15)
				)
			)
		)
		(property "License" "Apache-2.0"
			(at 0 0 180)
			(unlocked yes)
			(layer "F.Fab")
			(hide yes)
			(effects
				(font
					(size 1 1)
					(thickness 0.15)
				)
			)
		)
		(property "Author" "Antmicro"
			(at 0 0 180)
			(unlocked yes)
			(layer "F.Fab")
			(hide yes)
			(effects
				(font
					(size 1 1)
					(thickness 0.15)
				)
			)
		)
		(sheetname "/X710-AT2 power/")
		(sheetfile "x710-at2-power.kicad_sch")
		(attr smd)
		(fp_line
			(start -0.15 0.4)
			(end 0.15 0.4)
			(stroke
				(width 0.15)
				(type solid)
			)
			(layer "F.SilkS")
		)
		(fp_line
			(start -0.15 -0.4)
			(end 0.15 -0.4)
			(stroke
				(width 0.15)
				(type solid)
			)
			(layer "F.SilkS")
		)
		(fp_rect
			(start -1.25 -0.65)
			(end 1.25 0.65)
			(stroke
				(width 0.05)
				(type solid)
			)
			(fill no)
			(layer "F.CrtYd")
		)
		(fp_rect
			(start -0.8 -0.4)
			(end 0.8 0.4)
			(stroke
				(width 0.15)
				(type solid)
			)
			(fill no)
			(layer "F.Fab")
		)
		(fp_text user "Author: Antmicro"
			(at -1.682 4.894 180)
			(layer "F.Fab")
			(effects
				(font
					(size 0.7 0.7)
					(thickness 0.15)
				)
				(justify left bottom)
			)
		)
		(fp_text user "License: Apache-2.0"
			(at -1.682 5.895 180)
			(layer "F.Fab")
			(effects
				(font
					(size 0.7 0.7)
					(thickness 0.15)
				)
				(justify left bottom)
			)
		)
		(fp_text user "${REFERENCE}"
			(at -1.682 3.895 180)
			(layer "F.Fab")
			(effects
				(font
					(size 0.7 0.7)
					(thickness 0.15)
				)
				(justify left bottom)
			)
		)
		(pad "1" smd roundrect
			(at -0.7 0 180)
			(size 0.8 1)
			(layers "F.Cu" "F.Mask" "F.Paste")
			(roundrect_rratio 0.2)
			(net 23 "GND")
			(pintype "passive")
		)
		(pad "2" smd roundrect
			(at 0.7 0 180)
			(size 0.8 1)
			(layers "F.Cu" "F.Mask" "F.Paste")
			(roundrect_rratio 0.2)
			(net 14 "P1_AVDDL")
			(pintype "passive")
		)
	)
	(footprint "antmicro-footprints:R_0402_1005Metric"
		(layer "F.Cu")
		(at 143.849999 113.150002)
		(descr "Resistor SMD 0402")
		(tags "resistor SMD 0402")
		(property "Reference" "R95"
			(at 15.349999 17.25 0)
			(layer "F.SilkS")
			(effects
				(font
					(size 0.7 0.7)
					(thickness 0.15)
				)
			)
		)
		(property "Value" "R_0R_0402"
			(at -1.011843 1.772047 0)
			(layer "F.Fab")
			(effects
				(font
					(size 0.7 0.7)
					(thickness 0.15)
				)
				(justify left bottom)
			)
		)
		(property "Datasheet" "https://industrial.panasonic.com/cdbs/www-data/pdf/RDA0000/AOA0000C301.pdf"
			(at 0 0 0)
			(layer "F.Fab")
			(hide yes)
			(effects
				(font
					(size 1.27 1.27)
					(thickness 0.15)
				)
			)
		)
		(property "Description" "SMD Chip Resistor, Jumper, 0 ohm, 100 mW, 0402 [1005 Metric], Thick Film, General Purpose"
			(at 0 0 0)
			(layer "F.Fab")
			(hide yes)
			(effects
				(font
					(size 1.27 1.27)
					(thickness 0.15)
				)
			)
		)
		(property "MPN" "ERJ2GE0R00X"
			(at 0 0 0)
			(unlocked yes)
			(layer "F.Fab")
			(hide yes)
			(effects
				(font
					(size 1 1)
					(thickness 0.15)
				)
			)
		)
		(property "Manufacturer" "Panasonic"
			(at 0 0 0)
			(unlocked yes)
			(layer "F.Fab")
			(hide yes)
			(effects
				(font
					(size 1 1)
					(thickness 0.15)
				)
			)
		)
		(property "License" "Apache-2.0"
			(at 0 0 0)
			(unlocked yes)
			(layer "F.Fab")
			(hide yes)
			(effects
				(font
					(size 1 1)
					(thickness 0.15)
				)
			)
		)
		(property "Author" "Antmicro"
			(at 0 0 0)
			(unlocked yes)
			(layer "F.Fab")
			(hide yes)
			(effects
				(font
					(size 1 1)
					(thickness 0.15)
				)
			)
		)
		(property "Val" "0R"
			(at 0 0 0)
			(unlocked yes)
			(layer "F.Fab")
			(hide yes)
			(effects
				(font
					(size 1 1)
					(thickness 0.15)
				)
			)
		)
		(property "Tolerance" "~"
			(at 0 0 0)
			(unlocked yes)
			(layer "F.Fab")
			(hide yes)
			(effects
				(font
					(size 1 1)
					(thickness 0.15)
				)
			)
		)
		(property "Current" "1A"
			(at 0 0 0)
			(unlocked yes)
			(layer "F.Fab")
			(hide yes)
			(effects
				(font
					(size 1 1)
					(thickness 0.15)
				)
			)
		)
		(sheetname "/X710 DCDC converters/")
		(sheetfile "DCDC_converters_X710.kicad_sch")
		(attr smd)
		(fp_rect
			(start -0.925 -0.47)
			(end 0.925 0.47)
			(stroke
				(width 0.05)
				(type default)
			)
			(fill no)
			(layer "F.CrtYd")
		)
		(fp_rect
			(start -0.5 -0.25)
			(end 0.5 0.25)
			(stroke
				(width 0.15)
				(type solid)
			)
			(fill no)
			(layer "F.Fab")
		)
		(fp_text user "${REFERENCE}"
			(at -0.95 3.168 0)
			(layer "F.Fab")
			(effects
				(font
					(size 0.7 0.7)
					(thickness 0.15)
				)
				(justify left bottom)
			)
		)
		(fp_text user "License: Apache-2.0"
			(at -0.95 5.169 0)
			(layer "F.Fab")
			(effects
				(font
					(size 0.7 0.7)
					(thickness 0.15)
				)
				(justify left bottom)
			)
		)
		(fp_text user "Author: Antmicro"
			(at -0.95 4.169 0)
			(layer "F.Fab")
			(effects
				(font
					(size 0.7 0.7)
					(thickness 0.15)
				)
				(justify left bottom)
			)
		)
		(pad "1" smd roundrect
			(at -0.48 0)
			(size 0.59 0.64)
			(layers "F.Cu" "F.Mask" "F.Paste")
			(roundrect_rratio 0.25)
			(net 381 "/X710 DCDC converters/1V0_PG")
			(pintype "passive")
		)
		(pad "2" smd roundrect
			(at 0.48 0)
			(size 0.59 0.64)
			(layers "F.Cu" "F.Mask" "F.Paste")
			(roundrect_rratio 0.25)
			(net 386 "/X710 DCDC converters/DVDD_EN")
			(pintype "passive")
		)
	)
	(footprint "antmicro-footprints:BarrelJack_Pin1.3mm_694103107102"
		(layer "F.Cu")
		(at 133 50 90)
		(property "Reference" "J9"
			(at 3 5.4 90)
			(layer "F.SilkS")
			(effects
				(font
					(size 0.7 0.7)
					(thickness 0.15)
				)
				(justify left bottom)
			)
		)
		(property "Value" "BarrelJack_Pin1.3mm_694103107102"
			(at -4.92 6.81 90)
			(layer "F.Fab")
			(effects
				(font
					(size 0.7 0.7)
					(thickness 0.15)
				)
				(justify left bottom)
			)
		)
		(property "Datasheet" "https://www.we-online.de/katalog/datasheet/694103107102.pdf"
			(at 0 0 90)
			(layer "F.Fab")
			(hide yes)
			(effects
				(font
					(size 0.7 0.7)
					(thickness 0.15)
				)
				(justify left bottom)
			)
		)
		(property "Description" "DC Power Connector, Jack, 5 A, 1.35 mm, PCB Mount, Surface Mount"
			(at 0 0 90)
			(layer "F.Fab")
			(hide yes)
			(effects
				(font
					(size 0.7 0.7)
					(thickness 0.15)
				)
				(justify left bottom)
			)
		)
		(property "MPN" "694103107102"
			(at 0 0 90)
			(unlocked yes)
			(layer "F.Fab")
			(hide yes)
			(effects
				(font
					(size 1 1)
					(thickness 0.15)
				)
			)
		)
		(property "Manufacturer" "Würth Elektronik"
			(at 0 0 90)
			(unlocked yes)
			(layer "F.Fab")
			(hide yes)
			(effects
				(font
					(size 1 1)
					(thickness 0.15)
				)
			)
		)
		(property "Author" "Antmicro"
			(at 0 0 90)
			(unlocked yes)
			(layer "F.Fab")
			(hide yes)
			(effects
				(font
					(size 1 1)
					(thickness 0.15)
				)
			)
		)
		(property "License" "Apache-2.0"
			(at 0 0 90)
			(unlocked yes)
			(layer "F.Fab")
			(hide yes)
			(effects
				(font
					(size 1 1)
					(thickness 0.15)
				)
			)
		)
		(sheetname "/Power input/")
		(sheetfile "power_input.kicad_sch")
		(attr smd dnp)
		(fp_line
			(start 4.85 -4)
			(end 4.85 4)
			(stroke
				(width 0.15)
				(type solid)
			)
			(layer "F.SilkS")
		)
		(fp_line
			(start 2.65 -4)
			(end 4.85 -4)
			(stroke
				(width 0.15)
				(type solid)
			)
			(layer "F.SilkS")
		)
		(fp_line
			(start 0.05 -4)
			(end -1.85 -4)
			(stroke
				(width 0.15)
				(type solid)
			)
			(layer "F.SilkS")
		)
		(fp_line
			(start 2.65 4)
			(end 4.85 4)
			(stroke
				(width 0.15)
				(type solid)
			)
			(layer "F.SilkS")
		)
		(fp_line
			(start 0.05 4)
			(end -1.85 4)
			(stroke
				(width 0.15)
				(type solid)
			)
			(layer "F.SilkS")
		)
		(fp_line
			(start -4.45 4)
			(end -4.45 -4)
			(stroke
				(width 0.15)
				(type solid)
			)
			(layer "F.SilkS")
		)
		(fp_rect
			(start -4.85 5.8)
			(end 5.25 -5.8)
			(stroke
				(width 0.05)
				(type solid)
			)
			(fill no)
			(layer "F.CrtYd")
		)
		(fp_rect
			(start -4.45 4.9)
			(end 4.85 -4.9)
			(stroke
				(width 0.15)
				(type solid)
			)
			(fill no)
			(layer "F.Fab")
		)
		(fp_text user "plug:"
			(at 5.334 -0.254 90)
			(unlocked yes)
			(layer "F.Fab")
			(effects
				(font
					(size 0.7 0.7)
					(thickness 0.15)
				)
				(justify left bottom)
			)
		)
		(fp_text user "Author: Antmicro"
			(at -4.85 10.2 90)
			(layer "F.Fab")
			(effects
				(font
					(size 0.7 0.7)
					(thickness 0.15)
				)
				(justify left bottom)
			)
		)
		(fp_text user "Ø3.5/1.35mm"
			(at 5.334 1.016 90)
			(unlocked yes)
			(layer "F.Fab")
			(effects
				(font
					(size 0.7 0.7)
					(thickness 0.15)
				)
				(justify left bottom)
			)
		)
		(fp_text user "License: Apache-2.0"
			(at -4.85 7.8 90)
			(layer "F.Fab")
			(effects
				(font
					(size 0.7 0.7)
					(thickness 0.15)
				)
				(justify left bottom)
			)
		)
		(fp_text user "${REFERENCE}"
			(at -4.85 9 90)
			(layer "F.Fab")
			(effects
				(font
					(size 0.7 0.7)
					(thickness 0.15)
				)
				(justify left bottom)
			)
		)
		(pad "" np_thru_hole circle
			(at -1.65 0 180)
			(size 1 1)
			(drill 1)
			(layers "*.Cu" "*.Mask" "F.SilkS")
		)
		(pad "" np_thru_hole circle
			(at 3.35 0 180)
			(size 1 1)
			(drill 1)
			(layers "*.Cu" "*.Mask" "F.SilkS")
		)
		(pad "1" smd rect
			(at -3.15 4.3)
			(size 2.2 2.2)
			(layers "F.Cu" "F.Mask" "F.Paste")
			(net 412 "Net-(D15-C)")
			(pinfunction "1")
			(pintype "passive")
		)
		(pad "1" smd rect
			(at 1.35 4.3)
			(size 2.2 2.2)
			(layers "F.Cu" "F.Mask" "F.Paste")
			(net 412 "Net-(D15-C)")
			(pinfunction "1")
			(pintype "passive")
		)
		(pad "2" smd rect
			(at 1.35 -4.3)
			(size 2.2 2.2)
			(layers "F.Cu" "F.Mask" "F.Paste")
			(net 23 "GND")
			(pinfunction "2")
			(pintype "passive")
		)
		(pad "3" smd rect
			(at -3.15 -4.3)
			(size 2.2 2.2)
			(layers "F.Cu" "F.Mask" "F.Paste")
			(net 23 "GND")
			(pinfunction "3")
			(pintype "passive")
		)
	)
	(footprint "antmicro-footprints:R_0402_1005Metric"
		(layer "F.Cu")
		(at 117 145.6)
		(descr "Resistor SMD 0402")
		(tags "resistor SMD 0402")
		(property "Reference" "R1"
			(at 1 0.4 0)
			(layer "F.SilkS")
			(effects
				(font
					(size 0.7 0.7)
					(thickness 0.15)
				)
				(justify left bottom)
			)
		)
		(property "Value" "R_2k2_0402"
			(at -1.011843 1.772047 0)
			(layer "F.Fab")
			(effects
				(font
					(size 0.7 0.7)
					(thickness 0.15)
				)
				(justify left bottom)
			)
		)
		(property "Datasheet" "https://www.bourns.com/docs/product-datasheets/cr.pdf"
			(at 0 0 0)
			(layer "F.Fab")
			(hide yes)
			(effects
				(font
					(size 1.27 1.27)
					(thickness 0.15)
				)
			)
		)
		(property "Description" "SMD Chip Resistor, 2.2 kohm, ± 1%, 62.5 mW, 0402 [1005 Metric], Thick Film, General Purpose"
			(at 0 0 0)
			(layer "F.Fab")
			(hide yes)
			(effects
				(font
					(size 1.27 1.27)
					(thickness 0.15)
				)
			)
		)
		(property "MPN" "CR0402-FX-2201GLF"
			(at 0 0 0)
			(unlocked yes)
			(layer "F.Fab")
			(hide yes)
			(effects
				(font
					(size 1 1)
					(thickness 0.15)
				)
			)
		)
		(property "Manufacturer" "Bourns"
			(at 0 0 0)
			(unlocked yes)
			(layer "F.Fab")
			(hide yes)
			(effects
				(font
					(size 1 1)
					(thickness 0.15)
				)
			)
		)
		(property "License" "Apache-2.0"
			(at 0 0 0)
			(unlocked yes)
			(layer "F.Fab")
			(hide yes)
			(effects
				(font
					(size 1 1)
					(thickness 0.15)
				)
			)
		)
		(property "Author" "Antmicro"
			(at 0 0 0)
			(unlocked yes)
			(layer "F.Fab")
			(hide yes)
			(effects
				(font
					(size 1 1)
					(thickness 0.15)
				)
			)
		)
		(property "Val" "2k2"
			(at 0 0 0)
			(unlocked yes)
			(layer "F.Fab")
			(hide yes)
			(effects
				(font
					(size 1 1)
					(thickness 0.15)
				)
			)
		)
		(property "Tolerance" "1%"
			(at 0 0 0)
			(unlocked yes)
			(layer "F.Fab")
			(hide yes)
			(effects
				(font
					(size 1 1)
					(thickness 0.15)
				)
			)
		)
		(sheetname "/USB-C connector/")
		(sheetfile "USB-C_connector.kicad_sch")
		(attr smd)
		(fp_rect
			(start -0.925 -0.47)
			(end 0.925 0.47)
			(stroke
				(width 0.05)
				(type default)
			)
			(fill no)
			(layer "F.CrtYd")
		)
		(fp_rect
			(start -0.5 -0.25)
			(end 0.5 0.25)
			(stroke
				(width 0.15)
				(type solid)
			)
			(fill no)
			(layer "F.Fab")
		)
		(fp_text user "${REFERENCE}"
			(at -0.95 3.168 0)
			(layer "F.Fab")
			(effects
				(font
					(size 0.7 0.7)
					(thickness 0.15)
				)
				(justify left bottom)
			)
		)
		(fp_text user "License: Apache-2.0"
			(at -0.95 5.169 0)
			(layer "F.Fab")
			(effects
				(font
					(size 0.7 0.7)
					(thickness 0.15)
				)
				(justify left bottom)
			)
		)
		(fp_text user "Author: Antmicro"
			(at -0.95 4.169 0)
			(layer "F.Fab")
			(effects
				(font
					(size 0.7 0.7)
					(thickness 0.15)
				)
				(justify left bottom)
			)
		)
		(pad "1" smd roundrect
			(at -0.48 0)
			(size 0.59 0.64)
			(layers "F.Cu" "F.Mask" "F.Paste")
			(roundrect_rratio 0.25)
			(net 23 "GND")
			(pintype "passive")
		)
		(pad "2" smd roundrect
			(at 0.48 0)
			(size 0.59 0.64)
			(layers "F.Cu" "F.Mask" "F.Paste")
			(roundrect_rratio 0.25)
			(net 434 "Net-(U1-ISET)")
			(pintype "passive")
		)
	)
	(footprint "antmicro-footprints:Mech_Lightpipe_Mentor_1271.1001"
		(layer "F.Cu")
		(at 139.55 147.813534 180)
		(descr "1x1  Horizontal Light Guide with transparent pipe")
		(tags "Horizontal, THT, MECHANICAL, MODULE")
		(property "Reference" "H2"
			(at 1.8 -3.386466 0)
			(unlocked yes)
			(layer "F.SilkS")
			(effects
				(font
					(size 0.7 0.7)
					(thickness 0.15)
				)
				(justify left bottom)
			)
		)
		(property "Value" "Lightpipe_Mentor_1271.1001"
			(at 0 9 180)
			(unlocked yes)
			(layer "F.Fab")
			(effects
				(font
					(size 0.7 0.7)
					(thickness 0.15)
				)
				(justify left bottom)
			)
		)
		(property "Datasheet" "https://www.mentor.de.com/productpdfs/ll/ll14-20.pdf"
			(at 0 0 180)
			(layer "F.Fab")
			(hide yes)
			(effects
				(font
					(size 1.27 1.27)
					(thickness 0.15)
				)
			)
		)
		(property "Description" "Light Pipe, 14.45 mm, 1 Pipe, Circular, PC Board, Transparent"
			(at 0 0 180)
			(layer "F.Fab")
			(hide yes)
			(effects
				(font
					(size 1.27 1.27)
					(thickness 0.15)
				)
			)
		)
		(property "MPN" "1271.1001"
			(at 0 0 180)
			(unlocked yes)
			(layer "F.Fab")
			(hide yes)
			(effects
				(font
					(size 1 1)
					(thickness 0.15)
				)
			)
		)
		(property "Manufacturer" "Mentor Worldwide"
			(at 0 0 180)
			(unlocked yes)
			(layer "F.Fab")
			(hide yes)
			(effects
				(font
					(size 1 1)
					(thickness 0.15)
				)
			)
		)
		(property "Author" "Antmicro"
			(at 0 0 180)
			(unlocked yes)
			(layer "F.Fab")
			(hide yes)
			(effects
				(font
					(size 1 1)
					(thickness 0.15)
				)
			)
		)
		(property "License" "Apache-2.0"
			(at 0 0 180)
			(unlocked yes)
			(layer "F.Fab")
			(hide yes)
			(effects
				(font
					(size 1 1)
					(thickness 0.15)
				)
			)
		)
		(sheetname "/")
		(sheetfile "thunderbolt-to-10gbe-adapter.kicad_sch")
		(attr through_hole)
		(fp_rect
			(start -1.55 -2.1)
			(end 1.55 1.3)
			(stroke
				(width 0.05)
				(type solid)
			)
			(fill no)
			(layer "F.SilkS")
		)
		(fp_rect
			(start -1.75 -2.3)
			(end 1.75 1.475)
			(stroke
				(width 0.05)
				(type solid)
			)
			(fill no)
			(layer "F.CrtYd")
		)
		(fp_rect
			(start -1.4732 -8.128)
			(end 1.4732 6.2484)
			(stroke
				(width 0.15)
				(type solid)
			)
			(fill no)
			(layer "F.Fab")
		)
		(fp_text user "License: Apache-2.0"
			(at -1.8 11.7 180)
			(layer "F.Fab")
			(effects
				(font
					(size 0.7 0.7)
					(thickness 0.15)
				)
				(justify left bottom)
			)
		)
		(fp_text user "Author: Antmicro"
			(at -1.8 10.5 180)
			(layer "F.Fab")
			(effects
				(font
					(size 0.7 0.7)
					(thickness 0.15)
				)
				(justify left bottom)
			)
		)
		(fp_text user "${REFERENCE}"
			(at -1.8 12.9 180)
			(layer "F.Fab")
			(effects
				(font
					(size 0.7 0.7)
					(thickness 0.15)
				)
				(justify left bottom)
			)
		)
		(pad "" np_thru_hole circle
			(at 0 0 180)
			(size 2.3 2.3)
			(drill 2.3)
			(layers "*.Cu" "*.Mask")
		)
	)
	(footprint "antmicro-footprints:MP_Pad6mm_Drill3.2mm"
		(layer "F.Cu")
		(at 120 135.25)
		(property "Reference" "MP1"
			(at 1.5 -3.15 0)
			(layer "F.SilkS")
			(effects
				(font
					(size 0.7 0.7)
					(thickness 0.15)
				)
				(justify left bottom)
			)
		)
		(property "Value" "MP_Pad6mm_Drill3.2mm"
			(at 0 3.9 0)
			(layer "F.Fab")
			(effects
				(font
					(size 0.7 0.7)
					(thickness 0.15)
				)
				(justify left bottom)
			)
		)
		(property "Description" "Mechanical part"
			(at 0 0 0)
			(layer "F.Fab")
			(hide yes)
			(effects
				(font
					(size 1.27 1.27)
					(thickness 0.15)
				)
			)
		)
		(property "Author" "Antmicro"
			(at 0 0 0)
			(unlocked yes)
			(layer "F.Fab")
			(hide yes)
			(effects
				(font
					(size 1 1)
					(thickness 0.15)
				)
			)
		)
		(property "License" "Apache-2.0"
			(at 0 0 0)
			(unlocked yes)
			(layer "F.Fab")
			(hide yes)
			(effects
				(font
					(size 1 1)
					(thickness 0.15)
				)
			)
		)
		(sheetname "/")
		(sheetfile "thunderbolt-to-10gbe-adapter.kicad_sch")
		(attr exclude_from_pos_files exclude_from_bom)
		(fp_circle
			(center 0 0)
			(end 3.25 0)
			(stroke
				(width 0.05)
				(type default)
			)
			(fill no)
			(layer "F.CrtYd")
		)
		(fp_text user "License: Apache-2.0"
			(at -0.178 8.425 0)
			(layer "F.Fab")
			(effects
				(font
					(size 0.7 0.7)
					(thickness 0.15)
				)
				(justify left bottom)
			)
		)
		(fp_text user "Author: Antmicro"
			(at -0.178 7.225 0)
			(layer "F.Fab")
			(effects
				(font
					(size 0.7 0.7)
					(thickness 0.15)
				)
				(justify left bottom)
			)
		)
		(fp_text user "${REFERENCE}"
			(at -0.178 6.025 0)
			(layer "F.Fab")
			(effects
				(font
					(size 0.7 0.7)
					(thickness 0.15)
				)
				(justify left bottom)
			)
		)
		(pad "1" thru_hole circle
			(at 0 0)
			(size 6 6)
			(drill 3.2)
			(layers "*.Cu" "*.Mask")
			(remove_unused_layers no)
			(net 23 "GND")
			(pintype "passive")
		)
	)
	(footprint "antmicro-footprints:R_0402_1005Metric"
		(layer "F.Cu")
		(at 131.52 116.5 90)
		(descr "Resistor SMD 0402")
		(tags "resistor SMD 0402")
		(property "Reference" "R69"
			(at 0.9 0.290003 90)
			(layer "F.SilkS")
			(effects
				(font
					(size 0.7 0.7)
					(thickness 0.15)
				)
				(justify left bottom)
			)
		)
		(property "Value" "R_100R_0402"
			(at -1.011843 1.772047 90)
			(layer "F.Fab")
			(effects
				(font
					(size 0.7 0.7)
					(thickness 0.15)
				)
				(justify left bottom)
			)
		)
		(property "Datasheet" "https://www.bourns.com/docs/product-datasheets/cr.pdf"
			(at 0 0 90)
			(layer "F.Fab")
			(hide yes)
			(effects
				(font
					(size 1.27 1.27)
					(thickness 0.15)
				)
			)
		)
		(property "Description" "SMD Chip Resistor, 100 ohm, ± 1%, 62.5 mW, 0402 [1005 Metric], Thick Film, General Purpose"
			(at 0 0 90)
			(layer "F.Fab")
			(hide yes)
			(effects
				(font
					(size 1.27 1.27)
					(thickness 0.15)
				)
			)
		)
		(property "MPN" "CR0402-FX-1000GLF"
			(at 0 0 90)
			(unlocked yes)
			(layer "F.Fab")
			(hide yes)
			(effects
				(font
					(size 1 1)
					(thickness 0.15)
				)
			)
		)
		(property "Manufacturer" "Bourns"
			(at 0 0 90)
			(unlocked yes)
			(layer "F.Fab")
			(hide yes)
			(effects
				(font
					(size 1 1)
					(thickness 0.15)
				)
			)
		)
		(property "License" "Apache-2.0"
			(at 0 0 90)
			(unlocked yes)
			(layer "F.Fab")
			(hide yes)
			(effects
				(font
					(size 1 1)
					(thickness 0.15)
				)
			)
		)
		(property "Val" "100R"
			(at 0 0 90)
			(unlocked yes)
			(layer "F.Fab")
			(hide yes)
			(effects
				(font
					(size 1 1)
					(thickness 0.15)
				)
			)
		)
		(property "Tolerance" "1%"
			(at 0 0 90)
			(unlocked yes)
			(layer "F.Fab")
			(hide yes)
			(effects
				(font
					(size 1 1)
					(thickness 0.15)
				)
			)
		)
		(property "Author" "Antmicro"
			(at 0 0 90)
			(unlocked yes)
			(layer "F.Fab")
			(hide yes)
			(effects
				(font
					(size 1 1)
					(thickness 0.15)
				)
			)
		)
		(sheetname "/TB Controller/")
		(sheetfile "tb.kicad_sch")
		(attr smd)
		(fp_rect
			(start -0.925 -0.47)
			(end 0.925 0.47)
			(stroke
				(width 0.05)
				(type default)
			)
			(fill no)
			(layer "F.CrtYd")
		)
		(fp_rect
			(start -0.5 -0.25)
			(end 0.5 0.25)
			(stroke
				(width 0.15)
				(type solid)
			)
			(fill no)
			(layer "F.Fab")
		)
		(fp_text user "${REFERENCE}"
			(at -0.95 3.168 90)
			(layer "F.Fab")
			(effects
				(font
					(size 0.7 0.7)
					(thickness 0.15)
				)
				(justify left bottom)
			)
		)
		(fp_text user "License: Apache-2.0"
			(at -0.95 5.169 90)
			(layer "F.Fab")
			(effects
				(font
					(size 0.7 0.7)
					(thickness 0.15)
				)
				(justify left bottom)
			)
		)
		(fp_text user "Author: Antmicro"
			(at -0.95 4.169 90)
			(layer "F.Fab")
			(effects
				(font
					(size 0.7 0.7)
					(thickness 0.15)
				)
				(justify left bottom)
			)
		)
		(pad "1" smd roundrect
			(at -0.48 0 90)
			(size 0.59 0.64)
			(layers "F.Cu" "F.Mask" "F.Paste")
			(roundrect_rratio 0.25)
			(net 238 "Net-(U4D-TEST_PWR_GOOD)")
			(pintype "passive")
		)
		(pad "2" smd roundrect
			(at 0.48 0 90)
			(size 0.59 0.64)
			(layers "F.Cu" "F.Mask" "F.Paste")
			(roundrect_rratio 0.25)
			(net 23 "GND")
			(pintype "passive")
		)
	)
	(footprint "antmicro-footprints:LED_0603_1608Metric_G"
		(layer "F.Cu")
		(at 183.2 71.5)
		(descr "LED SMD 0603 Green")
		(tags "LED SMD 0603 Green")
		(property "Reference" "D7"
			(at -1.2 7.25 0)
			(layer "F.SilkS")
			(effects
				(font
					(size 0.7 0.7)
					(thickness 0.15)
				)
				(justify left bottom)
			)
		)
		(property "Value" "LED_G_0603_LG_L29K-G2J1-24-Z"
			(at -0.001 1.599 0)
			(layer "F.Fab")
			(effects
				(font
					(size 0.7 0.7)
					(thickness 0.15)
				)
				(justify left bottom)
			)
		)
		(property "Datasheet" "https://look.ams-osram.com/m/19ee86b3ae0ee95b/original/LG-L29K.pdf"
			(at 0 0 0)
			(layer "F.Fab")
			(hide yes)
			(effects
				(font
					(size 1.27 1.27)
					(thickness 0.15)
				)
			)
		)
		(property "Description" "LED, Green, SMD, 0603, 20 mA, 1.7 V, 570 nm"
			(at 0 0 0)
			(layer "F.Fab")
			(hide yes)
			(effects
				(font
					(size 1.27 1.27)
					(thickness 0.15)
				)
			)
		)
		(property "MPN" "LG L29K-G2J1-24-Z"
			(at 0 0 0)
			(unlocked yes)
			(layer "F.Fab")
			(hide yes)
			(effects
				(font
					(size 1 1)
					(thickness 0.15)
				)
			)
		)
		(property "Manufacturer" "OSRAM"
			(at 0 0 0)
			(unlocked yes)
			(layer "F.Fab")
			(hide yes)
			(effects
				(font
					(size 1 1)
					(thickness 0.15)
				)
			)
		)
		(property "Color" "Green"
			(at 0 0 0)
			(unlocked yes)
			(layer "F.Fab")
			(hide yes)
			(effects
				(font
					(size 1 1)
					(thickness 0.15)
				)
			)
		)
		(property "Author" "Antmicro"
			(at 0 0 0)
			(unlocked yes)
			(layer "F.Fab")
			(hide yes)
			(effects
				(font
					(size 1 1)
					(thickness 0.15)
				)
			)
		)
		(property "License" "Apache-2.0"
			(at 0 0 0)
			(unlocked yes)
			(layer "F.Fab")
			(hide yes)
			(effects
				(font
					(size 1 1)
					(thickness 0.15)
				)
			)
		)
		(sheetname "/X710 DCDC converters/")
		(sheetfile "DCDC_converters_X710.kicad_sch")
		(attr smd)
		(fp_line
			(start -1.18 -0.319)
			(end -1.18 0.321)
			(stroke
				(width 0.15)
				(type solid)
			)
			(layer "F.SilkS")
		)
		(fp_line
			(start -0.094672 0.001008)
			(end -0.24 0.001008)
			(stroke
				(width 0.1)
				(type solid)
			)
			(layer "F.SilkS")
		)
		(fp_line
			(start -0.094672 0.001008)
			(end 0.105328 -0.198992)
			(stroke
				(width 0.1)
				(type solid)
			)
			(layer "F.SilkS")
		)
		(fp_line
			(start -0.094672 0.201008)
			(end -0.094672 -0.198992)
			(stroke
				(width 0.1)
				(type solid)
			)
			(layer "F.SilkS")
		)
		(fp_line
			(start 0.105328 0.001008)
			(end 0.24 0.001)
			(stroke
				(width 0.1)
				(type solid)
			)
			(layer "F.SilkS")
		)
		(fp_line
			(start 0.105328 0.201008)
			(end -0.094672 0.001008)
			(stroke
				(width 0.1)
				(type solid)
			)
			(layer "F.SilkS")
		)
		(fp_line
			(start 0.105328 0.201008)
			(end 0.105328 -0.198992)
			(stroke
				(width 0.1)
				(type solid)
			)
			(layer "F.SilkS")
		)
		(fp_line
			(start 0.22 -0.35)
			(end -0.22 -0.35)
			(stroke
				(width 0.15)
				(type solid)
			)
			(layer "F.SilkS")
		)
		(fp_line
			(start 0.22 0.35)
			(end -0.22 0.35)
			(stroke
				(width 0.15)
				(type solid)
			)
			(layer "F.SilkS")
		)
		(fp_rect
			(start 1.25 0.65)
			(end -1.25 -0.65)
			(stroke
				(width 0.05)
				(type solid)
			)
			(fill no)
			(layer "F.CrtYd")
		)
		(fp_line
			(start -0.199 -0.202)
			(end -0.199 0.1)
			(stroke
				(width 0.15)
				(type solid)
			)
			(layer "F.Fab")
		)
		(fp_line
			(start -0.199 0)
			(end -0.597 0)
			(stroke
				(width 0.15)
				(type solid)
			)
			(layer "F.Fab")
		)
		(fp_line
			(start -0.199 0.2)
			(end -0.199 0.1)
			(stroke
				(width 0.15)
				(type solid)
			)
			(layer "F.Fab")
		)
		(fp_line
			(start -0.101 0)
			(end 0.201 0.2)
			(stroke
				(width 0.15)
				(type solid)
			)
			(layer "F.Fab")
		)
		(fp_line
			(start 0.201 -0.202)
			(end -0.101 0)
			(stroke
				(width 0.15)
				(type solid)
			)
			(layer "F.Fab")
		)
		(fp_line
			(start 0.201 0)
			(end 0.201 -0.202)
			(stroke
				(width 0.15)
				(type solid)
			)
			(layer "F.Fab")
		)
		(fp_line
			(start 0.201 0.2)
			(end 0.201 0)
			(stroke
				(width 0.15)
				(type solid)
			)
			(layer "F.Fab")
		)
		(fp_line
			(start 0.599 0)
			(end 0.201 0)
			(stroke
				(width 0.15)
				(type solid)
			)
			(layer "F.Fab")
		)
		(fp_rect
			(start 0.848 0.4)
			(end -0.85 -0.402)
			(stroke
				(width 0.15)
				(type solid)
			)
			(fill no)
			(layer "F.Fab")
		)
		(fp_text user "${REFERENCE}"
			(at -1.4224 5.999 0)
			(layer "F.Fab")
			(effects
				(font
					(size 0.7 0.7)
					(thickness 0.15)
				)
				(justify left bottom)
			)
		)
		(fp_text user "License: Apache-2.0"
			(at -1.4224 3.599 0)
			(layer "F.Fab")
			(effects
				(font
					(size 0.7 0.7)
					(thickness 0.15)
				)
				(justify left bottom)
			)
		)
		(fp_text user "Author: Antmicro"
			(at -1.4224 4.799 0)
			(layer "F.Fab")
			(effects
				(font
					(size 0.7 0.7)
					(thickness 0.15)
				)
				(justify left bottom)
			)
		)
		(pad "1" smd roundrect
			(at -0.7 0 180)
			(size 0.8 1)
			(layers "F.Cu" "F.Mask" "F.Paste")
			(roundrect_rratio 0.2)
			(net 415 "Net-(D7-C)")
			(pinfunction "C")
			(pintype "passive")
		)
		(pad "2" smd roundrect
			(at 0.7 0 180)
			(size 0.8 1)
			(layers "F.Cu" "F.Mask" "F.Paste")
			(roundrect_rratio 0.2)
			(net 334 "/X710 DCDC converters/+3V3_OUT")
			(pinfunction "A")
			(pintype "passive")
		)
	)
	(footprint "antmicro-footprints:R_0402_1005Metric"
		(layer "F.Cu")
		(at 162 46.3 -90)
		(descr "Resistor SMD 0402")
		(tags "resistor SMD 0402")
		(property "Reference" "R232"
			(at 1.9 -6.3 270)
			(layer "F.SilkS")
			(effects
				(font
					(size 0.7 0.7)
					(thickness 0.15)
				)
				(justify left bottom)
			)
		)
		(property "Value" "R_10k_0402"
			(at -1.011843 1.772047 270)
			(layer "F.Fab")
			(effects
				(font
					(size 0.7 0.7)
					(thickness 0.15)
				)
				(justify left bottom)
			)
		)
		(property "Datasheet" "https://www.bourns.com/docs/product-datasheets/cr.pdf"
			(at 0 0 270)
			(layer "F.Fab")
			(hide yes)
			(effects
				(font
					(size 1.27 1.27)
					(thickness 0.15)
				)
			)
		)
		(property "Description" "SMD Chip Resistor, 10 kohm, ± 1%, 62.5 mW, 0402 [1005 Metric], Thick Film, General Purpose"
			(at 0 0 270)
			(layer "F.Fab")
			(hide yes)
			(effects
				(font
					(size 1.27 1.27)
					(thickness 0.15)
				)
			)
		)
		(property "MPN" "CR0402-FX-1002GLF"
			(at 0 0 270)
			(unlocked yes)
			(layer "F.Fab")
			(hide yes)
			(effects
				(font
					(size 1 1)
					(thickness 0.15)
				)
			)
		)
		(property "Manufacturer" "Bourns"
			(at 0 0 270)
			(unlocked yes)
			(layer "F.Fab")
			(hide yes)
			(effects
				(font
					(size 1 1)
					(thickness 0.15)
				)
			)
		)
		(property "License" "Apache-2.0"
			(at 0 0 270)
			(unlocked yes)
			(layer "F.Fab")
			(hide yes)
			(effects
				(font
					(size 1 1)
					(thickness 0.15)
				)
			)
		)
		(property "Author" "Antmicro"
			(at 0 0 270)
			(unlocked yes)
			(layer "F.Fab")
			(hide yes)
			(effects
				(font
					(size 1 1)
					(thickness 0.15)
				)
			)
		)
		(property "Val" "10k"
			(at 0 0 270)
			(unlocked yes)
			(layer "F.Fab")
			(hide yes)
			(effects
				(font
					(size 1 1)
					(thickness 0.15)
				)
			)
		)
		(property "Tolerance" "1%"
			(at 0 0 270)
			(unlocked yes)
			(layer "F.Fab")
			(hide yes)
			(effects
				(font
					(size 1 1)
					(thickness 0.15)
				)
			)
		)
		(sheetname "/Power input/")
		(sheetfile "power_input.kicad_sch")
		(attr smd)
		(fp_rect
			(start -0.925 -0.47)
			(end 0.925 0.47)
			(stroke
				(width 0.05)
				(type default)
			)
			(fill no)
			(layer "F.CrtYd")
		)
		(fp_rect
			(start -0.5 -0.25)
			(end 0.5 0.25)
			(stroke
				(width 0.15)
				(type solid)
			)
			(fill no)
			(layer "F.Fab")
		)
		(fp_text user "${REFERENCE}"
			(at -0.95 3.168 270)
			(layer "F.Fab")
			(effects
				(font
					(size 0.7 0.7)
					(thickness 0.15)
				)
				(justify left bottom)
			)
		)
		(fp_text user "Author: Antmicro"
			(at -0.95 4.169 270)
			(layer "F.Fab")
			(effects
				(font
					(size 0.7 0.7)
					(thickness 0.15)
				)
				(justify left bottom)
			)
		)
		(fp_text user "License: Apache-2.0"
			(at -0.95 5.169 270)
			(layer "F.Fab")
			(effects
				(font
					(size 0.7 0.7)
					(thickness 0.15)
				)
				(justify left bottom)
			)
		)
		(pad "1" smd roundrect
			(at -0.48 0 270)
			(size 0.59 0.64)
			(layers "F.Cu" "F.Mask" "F.Paste")
			(roundrect_rratio 0.25)
			(net 23 "GND")
			(pintype "passive")
		)
		(pad "2" smd roundrect
			(at 0.48 0 270)
			(size 0.59 0.64)
			(layers "F.Cu" "F.Mask" "F.Paste")
			(roundrect_rratio 0.25)
			(net 391 "/Power input/5V_FB")
			(pintype "passive")
		)
	)
	(footprint "antmicro-footprints:C_0402_1005Metric"
		(layer "F.Cu")
		(at 116.4 103.1)
		(descr "Capacitor SMD 0402")
		(tags "capacitor SMD 0402")
		(property "Reference" "C11"
			(at 0 -8.1 0)
			(layer "F.SilkS")
			(effects
				(font
					(size 0.7 0.7)
					(thickness 0.15)
				)
			)
		)
		(property "Value" "C_1u_0402"
			(at -1.022927 2.155213 0)
			(layer "F.Fab")
			(effects
				(font
					(size 0.7 0.7)
					(thickness 0.15)
				)
				(justify left bottom)
			)
		)
		(property "Datasheet" "https://product.tdk.com/en/search/capacitor/ceramic/mlcc/info?part_no=C1005X6S1A105K050BC"
			(at 0 0 0)
			(layer "F.Fab")
			(hide yes)
			(effects
				(font
					(size 1.27 1.27)
					(thickness 0.15)
				)
			)
		)
		(property "Description" "SMD Multilayer Ceramic Capacitor, 1 µF, 10 V, 0402 [1005 Metric], ± 10%, X6S, C"
			(at 0 0 0)
			(layer "F.Fab")
			(hide yes)
			(effects
				(font
					(size 1.27 1.27)
					(thickness 0.15)
				)
			)
		)
		(property "MPN" "C1005X6S1A105K050BC"
			(at 0 0 0)
			(unlocked yes)
			(layer "F.Fab")
			(hide yes)
			(effects
				(font
					(size 1 1)
					(thickness 0.15)
				)
			)
		)
		(property "Manufacturer" "TDK"
			(at 0 0 0)
			(unlocked yes)
			(layer "F.Fab")
			(hide yes)
			(effects
				(font
					(size 1 1)
					(thickness 0.15)
				)
			)
		)
		(property "License" "Apache-2.0"
			(at 0 0 0)
			(unlocked yes)
			(layer "F.Fab")
			(hide yes)
			(effects
				(font
					(size 1 1)
					(thickness 0.15)
				)
			)
		)
		(property "Val" "1u"
			(at 0 0 0)
			(unlocked yes)
			(layer "F.Fab")
			(hide yes)
			(effects
				(font
					(size 1 1)
					(thickness 0.15)
				)
			)
		)
		(property "Voltage" ""
			(at 0 0 0)
			(unlocked yes)
			(layer "F.Fab")
			(hide yes)
			(effects
				(font
					(size 1 1)
					(thickness 0.15)
				)
			)
		)
		(property "Dielectric" ""
			(at 0 0 0)
			(unlocked yes)
			(layer "F.Fab")
			(hide yes)
			(effects
				(font
					(size 1 1)
					(thickness 0.15)
				)
			)
		)
		(property "Author" "Antmicro"
			(at 0 0 0)
			(unlocked yes)
			(layer "F.Fab")
			(hide yes)
			(effects
				(font
					(size 1 1)
					(thickness 0.15)
				)
			)
		)
		(sheetname "/PD and TB DC-DC/")
		(sheetfile "PD_and_TB_DC_DC.kicad_sch")
		(attr smd)
		(fp_rect
			(start -0.925 -0.47)
			(end 0.925 0.47)
			(stroke
				(width 0.05)
				(type default)
			)
			(fill no)
			(layer "F.CrtYd")
		)
		(fp_line
			(start -0.494 -0.25)
			(end 0.504 -0.25)
			(stroke
				(width 0.15)
				(type solid)
			)
			(layer "F.Fab")
		)
		(fp_line
			(start -0.494 0.248)
			(end -0.494 -0.25)
			(stroke
				(width 0.15)
				(type solid)
			)
			(layer "F.Fab")
		)
		(fp_line
			(start 0.504 -0.25)
			(end 0.504 0.248)
			(stroke
				(width 0.15)
				(type solid)
			)
			(layer "F.Fab")
		)
		(fp_line
			(start 0.504 0.248)
			(end -0.494 0.248)
			(stroke
				(width 0.15)
				(type solid)
			)
			(layer "F.Fab")
		)
		(fp_text user "License: Apache-2.0"
			(at -0.939 5.799 0)
			(layer "F.Fab")
			(effects
				(font
					(size 0.7 0.7)
					(thickness 0.15)
				)
				(justify left bottom)
			)
		)
		(fp_text user "${REFERENCE}"
			(at -0.939 4.599 0)
			(layer "F.Fab")
			(effects
				(font
					(size 0.7 0.7)
					(thickness 0.15)
				)
				(justify left bottom)
			)
		)
		(fp_text user "Author: Antmicro"
			(at -0.939 3.399 0)
			(layer "F.Fab")
			(effects
				(font
					(size 0.7 0.7)
					(thickness 0.15)
				)
				(justify left bottom)
			)
		)
		(pad "1" smd roundrect
			(at -0.48 0)
			(size 0.59 0.64)
			(layers "F.Cu" "F.Mask" "F.Paste")
			(roundrect_rratio 0.25)
			(net 23 "GND")
			(pintype "passive")
		)
		(pad "2" smd roundrect
			(at 0.48 0)
			(size 0.59 0.64)
			(layers "F.Cu" "F.Mask" "F.Paste")
			(roundrect_rratio 0.25)
			(net 303 "/PD and TB DC-DC/SMPS_LDO")
			(pintype "passive")
		)
	)
	(footprint "antmicro-footprints:C_0603_1608Metric_EIA"
		(layer "F.Cu")
		(at 139.500001 113)
		(descr "Capacitor SMD 0603, IPC-7351 Density Level A")
		(tags "Capacitor 0603")
		(property "Reference" "C110"
			(at 16 16.799998 0)
			(layer "F.SilkS")
			(effects
				(font
					(size 0.7 0.7)
					(thickness 0.15)
				)
			)
		)
		(property "Value" "C_22u_16V_0603"
			(at -1.42757 1.770288 0)
			(layer "F.Fab")
			(effects
				(font
					(size 0.7 0.7)
					(thickness 0.15)
				)
				(justify left bottom)
			)
		)
		(property "Datasheet" "https://product.samsungsem.com/mlcc/CL10A226MO7JZN.do"
			(at 0 0 0)
			(layer "F.Fab")
			(hide yes)
			(effects
				(font
					(size 1.27 1.27)
					(thickness 0.15)
				)
			)
		)
		(property "Description" "SMD Multilayer Ceramic Capacitor"
			(at 0 0 0)
			(layer "F.Fab")
			(hide yes)
			(effects
				(font
					(size 1.27 1.27)
					(thickness 0.15)
				)
			)
		)
		(property "MPN" "CL10A226MO7JZNC"
			(at 0 0 0)
			(unlocked yes)
			(layer "F.Fab")
			(hide yes)
			(effects
				(font
					(size 1 1)
					(thickness 0.15)
				)
			)
		)
		(property "Manufacturer" "Samsung Electro-Mechanics"
			(at 0 0 0)
			(unlocked yes)
			(layer "F.Fab")
			(hide yes)
			(effects
				(font
					(size 1 1)
					(thickness 0.15)
				)
			)
		)
		(property "License" "Apache-2.0"
			(at 0 0 0)
			(unlocked yes)
			(layer "F.Fab")
			(hide yes)
			(effects
				(font
					(size 1 1)
					(thickness 0.15)
				)
			)
		)
		(property "Author" "Antmicro"
			(at 0 0 0)
			(unlocked yes)
			(layer "F.Fab")
			(hide yes)
			(effects
				(font
					(size 1 1)
					(thickness 0.15)
				)
			)
		)
		(property "Val" "22u"
			(at 0 0 0)
			(unlocked yes)
			(layer "F.Fab")
			(hide yes)
			(effects
				(font
					(size 1 1)
					(thickness 0.15)
				)
			)
		)
		(property "Voltage" "16V"
			(at 0 0 0)
			(unlocked yes)
			(layer "F.Fab")
			(hide yes)
			(effects
				(font
					(size 1 1)
					(thickness 0.15)
				)
			)
		)
		(property "Dielectric" ""
			(at 0 0 0)
			(unlocked yes)
			(layer "F.Fab")
			(hide yes)
			(effects
				(font
					(size 1 1)
					(thickness 0.15)
				)
			)
		)
		(sheetname "/X710 DCDC converters/")
		(sheetfile "DCDC_converters_X710.kicad_sch")
		(attr smd)
		(fp_line
			(start -0.15 -0.55)
			(end 0.15 -0.55)
			(stroke
				(width 0.15)
				(type solid)
			)
			(layer "F.SilkS")
		)
		(fp_line
			(start -0.15 0.55)
			(end 0.15 0.55)
			(stroke
				(width 0.15)
				(type solid)
			)
			(layer "F.SilkS")
		)
		(fp_rect
			(start -1.25 -0.65)
			(end 1.25 0.65)
			(stroke
				(width 0.05)
				(type solid)
			)
			(fill no)
			(layer "F.CrtYd")
		)
		(fp_rect
			(start -0.8 -0.45)
			(end 0.8 0.45)
			(stroke
				(width 0.15)
				(type solid)
			)
			(fill no)
			(layer "F.Fab")
		)
		(fp_text user "${REFERENCE}"
			(at -1.682 3.895 0)
			(layer "F.Fab")
			(effects
				(font
					(size 0.7 0.7)
					(thickness 0.15)
				)
				(justify left bottom)
			)
		)
		(fp_text user "License: Apache-2.0"
			(at -1.682 5.895 0)
			(layer "F.Fab")
			(effects
				(font
					(size 0.7 0.7)
					(thickness 0.15)
				)
				(justify left bottom)
			)
		)
		(fp_text user "Author: Antmicro"
			(at -1.682 4.894 0)
			(layer "F.Fab")
			(effects
				(font
					(size 0.7 0.7)
					(thickness 0.15)
				)
				(justify left bottom)
			)
		)
		(pad "1" smd roundrect
			(at -0.7 0)
			(size 0.8 1.1)
			(layers "F.Cu" "F.Mask" "F.Paste")
			(roundrect_rratio 0.2)
			(net 23 "GND")
			(pintype "passive")
		)
		(pad "2" smd roundrect
			(at 0.7 0)
			(size 0.8 1.1)
			(layers "F.Cu" "F.Mask" "F.Paste")
			(roundrect_rratio 0.2)
			(net 40 "+5V")
			(pintype "passive")
		)
	)
	(footprint "antmicro-footprints:R_0402_1005Metric"
		(layer "F.Cu")
		(at 159 46.3 -90)
		(descr "Resistor SMD 0402")
		(tags "resistor SMD 0402")
		(property "Reference" "R229"
			(at 1.9 -6.3 270)
			(layer "F.SilkS")
			(effects
				(font
					(size 0.7 0.7)
					(thickness 0.15)
				)
				(justify left bottom)
			)
		)
		(property "Value" "R_200k_0402"
			(at -1.011843 1.772047 270)
			(layer "F.Fab")
			(effects
				(font
					(size 0.7 0.7)
					(thickness 0.15)
				)
				(justify left bottom)
			)
		)
		(property "Datasheet" "https://www.bourns.com/docs/product-datasheets/cr.pdf"
			(at 0 0 270)
			(layer "F.Fab")
			(hide yes)
			(effects
				(font
					(size 1.27 1.27)
					(thickness 0.15)
				)
			)
		)
		(property "Description" "SMD Chip Resistor, 200 kohm, ± 1%, 62.5 mW, 0402 [1005 Metric], Thick Film, General Purpose"
			(at 0 0 270)
			(layer "F.Fab")
			(hide yes)
			(effects
				(font
					(size 1.27 1.27)
					(thickness 0.15)
				)
			)
		)
		(property "MPN" "CR0402-FX-2003GLF"
			(at 0 0 270)
			(unlocked yes)
			(layer "F.Fab")
			(hide yes)
			(effects
				(font
					(size 1 1)
					(thickness 0.15)
				)
			)
		)
		(property "Manufacturer" "Bourns"
			(at 0 0 270)
			(unlocked yes)
			(layer "F.Fab")
			(hide yes)
			(effects
				(font
					(size 1 1)
					(thickness 0.15)
				)
			)
		)
		(property "License" "Apache-2.0"
			(at 0 0 270)
			(unlocked yes)
			(layer "F.Fab")
			(hide yes)
			(effects
				(font
					(size 1 1)
					(thickness 0.15)
				)
			)
		)
		(property "Author" "Antmicro"
			(at 0 0 270)
			(unlocked yes)
			(layer "F.Fab")
			(hide yes)
			(effects
				(font
					(size 1 1)
					(thickness 0.15)
				)
			)
		)
		(property "Val" "200k"
			(at 0 0 270)
			(unlocked yes)
			(layer "F.Fab")
			(hide yes)
			(effects
				(font
					(size 1 1)
					(thickness 0.15)
				)
			)
		)
		(property "Tolerance" "1%"
			(at 0 0 270)
			(unlocked yes)
			(layer "F.Fab")
			(hide yes)
			(effects
				(font
					(size 1 1)
					(thickness 0.15)
				)
			)
		)
		(sheetname "/Power input/")
		(sheetfile "power_input.kicad_sch")
		(attr smd)
		(fp_rect
			(start -0.925 -0.47)
			(end 0.925 0.47)
			(stroke
				(width 0.05)
				(type default)
			)
			(fill no)
			(layer "F.CrtYd")
		)
		(fp_rect
			(start -0.5 -0.25)
			(end 0.5 0.25)
			(stroke
				(width 0.15)
				(type solid)
			)
			(fill no)
			(layer "F.Fab")
		)
		(fp_text user "License: Apache-2.0"
			(at -0.95 5.169 270)
			(layer "F.Fab")
			(effects
				(font
					(size 0.7 0.7)
					(thickness 0.15)
				)
				(justify left bottom)
			)
		)
		(fp_text user "${REFERENCE}"
			(at -0.95 3.168 270)
			(layer "F.Fab")
			(effects
				(font
					(size 0.7 0.7)
					(thickness 0.15)
				)
				(justify left bottom)
			)
		)
		(fp_text user "Author: Antmicro"
			(at -0.95 4.169 270)
			(layer "F.Fab")
			(effects
				(font
					(size 0.7 0.7)
					(thickness 0.15)
				)
				(justify left bottom)
			)
		)
		(pad "1" smd roundrect
			(at -0.48 0 270)
			(size 0.59 0.64)
			(layers "F.Cu" "F.Mask" "F.Paste")
			(roundrect_rratio 0.25)
			(net 23 "GND")
			(pintype "passive")
		)
		(pad "2" smd roundrect
			(at 0.48 0 270)
			(size 0.59 0.64)
			(layers "F.Cu" "F.Mask" "F.Paste")
			(roundrect_rratio 0.25)
			(net 389 "/Power input/5V_MODE1")
			(pintype "passive")
		)
	)
	(footprint "antmicro-footprints:R_0402_1005Metric"
		(layer "F.Cu")
		(at 117 68.9)
		(descr "Resistor SMD 0402")
		(tags "resistor SMD 0402")
		(property "Reference" "R219"
			(at 3.6 -10.5 0)
			(layer "F.SilkS")
			(effects
				(font
					(size 0.7 0.7)
					(thickness 0.15)
				)
				(justify left bottom)
			)
		)
		(property "Value" "R_1k_0402"
			(at -1.011843 1.772047 0)
			(layer "F.Fab")
			(effects
				(font
					(size 0.7 0.7)
					(thickness 0.15)
				)
				(justify left bottom)
			)
		)
		(property "Datasheet" "https://www.bourns.com/docs/product-datasheets/cr.pdf"
			(at 0 0 0)
			(layer "F.Fab")
			(hide yes)
			(effects
				(font
					(size 1.27 1.27)
					(thickness 0.15)
				)
			)
		)
		(property "Description" "SMD Chip Resistor, 1 kohm, ± 1%, 63 mW, 0402 [1005 Metric], Thick Film, General Purpose"
			(at 0 0 0)
			(layer "F.Fab")
			(hide yes)
			(effects
				(font
					(size 1.27 1.27)
					(thickness 0.15)
				)
			)
		)
		(property "MPN" "CR0402-FX-1001GLF"
			(at 0 0 0)
			(unlocked yes)
			(layer "F.Fab")
			(hide yes)
			(effects
				(font
					(size 1 1)
					(thickness 0.15)
				)
			)
		)
		(property "Manufacturer" "Bourns"
			(at 0 0 0)
			(unlocked yes)
			(layer "F.Fab")
			(hide yes)
			(effects
				(font
					(size 1 1)
					(thickness 0.15)
				)
			)
		)
		(property "License" "Apache-2.0"
			(at 0 0 0)
			(unlocked yes)
			(layer "F.Fab")
			(hide yes)
			(effects
				(font
					(size 1 1)
					(thickness 0.15)
				)
			)
		)
		(property "Author" "Antmicro"
			(at 0 0 0)
			(unlocked yes)
			(layer "F.Fab")
			(hide yes)
			(effects
				(font
					(size 1 1)
					(thickness 0.15)
				)
			)
		)
		(property "Val" "1k"
			(at 0 0 0)
			(unlocked yes)
			(layer "F.Fab")
			(hide yes)
			(effects
				(font
					(size 1 1)
					(thickness 0.15)
				)
			)
		)
		(property "Tolerance" "1%"
			(at 0 0 0)
			(unlocked yes)
			(layer "F.Fab")
			(hide yes)
			(effects
				(font
					(size 1 1)
					(thickness 0.15)
				)
			)
		)
		(sheetname "/Fan controller/")
		(sheetfile "fan-controller.kicad_sch")
		(attr smd)
		(fp_rect
			(start -0.925 -0.47)
			(end 0.925 0.47)
			(stroke
				(width 0.05)
				(type default)
			)
			(fill no)
			(layer "F.CrtYd")
		)
		(fp_rect
			(start -0.5 -0.25)
			(end 0.5 0.25)
			(stroke
				(width 0.15)
				(type solid)
			)
			(fill no)
			(layer "F.Fab")
		)
		(fp_text user "Author: Antmicro"
			(at -0.95 4.169 0)
			(layer "F.Fab")
			(effects
				(font
					(size 0.7 0.7)
					(thickness 0.15)
				)
				(justify left bottom)
			)
		)
		(fp_text user "License: Apache-2.0"
			(at -0.95 5.169 0)
			(layer "F.Fab")
			(effects
				(font
					(size 0.7 0.7)
					(thickness 0.15)
				)
				(justify left bottom)
			)
		)
		(fp_text user "${REFERENCE}"
			(at -0.95 3.168 0)
			(layer "F.Fab")
			(effects
				(font
					(size 0.7 0.7)
					(thickness 0.15)
				)
				(justify left bottom)
			)
		)
		(pad "1" smd roundrect
			(at -0.48 0)
			(size 0.59 0.64)
			(layers "F.Cu" "F.Mask" "F.Paste")
			(roundrect_rratio 0.25)
			(net 23 "GND")
			(pintype "passive")
		)
		(pad "2" smd roundrect
			(at 0.48 0)
			(size 0.59 0.64)
			(layers "F.Cu" "F.Mask" "F.Paste")
			(roundrect_rratio 0.25)
			(net 157 "/Fan controller/DMIN")
			(pintype "passive")
		)
	)
	(footprint "antmicro-footprints:R_0402_1005Metric"
		(layer "F.Cu")
		(at 127.084 87.77)
		(descr "Resistor SMD 0402")
		(tags "resistor SMD 0402")
		(property "Reference" "R118"
			(at -1.084 -0.509 0)
			(layer "F.SilkS")
			(effects
				(font
					(size 0.7 0.7)
					(thickness 0.15)
				)
				(justify left bottom)
			)
		)
		(property "Value" "R_8k2_0402"
			(at -1.011843 1.772047 0)
			(layer "F.Fab")
			(effects
				(font
					(size 0.7 0.7)
					(thickness 0.15)
				)
				(justify left bottom)
			)
		)
		(property "Datasheet" "https://www.bourns.com/docs/product-datasheets/cr.pdf"
			(at 0 0 0)
			(layer "F.Fab")
			(hide yes)
			(effects
				(font
					(size 1.27 1.27)
					(thickness 0.15)
				)
			)
		)
		(property "Description" "SMD Chip Resistor"
			(at 0 0 0)
			(layer "F.Fab")
			(hide yes)
			(effects
				(font
					(size 1.27 1.27)
					(thickness 0.15)
				)
			)
		)
		(property "MPN" "CR0402-FX-8201GLF"
			(at 0 0 0)
			(unlocked yes)
			(layer "F.Fab")
			(hide yes)
			(effects
				(font
					(size 1 1)
					(thickness 0.15)
				)
			)
		)
		(property "Manufacturer" "Bourns"
			(at 0 0 0)
			(unlocked yes)
			(layer "F.Fab")
			(hide yes)
			(effects
				(font
					(size 1 1)
					(thickness 0.15)
				)
			)
		)
		(property "License" "Apache-2.0"
			(at 0 0 0)
			(unlocked yes)
			(layer "F.Fab")
			(hide yes)
			(effects
				(font
					(size 1 1)
					(thickness 0.15)
				)
			)
		)
		(property "Author" "Antmicro"
			(at 0 0 0)
			(unlocked yes)
			(layer "F.Fab")
			(hide yes)
			(effects
				(font
					(size 1 1)
					(thickness 0.15)
				)
			)
		)
		(property "Val" "8k2"
			(at 0 0 0)
			(unlocked yes)
			(layer "F.Fab")
			(hide yes)
			(effects
				(font
					(size 1 1)
					(thickness 0.15)
				)
			)
		)
		(property "Tolerance" "1%"
			(at 0 0 0)
			(unlocked yes)
			(layer "F.Fab")
			(hide yes)
			(effects
				(font
					(size 1 1)
					(thickness 0.15)
				)
			)
		)
		(sheetname "/X710-AT2 PCIe/")
		(sheetfile "x710-at2-pcie.kicad_sch")
		(attr smd)
		(fp_rect
			(start -0.925 -0.47)
			(end 0.925 0.47)
			(stroke
				(width 0.05)
				(type default)
			)
			(fill no)
			(layer "F.CrtYd")
		)
		(fp_rect
			(start -0.5 -0.25)
			(end 0.5 0.25)
			(stroke
				(width 0.15)
				(type solid)
			)
			(fill no)
			(layer "F.Fab")
		)
		(fp_text user "License: Apache-2.0"
			(at -0.95 5.169 0)
			(layer "F.Fab")
			(effects
				(font
					(size 0.7 0.7)
					(thickness 0.15)
				)
				(justify left bottom)
			)
		)
		(fp_text user "Author: Antmicro"
			(at -0.95 4.169 0)
			(layer "F.Fab")
			(effects
				(font
					(size 0.7 0.7)
					(thickness 0.15)
				)
				(justify left bottom)
			)
		)
		(fp_text user "${REFERENCE}"
			(at -0.95 3.168 0)
			(layer "F.Fab")
			(effects
				(font
					(size 0.7 0.7)
					(thickness 0.15)
				)
				(justify left bottom)
			)
		)
		(pad "1" smd roundrect
			(at -0.48 0)
			(size 0.59 0.64)
			(layers "F.Cu" "F.Mask" "F.Paste")
			(roundrect_rratio 0.25)
			(net 4 "/X710-AT2 PCIe/PCIe_JTAG.JTMS")
			(pintype "passive")
		)
		(pad "2" smd roundrect
			(at 0.48 0)
			(size 0.59 0.64)
			(layers "F.Cu" "F.Mask" "F.Paste")
			(roundrect_rratio 0.25)
			(net 7 "+3V3")
			(pintype "passive")
		)
	)
	(footprint "antmicro-footprints:C_0603_1608Metric"
		(layer "F.Cu")
		(at 148.955 68.574999 -90)
		(descr "Capacitor SMD 0603")
		(tags "capacitor 0603")
		(property "Reference" "C215"
			(at -12.274999 -20.045 270)
			(layer "F.SilkS")
			(effects
				(font
					(size 0.7 0.7)
					(thickness 0.15)
				)
			)
		)
		(property "Value" "C_10u_10V_X7R_0603"
			(at -1.42757 1.770288 270)
			(layer "F.Fab")
			(effects
				(font
					(size 0.7 0.7)
					(thickness 0.15)
				)
				(justify left bottom)
			)
		)
		(property "Datasheet" "https://www.murata.com/products/productdetail?partno=GRM188Z71A106KA73%23"
			(at 0 0 270)
			(layer "F.Fab")
			(hide yes)
			(effects
				(font
					(size 1.27 1.27)
					(thickness 0.15)
				)
			)
		)
		(property "Description" "SMD Multilayer Ceramic Capacitor,  10µF, 10V, 0603, ±10%, X7R"
			(at 0 0 270)
			(layer "F.Fab")
			(hide yes)
			(effects
				(font
					(size 1.27 1.27)
					(thickness 0.15)
				)
			)
		)
		(property "MPN" "GRM188Z71A106KA73D"
			(at 0 0 270)
			(unlocked yes)
			(layer "F.Fab")
			(hide yes)
			(effects
				(font
					(size 1 1)
					(thickness 0.15)
				)
			)
		)
		(property "Val" "10u"
			(at 0 0 270)
			(unlocked yes)
			(layer "F.Fab")
			(hide yes)
			(effects
				(font
					(size 1 1)
					(thickness 0.15)
				)
			)
		)
		(property "Voltage" "10V"
			(at 0 0 270)
			(unlocked yes)
			(layer "F.Fab")
			(hide yes)
			(effects
				(font
					(size 1 1)
					(thickness 0.15)
				)
			)
		)
		(property "Dielectric" "X7R"
			(at 0 0 270)
			(unlocked yes)
			(layer "F.Fab")
			(hide yes)
			(effects
				(font
					(size 1 1)
					(thickness 0.15)
				)
			)
		)
		(property "Manufacturer" "Murata"
			(at 0 0 270)
			(unlocked yes)
			(layer "F.Fab")
			(hide yes)
			(effects
				(font
					(size 1 1)
					(thickness 0.15)
				)
			)
		)
		(property "License" "Apache-2.0"
			(at 0 0 270)
			(unlocked yes)
			(layer "F.Fab")
			(hide yes)
			(effects
				(font
					(size 1 1)
					(thickness 0.15)
				)
			)
		)
		(property "Author" "Antmicro"
			(at 0 0 270)
			(unlocked yes)
			(layer "F.Fab")
			(hide yes)
			(effects
				(font
					(size 1 1)
					(thickness 0.15)
				)
			)
		)
		(sheetname "/X710-AT2 power/")
		(sheetfile "x710-at2-power.kicad_sch")
		(attr smd)
		(fp_line
			(start -0.15 0.4)
			(end 0.15 0.4)
			(stroke
				(width 0.15)
				(type solid)
			)
			(layer "F.SilkS")
		)
		(fp_line
			(start -0.15 -0.4)
			(end 0.15 -0.4)
			(stroke
				(width 0.15)
				(type solid)
			)
			(layer "F.SilkS")
		)
		(fp_rect
			(start -1.25 -0.65)
			(end 1.25 0.65)
			(stroke
				(width 0.05)
				(type solid)
			)
			(fill no)
			(layer "F.CrtYd")
		)
		(fp_rect
			(start -0.8 -0.4)
			(end 0.8 0.4)
			(stroke
				(width 0.15)
				(type solid)
			)
			(fill no)
			(layer "F.Fab")
		)
		(fp_text user "License: Apache-2.0"
			(at -1.682 5.895 270)
			(layer "F.Fab")
			(effects
				(font
					(size 0.7 0.7)
					(thickness 0.15)
				)
				(justify left bottom)
			)
		)
		(fp_text user "${REFERENCE}"
			(at -1.682 3.895 270)
			(layer "F.Fab")
			(effects
				(font
					(size 0.7 0.7)
					(thickness 0.15)
				)
				(justify left bottom)
			)
		)
		(fp_text user "Author: Antmicro"
			(at -1.682 4.894 270)
			(layer "F.Fab")
			(effects
				(font
					(size 0.7 0.7)
					(thickness 0.15)
				)
				(justify left bottom)
			)
		)
		(pad "1" smd roundrect
			(at -0.7 0 270)
			(size 0.8 1)
			(layers "F.Cu" "F.Mask" "F.Paste")
			(roundrect_rratio 0.2)
			(net 23 "GND")
			(pintype "passive")
		)
		(pad "2" smd roundrect
			(at 0.7 0 270)
			(size 0.8 1)
			(layers "F.Cu" "F.Mask" "F.Paste")
			(roundrect_rratio 0.2)
			(net 7 "+3V3")
			(pintype "passive")
		)
	)
	(footprint "antmicro-footprints:R_0402_1005Metric"
		(layer "F.Cu")
		(at 160 46.3 -90)
		(descr "Resistor SMD 0402")
		(tags "resistor SMD 0402")
		(property "Reference" "R230"
			(at 1.9 -6.3 270)
			(layer "F.SilkS")
			(effects
				(font
					(size 0.7 0.7)
					(thickness 0.15)
				)
				(justify left bottom)
			)
		)
		(property "Value" "R_100k_0402"
			(at -1.011843 1.772047 270)
			(layer "F.Fab")
			(effects
				(font
					(size 0.7 0.7)
					(thickness 0.15)
				)
				(justify left bottom)
			)
		)
		(property "Datasheet" "https://www.bourns.com/docs/product-datasheets/cr.pdf"
			(at 0 0 270)
			(layer "F.Fab")
			(hide yes)
			(effects
				(font
					(size 1.27 1.27)
					(thickness 0.15)
				)
			)
		)
		(property "Description" "SMD Chip Resistor, 100 kohm, ± 1%, 62.5 mW, 0402 [1005 Metric], Thick Film, General Purpose"
			(at 0 0 270)
			(layer "F.Fab")
			(hide yes)
			(effects
				(font
					(size 1.27 1.27)
					(thickness 0.15)
				)
			)
		)
		(property "MPN" "CR0402-FX-1003GLF"
			(at 0 0 270)
			(unlocked yes)
			(layer "F.Fab")
			(hide yes)
			(effects
				(font
					(size 1 1)
					(thickness 0.15)
				)
			)
		)
		(property "Manufacturer" "Bourns"
			(at 0 0 270)
			(unlocked yes)
			(layer "F.Fab")
			(hide yes)
			(effects
				(font
					(size 1 1)
					(thickness 0.15)
				)
			)
		)
		(property "License" "Apache-2.0"
			(at 0 0 270)
			(unlocked yes)
			(layer "F.Fab")
			(hide yes)
			(effects
				(font
					(size 1 1)
					(thickness 0.15)
				)
			)
		)
		(property "Author" "Antmicro"
			(at 0 0 270)
			(unlocked yes)
			(layer "F.Fab")
			(hide yes)
			(effects
				(font
					(size 1 1)
					(thickness 0.15)
				)
			)
		)
		(property "Val" "100k"
			(at 0 0 270)
			(unlocked yes)
			(layer "F.Fab")
			(hide yes)
			(effects
				(font
					(size 1 1)
					(thickness 0.15)
				)
			)
		)
		(property "Tolerance" "1%"
			(at 0 0 270)
			(unlocked yes)
			(layer "F.Fab")
			(hide yes)
			(effects
				(font
					(size 1 1)
					(thickness 0.15)
				)
			)
		)
		(sheetname "/Power input/")
		(sheetfile "power_input.kicad_sch")
		(attr smd)
		(fp_rect
			(start -0.925 -0.47)
			(end 0.925 0.47)
			(stroke
				(width 0.05)
				(type default)
			)
			(fill no)
			(layer "F.CrtYd")
		)
		(fp_rect
			(start -0.5 -0.25)
			(end 0.5 0.25)
			(stroke
				(width 0.15)
				(type solid)
			)
			(fill no)
			(layer "F.Fab")
		)
		(fp_text user "Author: Antmicro"
			(at -0.95 4.169 270)
			(layer "F.Fab")
			(effects
				(font
					(size 0.7 0.7)
					(thickness 0.15)
				)
				(justify left bottom)
			)
		)
		(fp_text user "License: Apache-2.0"
			(at -0.95 5.169 270)
			(layer "F.Fab")
			(effects
				(font
					(size 0.7 0.7)
					(thickness 0.15)
				)
				(justify left bottom)
			)
		)
		(fp_text user "${REFERENCE}"
			(at -0.95 3.168 270)
			(layer "F.Fab")
			(effects
				(font
					(size 0.7 0.7)
					(thickness 0.15)
				)
				(justify left bottom)
			)
		)
		(pad "1" smd roundrect
			(at -0.48 0 270)
			(size 0.59 0.64)
			(layers "F.Cu" "F.Mask" "F.Paste")
			(roundrect_rratio 0.25)
			(net 23 "GND")
			(pintype "passive")
		)
		(pad "2" smd roundrect
			(at 0.48 0 270)
			(size 0.59 0.64)
			(layers "F.Cu" "F.Mask" "F.Paste")
			(roundrect_rratio 0.25)
			(net 390 "/Power input/5V_MODE2")
			(pintype "passive")
		)
	)
	(footprint "antmicro-footprints:R_0402_1005Metric"
		(layer "F.Cu")
		(at 156.205 65.174999 90)
		(descr "Resistor SMD 0402")
		(tags "resistor SMD 0402")
		(property "Reference" "R161"
			(at 2.374999 0.095001 90)
			(layer "F.SilkS")
			(effects
				(font
					(size 0.7 0.7)
					(thickness 0.15)
				)
			)
		)
		(property "Value" "R_10k_0402"
			(at -1.011843 1.772047 90)
			(layer "F.Fab")
			(effects
				(font
					(size 0.7 0.7)
					(thickness 0.15)
				)
				(justify left bottom)
			)
		)
		(property "Datasheet" "https://www.bourns.com/docs/product-datasheets/cr.pdf"
			(at 0 0 90)
			(layer "F.Fab")
			(hide yes)
			(effects
				(font
					(size 1.27 1.27)
					(thickness 0.15)
				)
			)
		)
		(property "Description" "SMD Chip Resistor, 10 kohm, ± 1%, 62.5 mW, 0402 [1005 Metric], Thick Film, General Purpose"
			(at 0 0 90)
			(layer "F.Fab")
			(hide yes)
			(effects
				(font
					(size 1.27 1.27)
					(thickness 0.15)
				)
			)
		)
		(property "MPN" "CR0402-FX-1002GLF"
			(at 0 0 90)
			(unlocked yes)
			(layer "F.Fab")
			(hide yes)
			(effects
				(font
					(size 1 1)
					(thickness 0.15)
				)
			)
		)
		(property "Manufacturer" "Bourns"
			(at 0 0 90)
			(unlocked yes)
			(layer "F.Fab")
			(hide yes)
			(effects
				(font
					(size 1 1)
					(thickness 0.15)
				)
			)
		)
		(property "License" "Apache-2.0"
			(at 0 0 90)
			(unlocked yes)
			(layer "F.Fab")
			(hide yes)
			(effects
				(font
					(size 1 1)
					(thickness 0.15)
				)
			)
		)
		(property "Author" "Antmicro"
			(at 0 0 90)
			(unlocked yes)
			(layer "F.Fab")
			(hide yes)
			(effects
				(font
					(size 1 1)
					(thickness 0.15)
				)
			)
		)
		(property "Val" "10k"
			(at 0 0 90)
			(unlocked yes)
			(layer "F.Fab")
			(hide yes)
			(effects
				(font
					(size 1 1)
					(thickness 0.15)
				)
			)
		)
		(property "Tolerance" "1%"
			(at 0 0 90)
			(unlocked yes)
			(layer "F.Fab")
			(hide yes)
			(effects
				(font
					(size 1 1)
					(thickness 0.15)
				)
			)
		)
		(sheetname "/X710-AT2 Misc/")
		(sheetfile "x710-at2-mics.kicad_sch")
		(attr smd)
		(fp_rect
			(start -0.925 -0.47)
			(end 0.925 0.47)
			(stroke
				(width 0.05)
				(type default)
			)
			(fill no)
			(layer "F.CrtYd")
		)
		(fp_rect
			(start -0.5 -0.25)
			(end 0.5 0.25)
			(stroke
				(width 0.15)
				(type solid)
			)
			(fill no)
			(layer "F.Fab")
		)
		(fp_text user "Author: Antmicro"
			(at -0.95 4.169 90)
			(layer "F.Fab")
			(effects
				(font
					(size 0.7 0.7)
					(thickness 0.15)
				)
				(justify left bottom)
			)
		)
		(fp_text user "License: Apache-2.0"
			(at -0.95 5.169 90)
			(layer "F.Fab")
			(effects
				(font
					(size 0.7 0.7)
					(thickness 0.15)
				)
				(justify left bottom)
			)
		)
		(fp_text user "${REFERENCE}"
			(at -0.95 3.168 90)
			(layer "F.Fab")
			(effects
				(font
					(size 0.7 0.7)
					(thickness 0.15)
				)
				(justify left bottom)
			)
		)
		(pad "1" smd roundrect
			(at -0.48 0 90)
			(size 0.59 0.64)
			(layers "F.Cu" "F.Mask" "F.Paste")
			(roundrect_rratio 0.25)
			(net 23 "GND")
			(pintype "passive")
		)
		(pad "2" smd roundrect
			(at 0.48 0 90)
			(size 0.59 0.64)
			(layers "F.Cu" "F.Mask" "F.Paste")
			(roundrect_rratio 0.25)
			(net 145 "/X710-AT2 Misc/NCSI.ARB_IN")
			(pintype "passive")
		)
	)
	(footprint "antmicro-footprints:C_0402_1005Metric"
		(layer "F.Cu")
		(at 117.8 127 180)
		(descr "Capacitor SMD 0402")
		(tags "capacitor SMD 0402")
		(property "Reference" "C47"
			(at -0.8 -0.2 180)
			(layer "F.SilkS")
			(effects
				(font
					(size 0.7 0.7)
					(thickness 0.15)
				)
				(justify left bottom)
			)
		)
		(property "Value" "C_220n_0402"
			(at -1.022927 2.155213 180)
			(layer "F.Fab")
			(effects
				(font
					(size 0.7 0.7)
					(thickness 0.15)
				)
				(justify left bottom)
			)
		)
		(property "Datasheet" "https://www.yageo.com/en/Chart/Download/pdf/CC0402KRX5R6BB224"
			(at 0 0 180)
			(layer "F.Fab")
			(hide yes)
			(effects
				(font
					(size 1.27 1.27)
					(thickness 0.15)
				)
			)
		)
		(property "Description" "SMD Multilayer Ceramic Capacitor, 0.22 µF, 10 V, 0402 [1005 Metric], ± 10%, X5R, CC Series"
			(at 0 0 180)
			(layer "F.Fab")
			(hide yes)
			(effects
				(font
					(size 1.27 1.27)
					(thickness 0.15)
				)
			)
		)
		(property "MPN" "CC0402KRX5R6BB224"
			(at 0 0 180)
			(unlocked yes)
			(layer "F.Fab")
			(hide yes)
			(effects
				(font
					(size 1 1)
					(thickness 0.15)
				)
			)
		)
		(property "Manufacturer" "YAGEO"
			(at 0 0 180)
			(unlocked yes)
			(layer "F.Fab")
			(hide yes)
			(effects
				(font
					(size 1 1)
					(thickness 0.15)
				)
			)
		)
		(property "License" "Apache-2.0"
			(at 0 0 180)
			(unlocked yes)
			(layer "F.Fab")
			(hide yes)
			(effects
				(font
					(size 1 1)
					(thickness 0.15)
				)
			)
		)
		(property "Val" "220n"
			(at 0 0 180)
			(unlocked yes)
			(layer "F.Fab")
			(hide yes)
			(effects
				(font
					(size 1 1)
					(thickness 0.15)
				)
			)
		)
		(property "Voltage" ""
			(at 0 0 180)
			(unlocked yes)
			(layer "F.Fab")
			(hide yes)
			(effects
				(font
					(size 1 1)
					(thickness 0.15)
				)
			)
		)
		(property "Dielectric" ""
			(at 0 0 180)
			(unlocked yes)
			(layer "F.Fab")
			(hide yes)
			(effects
				(font
					(size 1 1)
					(thickness 0.15)
				)
			)
		)
		(property "Author" "Antmicro"
			(at 0 0 180)
			(unlocked yes)
			(layer "F.Fab")
			(hide yes)
			(effects
				(font
					(size 1 1)
					(thickness 0.15)
				)
			)
		)
		(sheetname "/TB Controller/")
		(sheetfile "tb.kicad_sch")
		(attr smd)
		(fp_rect
			(start -0.925 -0.47)
			(end 0.925 0.47)
			(stroke
				(width 0.05)
				(type default)
			)
			(fill no)
			(layer "F.CrtYd")
		)
		(fp_line
			(start 0.504 0.248)
			(end -0.494 0.248)
			(stroke
				(width 0.15)
				(type solid)
			)
			(layer "F.Fab")
		)
		(fp_line
			(start 0.504 -0.25)
			(end 0.504 0.248)
			(stroke
				(width 0.15)
				(type solid)
			)
			(layer "F.Fab")
		)
		(fp_line
			(start -0.494 0.248)
			(end -0.494 -0.25)
			(stroke
				(width 0.15)
				(type solid)
			)
			(layer "F.Fab")
		)
		(fp_line
			(start -0.494 -0.25)
			(end 0.504 -0.25)
			(stroke
				(width 0.15)
				(type solid)
			)
			(layer "F.Fab")
		)
		(fp_text user "${REFERENCE}"
			(at -0.939 4.599 180)
			(layer "F.Fab")
			(effects
				(font
					(size 0.7 0.7)
					(thickness 0.15)
				)
				(justify left bottom)
			)
		)
		(fp_text user "Author: Antmicro"
			(at -0.939 3.399 180)
			(layer "F.Fab")
			(effects
				(font
					(size 0.7 0.7)
					(thickness 0.15)
				)
				(justify left bottom)
			)
		)
		(fp_text user "License: Apache-2.0"
			(at -0.939 5.799 180)
			(layer "F.Fab")
			(effects
				(font
					(size 0.7 0.7)
					(thickness 0.15)
				)
				(justify left bottom)
			)
		)
		(pad "1" smd roundrect
			(at -0.48 0 180)
			(size 0.59 0.64)
			(layers "F.Cu" "F.Mask" "F.Paste")
			(roundrect_rratio 0.25)
			(net 329 "/TB Controller/TB_PCIE_TX3_P")
			(pintype "passive")
		)
		(pad "2" smd roundrect
			(at 0.48 0 180)
			(size 0.59 0.64)
			(layers "F.Cu" "F.Mask" "F.Paste")
			(roundrect_rratio 0.25)
			(net 321 "/TB Controller/PCIex4.RX3+")
			(pintype "passive")
		)
	)
	(footprint "antmicro-footprints:R_0402_1005Metric"
		(layer "F.Cu")
		(at 143.849998 110.15 180)
		(descr "Resistor SMD 0402")
		(tags "resistor SMD 0402")
		(property "Reference" "R106"
			(at -15.349999 -17.25 180)
			(layer "F.SilkS")
			(effects
				(font
					(size 0.7 0.7)
					(thickness 0.15)
				)
			)
		)
		(property "Value" "R_20k_0402"
			(at -1.011843 1.772047 180)
			(layer "F.Fab")
			(effects
				(font
					(size 0.7 0.7)
					(thickness 0.15)
				)
				(justify left bottom)
			)
		)
		(property "Datasheet" "https://www.bourns.com/docs/product-datasheets/cr.pdf"
			(at 0 0 180)
			(layer "F.Fab")
			(hide yes)
			(effects
				(font
					(size 1.27 1.27)
					(thickness 0.15)
				)
			)
		)
		(property "Description" "SMD Chip Resistor, 20 kohm, ± 1%, 62.5 mW, 0402 [1005 Metric], Thick Film, General Purpose"
			(at 0 0 180)
			(layer "F.Fab")
			(hide yes)
			(effects
				(font
					(size 1.27 1.27)
					(thickness 0.15)
				)
			)
		)
		(property "MPN" "CR0402-FX-2002GLF"
			(at 0 0 180)
			(unlocked yes)
			(layer "F.Fab")
			(hide yes)
			(effects
				(font
					(size 1 1)
					(thickness 0.15)
				)
			)
		)
		(property "Manufacturer" "Bourns"
			(at 0 0 180)
			(unlocked yes)
			(layer "F.Fab")
			(hide yes)
			(effects
				(font
					(size 1 1)
					(thickness 0.15)
				)
			)
		)
		(property "License" "Apache-2.0"
			(at 0 0 180)
			(unlocked yes)
			(layer "F.Fab")
			(hide yes)
			(effects
				(font
					(size 1 1)
					(thickness 0.15)
				)
			)
		)
		(property "Author" "Antmicro"
			(at 0 0 180)
			(unlocked yes)
			(layer "F.Fab")
			(hide yes)
			(effects
				(font
					(size 1 1)
					(thickness 0.15)
				)
			)
		)
		(property "Val" "20k"
			(at 0 0 180)
			(unlocked yes)
			(layer "F.Fab")
			(hide yes)
			(effects
				(font
					(size 1 1)
					(thickness 0.15)
				)
			)
		)
		(property "Tolerance" "1%"
			(at 0 0 180)
			(unlocked yes)
			(layer "F.Fab")
			(hide yes)
			(effects
				(font
					(size 1 1)
					(thickness 0.15)
				)
			)
		)
		(sheetname "/X710 DCDC converters/")
		(sheetfile "DCDC_converters_X710.kicad_sch")
		(attr smd)
		(fp_rect
			(start -0.925 -0.47)
			(end 0.925 0.47)
			(stroke
				(width 0.05)
				(type default)
			)
			(fill no)
			(layer "F.CrtYd")
		)
		(fp_rect
			(start -0.5 -0.25)
			(end 0.5 0.25)
			(stroke
				(width 0.15)
				(type solid)
			)
			(fill no)
			(layer "F.Fab")
		)
		(fp_text user "License: Apache-2.0"
			(at -0.95 5.169 180)
			(layer "F.Fab")
			(effects
				(font
					(size 0.7 0.7)
					(thickness 0.15)
				)
				(justify left bottom)
			)
		)
		(fp_text user "${REFERENCE}"
			(at -0.95 3.168 180)
			(layer "F.Fab")
			(effects
				(font
					(size 0.7 0.7)
					(thickness 0.15)
				)
				(justify left bottom)
			)
		)
		(fp_text user "Author: Antmicro"
			(at -0.95 4.169 180)
			(layer "F.Fab")
			(effects
				(font
					(size 0.7 0.7)
					(thickness 0.15)
				)
				(justify left bottom)
			)
		)
		(pad "1" smd roundrect
			(at -0.48 0 180)
			(size 0.59 0.64)
			(layers "F.Cu" "F.Mask" "F.Paste")
			(roundrect_rratio 0.25)
			(net 342 "/X710 DCDC converters/DVDD_FB")
			(pintype "passive")
		)
		(pad "2" smd roundrect
			(at 0.48 0 180)
			(size 0.59 0.64)
			(layers "F.Cu" "F.Mask" "F.Paste")
			(roundrect_rratio 0.25)
			(net 341 "/X710 DCDC converters/+DVDD_OUT")
			(pintype "passive")
		)
	)
	(footprint "antmicro-footprints:Fiducial_1mm_Mask2mm"
		(layer "F.Cu")
		(at 125 47.5)
		(descr "Circular Fiducial, 1mm bare copper, 3mm soldermask opening")
		(tags "fiducial")
		(property "Reference" "FD1"
			(at -2.8 -1.1 0)
			(layer "F.SilkS")
			(effects
				(font
					(size 0.7 0.7)
					(thickness 0.15)
				)
				(justify left bottom)
			)
		)
		(property "Value" "Fiducial_1mm_Mask2mm"
			(at 0 2.2 0)
			(layer "F.Fab")
			(effects
				(font
					(size 0.7 0.7)
					(thickness 0.15)
				)
				(justify left bottom)
			)
		)
		(property "Description" "Fiducial mask"
			(at 0 0 0)
			(layer "F.Fab")
			(hide yes)
			(effects
				(font
					(size 1.27 1.27)
					(thickness 0.15)
				)
			)
		)
		(property "Author" "Antmicro"
			(at 0 0 0)
			(unlocked yes)
			(layer "F.Fab")
			(hide yes)
			(effects
				(font
					(size 1 1)
					(thickness 0.15)
				)
			)
		)
		(property "License" "Apache-2.0"
			(at 0 0 0)
			(unlocked yes)
			(layer "F.Fab")
			(hide yes)
			(effects
				(font
					(size 1 1)
					(thickness 0.15)
				)
			)
		)
		(sheetname "/")
		(sheetfile "thunderbolt-to-10gbe-adapter.kicad_sch")
		(attr exclude_from_pos_files exclude_from_bom)
		(fp_circle
			(center 0 0)
			(end 1.24 0)
			(stroke
				(width 0.05)
				(type solid)
			)
			(fill no)
			(layer "F.CrtYd")
		)
		(fp_circle
			(center 0 0)
			(end 0.999 0)
			(stroke
				(width 0.15)
				(type solid)
			)
			(fill no)
			(layer "F.Fab")
		)
		(fp_text user "Author: Antmicro"
			(at -1.25 5.803 0)
			(layer "F.Fab")
			(effects
				(font
					(size 0.7 0.7)
					(thickness 0.15)
				)
				(justify left bottom)
			)
		)
		(fp_text user "${REFERENCE}"
			(at -1.25 4.603 0)
			(layer "F.Fab")
			(effects
				(font
					(size 0.7 0.7)
					(thickness 0.15)
				)
				(justify left bottom)
			)
		)
		(fp_text user "License: Apache-2.0"
			(at -1.25 7.003 0)
			(layer "F.Fab")
			(effects
				(font
					(size 0.7 0.7)
					(thickness 0.15)
				)
				(justify left bottom)
			)
		)
		(pad "" smd circle
			(at 0 0)
			(size 1 1)
			(layers "F.Cu" "F.Mask")
			(solder_mask_margin 0.5)
			(clearance 0.5)
		)
	)
	(footprint "antmicro-footprints:R_0402_1005Metric"
		(layer "F.Cu")
		(at 129.52 94.2 180)
		(descr "Resistor SMD 0402")
		(tags "resistor SMD 0402")
		(property "Reference" "R99"
			(at -38.914999 9.199999 180)
			(layer "F.SilkS")
			(effects
				(font
					(size 0.7 0.7)
					(thickness 0.15)
				)
			)
		)
		(property "Value" "R_20k_0402"
			(at -1.011843 1.772047 180)
			(layer "F.Fab")
			(effects
				(font
					(size 0.7 0.7)
					(thickness 0.15)
				)
				(justify left bottom)
			)
		)
		(property "Datasheet" "https://www.bourns.com/docs/product-datasheets/cr.pdf"
			(at 0 0 180)
			(layer "F.Fab")
			(hide yes)
			(effects
				(font
					(size 1.27 1.27)
					(thickness 0.15)
				)
			)
		)
		(property "Description" "SMD Chip Resistor, 20 kohm, ± 1%, 62.5 mW, 0402 [1005 Metric], Thick Film, General Purpose"
			(at 0 0 180)
			(layer "F.Fab")
			(hide yes)
			(effects
				(font
					(size 1.27 1.27)
					(thickness 0.15)
				)
			)
		)
		(property "MPN" "CR0402-FX-2002GLF"
			(at 0 0 180)
			(unlocked yes)
			(layer "F.Fab")
			(hide yes)
			(effects
				(font
					(size 1 1)
					(thickness 0.15)
				)
			)
		)
		(property "Manufacturer" "Bourns"
			(at 0 0 180)
			(unlocked yes)
			(layer "F.Fab")
			(hide yes)
			(effects
				(font
					(size 1 1)
					(thickness 0.15)
				)
			)
		)
		(property "License" "Apache-2.0"
			(at 0 0 180)
			(unlocked yes)
			(layer "F.Fab")
			(hide yes)
			(effects
				(font
					(size 1 1)
					(thickness 0.15)
				)
			)
		)
		(property "Author" "Antmicro"
			(at 0 0 180)
			(unlocked yes)
			(layer "F.Fab")
			(hide yes)
			(effects
				(font
					(size 1 1)
					(thickness 0.15)
				)
			)
		)
		(property "Val" "20k"
			(at 0 0 180)
			(unlocked yes)
			(layer "F.Fab")
			(hide yes)
			(effects
				(font
					(size 1 1)
					(thickness 0.15)
				)
			)
		)
		(property "Tolerance" "1%"
			(at 0 0 180)
			(unlocked yes)
			(layer "F.Fab")
			(hide yes)
			(effects
				(font
					(size 1 1)
					(thickness 0.15)
				)
			)
		)
		(sheetname "/X710 DCDC converters/")
		(sheetfile "DCDC_converters_X710.kicad_sch")
		(attr smd)
		(fp_rect
			(start -0.925 -0.47)
			(end 0.925 0.47)
			(stroke
				(width 0.05)
				(type default)
			)
			(fill no)
			(layer "F.CrtYd")
		)
		(fp_rect
			(start -0.5 -0.25)
			(end 0.5 0.25)
			(stroke
				(width 0.15)
				(type solid)
			)
			(fill no)
			(layer "F.Fab")
		)
		(fp_text user "License: Apache-2.0"
			(at -0.95 5.169 180)
			(layer "F.Fab")
			(effects
				(font
					(size 0.7 0.7)
					(thickness 0.15)
				)
				(justify left bottom)
			)
		)
		(fp_text user "${REFERENCE}"
			(at -0.95 3.168 180)
			(layer "F.Fab")
			(effects
				(font
					(size 0.7 0.7)
					(thickness 0.15)
				)
				(justify left bottom)
			)
		)
		(fp_text user "Author: Antmicro"
			(at -0.95 4.169 180)
			(layer "F.Fab")
			(effects
				(font
					(size 0.7 0.7)
					(thickness 0.15)
				)
				(justify left bottom)
			)
		)
		(pad "1" smd roundrect
			(at -0.48 0 180)
			(size 0.59 0.64)
			(layers "F.Cu" "F.Mask" "F.Paste")
			(roundrect_rratio 0.25)
			(net 23 "GND")
			(pintype "passive")
		)
		(pad "2" smd roundrect
			(at 0.48 0 180)
			(size 0.59 0.64)
			(layers "F.Cu" "F.Mask" "F.Paste")
			(roundrect_rratio 0.25)
			(net 333 "/X710 DCDC converters/3V3_FB")
			(pintype "passive")
		)
	)
	(footprint "antmicro-footprints:C_0402_1005Metric"
		(layer "F.Cu")
		(at 135.85 131.1 90)
		(descr "Capacitor SMD 0402")
		(tags "capacitor SMD 0402")
		(property "Reference" "C96"
			(at -0.170996 7.15 90)
			(layer "F.SilkS")
			(effects
				(font
					(size 0.7 0.7)
					(thickness 0.15)
				)
				(justify left bottom)
			)
		)
		(property "Value" "C_100n_0402"
			(at -1.022927 2.155213 90)
			(layer "F.Fab")
			(effects
				(font
					(size 0.7 0.7)
					(thickness 0.15)
				)
				(justify left bottom)
			)
		)
		(property "Datasheet" "https://www.murata.com/products/productdetail?partno=GRM155R61H104KE14%23"
			(at 0 0 90)
			(layer "F.Fab")
			(hide yes)
			(effects
				(font
					(size 1.27 1.27)
					(thickness 0.15)
				)
			)
		)
		(property "Description" "SMD Multilayer Ceramic Capacitor, 0.1 µF, 50 V, 0402 [1005 Metric], ± 10%, X5R, GRM Series"
			(at 0 0 90)
			(layer "F.Fab")
			(hide yes)
			(effects
				(font
					(size 1.27 1.27)
					(thickness 0.15)
				)
			)
		)
		(property "MPN" "GRM155R61H104KE14D"
			(at 0 0 90)
			(unlocked yes)
			(layer "F.Fab")
			(hide yes)
			(effects
				(font
					(size 1 1)
					(thickness 0.15)
				)
			)
		)
		(property "Manufacturer" "Murata"
			(at 0 0 90)
			(unlocked yes)
			(layer "F.Fab")
			(hide yes)
			(effects
				(font
					(size 1 1)
					(thickness 0.15)
				)
			)
		)
		(property "License" "Apache-2.0"
			(at 0 0 90)
			(unlocked yes)
			(layer "F.Fab")
			(hide yes)
			(effects
				(font
					(size 1 1)
					(thickness 0.15)
				)
			)
		)
		(property "Val" "100n"
			(at 0 0 90)
			(unlocked yes)
			(layer "F.Fab")
			(hide yes)
			(effects
				(font
					(size 1 1)
					(thickness 0.15)
				)
			)
		)
		(property "Voltage" "50V"
			(at 0 0 90)
			(unlocked yes)
			(layer "F.Fab")
			(hide yes)
			(effects
				(font
					(size 1 1)
					(thickness 0.15)
				)
			)
		)
		(property "Dielectric" "X5R"
			(at 0 0 90)
			(unlocked yes)
			(layer "F.Fab")
			(hide yes)
			(effects
				(font
					(size 1 1)
					(thickness 0.15)
				)
			)
		)
		(property "Author" "Antmicro"
			(at 0 0 90)
			(unlocked yes)
			(layer "F.Fab")
			(hide yes)
			(effects
				(font
					(size 1 1)
					(thickness 0.15)
				)
			)
		)
		(sheetname "/TB Controller - Power/")
		(sheetfile "tb-power.kicad_sch")
		(attr smd)
		(fp_rect
			(start -0.925 -0.47)
			(end 0.925 0.47)
			(stroke
				(width 0.05)
				(type default)
			)
			(fill no)
			(layer "F.CrtYd")
		)
		(fp_line
			(start 0.504 -0.25)
			(end 0.504 0.248)
			(stroke
				(width 0.15)
				(type solid)
			)
			(layer "F.Fab")
		)
		(fp_line
			(start -0.494 -0.25)
			(end 0.504 -0.25)
			(stroke
				(width 0.15)
				(type solid)
			)
			(layer "F.Fab")
		)
		(fp_line
			(start 0.504 0.248)
			(end -0.494 0.248)
			(stroke
				(width 0.15)
				(type solid)
			)
			(layer "F.Fab")
		)
		(fp_line
			(start -0.494 0.248)
			(end -0.494 -0.25)
			(stroke
				(width 0.15)
				(type solid)
			)
			(layer "F.Fab")
		)
		(fp_text user "Author: Antmicro"
			(at -0.939 3.399 90)
			(layer "F.Fab")
			(effects
				(font
					(size 0.7 0.7)
					(thickness 0.15)
				)
				(justify left bottom)
			)
		)
		(fp_text user "License: Apache-2.0"
			(at -0.939 5.799 90)
			(layer "F.Fab")
			(effects
				(font
					(size 0.7 0.7)
					(thickness 0.15)
				)
				(justify left bottom)
			)
		)
		(fp_text user "${REFERENCE}"
			(at -0.939 4.599 90)
			(layer "F.Fab")
			(effects
				(font
					(size 0.7 0.7)
					(thickness 0.15)
				)
				(justify left bottom)
			)
		)
		(pad "1" smd roundrect
			(at -0.48 0 90)
			(size 0.59 0.64)
			(layers "F.Cu" "F.Mask" "F.Paste")
			(roundrect_rratio 0.25)
			(net 23 "GND")
			(pintype "passive")
		)
		(pad "2" smd roundrect
			(at 0.48 0 90)
			(size 0.59 0.64)
			(layers "F.Cu" "F.Mask" "F.Paste")
			(roundrect_rratio 0.25)
			(net 57 "+3V3_TB")
			(pintype "passive")
		)
	)
	(footprint "antmicro-footprints:R_0402_1005Metric"
		(layer "F.Cu")
		(at 159.25 108.15 180)
		(descr "Resistor SMD 0402")
		(tags "resistor SMD 0402")
		(property "Reference" "R90"
			(at -12.950004 -17.25 180)
			(layer "F.SilkS")
			(effects
				(font
					(size 0.7 0.7)
					(thickness 0.15)
				)
			)
		)
		(property "Value" "R_100k_0402"
			(at -1.011843 1.772047 180)
			(layer "F.Fab")
			(effects
				(font
					(size 0.7 0.7)
					(thickness 0.15)
				)
				(justify left bottom)
			)
		)
		(property "Datasheet" "https://www.bourns.com/docs/product-datasheets/cr.pdf"
			(at 0 0 180)
			(layer "F.Fab")
			(hide yes)
			(effects
				(font
					(size 1.27 1.27)
					(thickness 0.15)
				)
			)
		)
		(property "Description" "SMD Chip Resistor, 100 kohm, ± 1%, 62.5 mW, 0402 [1005 Metric], Thick Film, General Purpose"
			(at 0 0 180)
			(layer "F.Fab")
			(hide yes)
			(effects
				(font
					(size 1.27 1.27)
					(thickness 0.15)
				)
			)
		)
		(property "MPN" "CR0402-FX-1003GLF"
			(at 0 0 180)
			(unlocked yes)
			(layer "F.Fab")
			(hide yes)
			(effects
				(font
					(size 1 1)
					(thickness 0.15)
				)
			)
		)
		(property "Manufacturer" "Bourns"
			(at 0 0 180)
			(unlocked yes)
			(layer "F.Fab")
			(hide yes)
			(effects
				(font
					(size 1 1)
					(thickness 0.15)
				)
			)
		)
		(property "License" "Apache-2.0"
			(at 0 0 180)
			(unlocked yes)
			(layer "F.Fab")
			(hide yes)
			(effects
				(font
					(size 1 1)
					(thickness 0.15)
				)
			)
		)
		(property "Author" "Antmicro"
			(at 0 0 180)
			(unlocked yes)
			(layer "F.Fab")
			(hide yes)
			(effects
				(font
					(size 1 1)
					(thickness 0.15)
				)
			)
		)
		(property "Val" "100k"
			(at 0 0 180)
			(unlocked yes)
			(layer "F.Fab")
			(hide yes)
			(effects
				(font
					(size 1 1)
					(thickness 0.15)
				)
			)
		)
		(property "Tolerance" "1%"
			(at 0 0 180)
			(unlocked yes)
			(layer "F.Fab")
			(hide yes)
			(effects
				(font
					(size 1 1)
					(thickness 0.15)
				)
			)
		)
		(sheetname "/X710 DCDC converters/")
		(sheetfile "DCDC_converters_X710.kicad_sch")
		(attr smd)
		(fp_rect
			(start -0.925 -0.47)
			(end 0.925 0.47)
			(stroke
				(width 0.05)
				(type default)
			)
			(fill no)
			(layer "F.CrtYd")
		)
		(fp_rect
			(start -0.5 -0.25)
			(end 0.5 0.25)
			(stroke
				(width 0.15)
				(type solid)
			)
			(fill no)
			(layer "F.Fab")
		)
		(fp_text user "${REFERENCE}"
			(at -0.95 3.168 180)
			(layer "F.Fab")
			(effects
				(font
					(size 0.7 0.7)
					(thickness 0.15)
				)
				(justify left bottom)
			)
		)
		(fp_text user "License: Apache-2.0"
			(at -0.95 5.169 180)
			(layer "F.Fab")
			(effects
				(font
					(size 0.7 0.7)
					(thickness 0.15)
				)
				(justify left bottom)
			)
		)
		(fp_text user "Author: Antmicro"
			(at -0.95 4.169 180)
			(layer "F.Fab")
			(effects
				(font
					(size 0.7 0.7)
					(thickness 0.15)
				)
				(justify left bottom)
			)
		)
		(pad "1" smd roundrect
			(at -0.48 0 180)
			(size 0.59 0.64)
			(layers "F.Cu" "F.Mask" "F.Paste")
			(roundrect_rratio 0.25)
			(net 381 "/X710 DCDC converters/1V0_PG")
			(pintype "passive")
		)
		(pad "2" smd roundrect
			(at 0.48 0 180)
			(size 0.59 0.64)
			(layers "F.Cu" "F.Mask" "F.Paste")
			(roundrect_rratio 0.25)
			(net 109 "/X710 DCDC converters/1V0_VCC")
			(pintype "passive")
		)
	)
	(footprint "antmicro-footprints:L_Bourns-SRP4021HMT"
		(layer "F.Cu")
		(at 147.149999 106.000001 -90)
		(property "Reference" "L8"
			(at 17.549996 -14.850002 270)
			(layer "F.SilkS")
			(effects
				(font
					(size 0.7 0.7)
					(thickness 0.15)
				)
			)
		)
		(property "Value" "L_1u_10A_Bourns-SRP4021HMT"
			(at -2.85 3.4 270)
			(layer "F.Fab")
			(effects
				(font
					(size 0.7 0.7)
					(thickness 0.15)
				)
				(justify left bottom)
			)
		)
		(property "Datasheet" "https://www.mouser.com/datasheet/2/54/Bourns_04_01_2025_SRP4021HMT_Datasheet-3580094.pdf"
			(at 0 0 270)
			(layer "F.Fab")
			(effects
				(font
					(size 0.7 0.7)
					(thickness 0.15)
				)
				(justify left bottom)
			)
		)
		(property "Description" "Power Inductors - SMD Ind,4.1x4.2x1.9mm,1uH+/-20%,10A, Shielded"
			(at 0 0 270)
			(layer "F.Fab")
			(effects
				(font
					(size 0.7 0.7)
					(thickness 0.15)
				)
				(justify left bottom)
			)
		)
		(property "Val" "1u/10A"
			(at 0 0 270)
			(unlocked yes)
			(layer "F.Fab")
			(hide yes)
			(effects
				(font
					(size 1 1)
					(thickness 0.15)
				)
			)
		)
		(property "Manufacturer" "Bourns"
			(at 0 0 270)
			(unlocked yes)
			(layer "F.Fab")
			(hide yes)
			(effects
				(font
					(size 1 1)
					(thickness 0.15)
				)
			)
		)
		(property "MPN" "SRP4021HMT-1R0M"
			(at 0 0 270)
			(unlocked yes)
			(layer "F.Fab")
			(hide yes)
			(effects
				(font
					(size 1 1)
					(thickness 0.15)
				)
			)
		)
		(property "ISat" ""
			(at 0 0 270)
			(unlocked yes)
			(layer "F.Fab")
			(hide yes)
			(effects
				(font
					(size 1 1)
					(thickness 0.15)
				)
			)
		)
		(property "Isat" "8A"
			(at 0 0 270)
			(unlocked yes)
			(layer "F.Fab")
			(hide yes)
			(effects
				(font
					(size 1 1)
					(thickness 0.15)
				)
			)
		)
		(property "IMax" ""
			(at 0 0 270)
			(unlocked yes)
			(layer "F.Fab")
			(hide yes)
			(effects
				(font
					(size 1 1)
					(thickness 0.15)
				)
			)
		)
		(property "Imax" "10A"
			(at 0 0 270)
			(unlocked yes)
			(layer "F.Fab")
			(hide yes)
			(effects
				(font
					(size 1 1)
					(thickness 0.15)
				)
			)
		)
		(property "Size" "4.2x4.1"
			(at 0 0 270)
			(unlocked yes)
			(layer "F.Fab")
			(hide yes)
			(effects
				(font
					(size 1 1)
					(thickness 0.15)
				)
			)
		)
		(property "Author" "Antmicro"
			(at 0 0 270)
			(unlocked yes)
			(layer "F.Fab")
			(hide yes)
			(effects
				(font
					(size 1 1)
					(thickness 0.15)
				)
			)
		)
		(property "License" "Apache-2.0"
			(at 0 0 270)
			(unlocked yes)
			(layer "F.Fab")
			(hide yes)
			(effects
				(font
					(size 1 1)
					(thickness 0.15)
				)
			)
		)
		(sheetname "/X710 DCDC converters/")
		(sheetfile "DCDC_converters_X710.kicad_sch")
		(attr smd)
		(fp_line
			(start -0.8 2.05)
			(end 0.8 2.05)
			(stroke
				(width 0.15)
				(type solid)
			)
			(layer "F.SilkS")
		)
		(fp_line
			(start -0.8 -2.05)
			(end 0.8 -2.05)
			(stroke
				(width 0.15)
				(type solid)
			)
			(layer "F.SilkS")
		)
		(fp_rect
			(start -2.85 -2.3)
			(end 2.85 2.3)
			(stroke
				(width 0.05)
				(type solid)
			)
			(fill no)
			(layer "F.CrtYd")
		)
		(fp_rect
			(start -2 -2.05)
			(end 2 2.05)
			(stroke
				(width 0.15)
				(type solid)
			)
			(fill no)
			(layer "F.Fab")
		)
		(fp_text user "License: Apache-2.0"
			(at -2.85 7 270)
			(layer "F.Fab")
			(effects
				(font
					(size 0.7 0.7)
					(thickness 0.15)
				)
				(justify left bottom)
			)
		)
		(fp_text user "${REFERENCE}"
			(at -2.85 5.8 270)
			(layer "F.Fab")
			(effects
				(font
					(size 0.7 0.7)
					(thickness 0.15)
				)
				(justify left bottom)
			)
		)
		(fp_text user "Author: Antmicro"
			(at -2.85 4.6 270)
			(layer "F.Fab")
			(effects
				(font
					(size 0.7 0.7)
					(thickness 0.15)
				)
				(justify left bottom)
			)
		)
		(pad "1" smd rect
			(at 1.85 0 90)
			(size 1.5 3.5)
			(layers "F.Cu" "F.Mask" "F.Paste")
			(net 313 "/X710 DCDC converters/DVDD_SW")
			(pintype "passive")
		)
		(pad "2" smd rect
			(at -1.85 0 90)
			(size 1.5 3.5)
			(layers "F.Cu" "F.Mask" "F.Paste")
			(net 341 "/X710 DCDC converters/+DVDD_OUT")
			(pintype "passive")
		)
	)
	(footprint "antmicro-footprints:R_0402_1005Metric"
		(layer "F.Cu")
		(at 158.104998 67.124999 -90)
		(descr "Resistor SMD 0402")
		(tags "resistor SMD 0402")
		(property "Reference" "R191"
			(at -12.324999 -20.295 270)
			(layer "F.SilkS")
			(effects
				(font
					(size 0.7 0.7)
					(thickness 0.15)
				)
			)
		)
		(property "Value" "R_150R_0402"
			(at -1.011843 1.772047 270)
			(layer "F.Fab")
			(effects
				(font
					(size 0.7 0.7)
					(thickness 0.15)
				)
				(justify left bottom)
			)
		)
		(property "Datasheet" "https://www.bourns.com/docs/product-datasheets/cr.pdf"
			(at 0 0 270)
			(layer "F.Fab")
			(hide yes)
			(effects
				(font
					(size 1.27 1.27)
					(thickness 0.15)
				)
			)
		)
		(property "Description" "SMD Chip Resistor, 150 ohm, ± 1%, 62.5 mW, 0402 [1005 Metric], Thick Film, General Purpose"
			(at 0 0 270)
			(layer "F.Fab")
			(hide yes)
			(effects
				(font
					(size 1.27 1.27)
					(thickness 0.15)
				)
			)
		)
		(property "MPN" "CR0402-FX-1500GLF"
			(at 0 0 270)
			(unlocked yes)
			(layer "F.Fab")
			(hide yes)
			(effects
				(font
					(size 1 1)
					(thickness 0.15)
				)
			)
		)
		(property "Manufacturer" "Bourns"
			(at 0 0 270)
			(unlocked yes)
			(layer "F.Fab")
			(hide yes)
			(effects
				(font
					(size 1 1)
					(thickness 0.15)
				)
			)
		)
		(property "License" "Apache-2.0"
			(at 0 0 270)
			(unlocked yes)
			(layer "F.Fab")
			(hide yes)
			(effects
				(font
					(size 1 1)
					(thickness 0.15)
				)
			)
		)
		(property "Author" "Antmicro"
			(at 0 0 270)
			(unlocked yes)
			(layer "F.Fab")
			(hide yes)
			(effects
				(font
					(size 1 1)
					(thickness 0.15)
				)
			)
		)
		(property "Val" "150R"
			(at 0 0 270)
			(unlocked yes)
			(layer "F.Fab")
			(hide yes)
			(effects
				(font
					(size 1 1)
					(thickness 0.15)
				)
			)
		)
		(property "Tolerance" "1%"
			(at 0 0 270)
			(unlocked yes)
			(layer "F.Fab")
			(hide yes)
			(effects
				(font
					(size 1 1)
					(thickness 0.15)
				)
			)
		)
		(sheetname "/X710-AT2 10GbE/")
		(sheetfile "x710-at2-10gbe.kicad_sch")
		(attr smd)
		(fp_rect
			(start -0.925 -0.47)
			(end 0.925 0.47)
			(stroke
				(width 0.05)
				(type default)
			)
			(fill no)
			(layer "F.CrtYd")
		)
		(fp_rect
			(start -0.5 -0.25)
			(end 0.5 0.25)
			(stroke
				(width 0.15)
				(type solid)
			)
			(fill no)
			(layer "F.Fab")
		)
		(fp_text user "Author: Antmicro"
			(at -0.95 4.169 270)
			(layer "F.Fab")
			(effects
				(font
					(size 0.7 0.7)
					(thickness 0.15)
				)
				(justify left bottom)
			)
		)
		(fp_text user "License: Apache-2.0"
			(at -0.95 5.169 270)
			(layer "F.Fab")
			(effects
				(font
					(size 0.7 0.7)
					(thickness 0.15)
				)
				(justify left bottom)
			)
		)
		(fp_text user "${REFERENCE}"
			(at -0.95 3.168 270)
			(layer "F.Fab")
			(effects
				(font
					(size 0.7 0.7)
					(thickness 0.15)
				)
				(justify left bottom)
			)
		)
		(pad "1" smd roundrect
			(at -0.48 0 270)
			(size 0.59 0.64)
			(layers "F.Cu" "F.Mask" "F.Paste")
			(roundrect_rratio 0.25)
			(net 23 "GND")
			(pintype "passive")
		)
		(pad "2" smd roundrect
			(at 0.48 0 270)
			(size 0.59 0.64)
			(layers "F.Cu" "F.Mask" "F.Paste")
			(roundrect_rratio 0.25)
			(net 25 "/X710-AT2 10GbE/25MHZ_OSC_AC.+")
			(pintype "passive")
		)
	)
	(footprint "antmicro-footprints:C_0603_1608Metric_EIA"
		(layer "F.Cu")
		(at 143.054999 99.774999 -90)
		(descr "Capacitor SMD 0603, IPC-7351 Density Level A")
		(tags "Capacitor 0603")
		(property "Reference" "C166"
			(at -9.249998 -35.195001 270)
			(layer "F.SilkS")
			(effects
				(font
					(size 0.7 0.7)
					(thickness 0.15)
				)
			)
		)
		(property "Value" "C_22u_16V_0603"
			(at -1.42757 1.770288 270)
			(layer "F.Fab")
			(effects
				(font
					(size 0.7 0.7)
					(thickness 0.15)
				)
				(justify left bottom)
			)
		)
		(property "Datasheet" "https://product.samsungsem.com/mlcc/CL10A226MO7JZN.do"
			(at 0 0 270)
			(layer "F.Fab")
			(hide yes)
			(effects
				(font
					(size 1.27 1.27)
					(thickness 0.15)
				)
			)
		)
		(property "Description" "SMD Multilayer Ceramic Capacitor"
			(at 0 0 270)
			(layer "F.Fab")
			(hide yes)
			(effects
				(font
					(size 1.27 1.27)
					(thickness 0.15)
				)
			)
		)
		(property "MPN" "CL10A226MO7JZNC"
			(at 0 0 270)
			(unlocked yes)
			(layer "F.Fab")
			(hide yes)
			(effects
				(font
					(size 1 1)
					(thickness 0.15)
				)
			)
		)
		(property "Manufacturer" "Samsung Electro-Mechanics"
			(at 0 0 270)
			(unlocked yes)
			(layer "F.Fab")
			(hide yes)
			(effects
				(font
					(size 1 1)
					(thickness 0.15)
				)
			)
		)
		(property "License" "Apache-2.0"
			(at 0 0 270)
			(unlocked yes)
			(layer "F.Fab")
			(hide yes)
			(effects
				(font
					(size 1 1)
					(thickness 0.15)
				)
			)
		)
		(property "Author" "Antmicro"
			(at 0 0 270)
			(unlocked yes)
			(layer "F.Fab")
			(hide yes)
			(effects
				(font
					(size 1 1)
					(thickness 0.15)
				)
			)
		)
		(property "Val" "22u"
			(at 0 0 270)
			(unlocked yes)
			(layer "F.Fab")
			(hide yes)
			(effects
				(font
					(size 1 1)
					(thickness 0.15)
				)
			)
		)
		(property "Voltage" "16V"
			(at 0 0 270)
			(unlocked yes)
			(layer "F.Fab")
			(hide yes)
			(effects
				(font
					(size 1 1)
					(thickness 0.15)
				)
			)
		)
		(property "Dielectric" ""
			(at 0 0 270)
			(unlocked yes)
			(layer "F.Fab")
			(hide yes)
			(effects
				(font
					(size 1 1)
					(thickness 0.15)
				)
			)
		)
		(sheetname "/X710-AT2 power/")
		(sheetfile "x710-at2-power.kicad_sch")
		(attr smd)
		(fp_line
			(start -0.15 0.55)
			(end 0.15 0.55)
			(stroke
				(width 0.15)
				(type solid)
			)
			(layer "F.SilkS")
		)
		(fp_line
			(start -0.15 -0.55)
			(end 0.15 -0.55)
			(stroke
				(width 0.15)
				(type solid)
			)
			(layer "F.SilkS")
		)
		(fp_rect
			(start -1.25 -0.65)
			(end 1.25 0.65)
			(stroke
				(width 0.05)
				(type solid)
			)
			(fill no)
			(layer "F.CrtYd")
		)
		(fp_rect
			(start -0.8 -0.45)
			(end 0.8 0.45)
			(stroke
				(width 0.15)
				(type solid)
			)
			(fill no)
			(layer "F.Fab")
		)
		(fp_text user "License: Apache-2.0"
			(at -1.682 5.895 270)
			(layer "F.Fab")
			(effects
				(font
					(size 0.7 0.7)
					(thickness 0.15)
				)
				(justify left bottom)
			)
		)
		(fp_text user "${REFERENCE}"
			(at -1.682 3.895 270)
			(layer "F.Fab")
			(effects
				(font
					(size 0.7 0.7)
					(thickness 0.15)
				)
				(justify left bottom)
			)
		)
		(fp_text user "Author: Antmicro"
			(at -1.682 4.894 270)
			(layer "F.Fab")
			(effects
				(font
					(size 0.7 0.7)
					(thickness 0.15)
				)
				(justify left bottom)
			)
		)
		(pad "1" smd roundrect
			(at -0.7 0 270)
			(size 0.8 1.1)
			(layers "F.Cu" "F.Mask" "F.Paste")
			(roundrect_rratio 0.2)
			(net 23 "GND")
			(pintype "passive")
		)
		(pad "2" smd roundrect
			(at 0.7 0 270)
			(size 0.8 1.1)
			(layers "F.Cu" "F.Mask" "F.Paste")
			(roundrect_rratio 0.2)
			(net 6 "DVDD")
			(pintype "passive")
		)
	)
	(footprint "antmicro-footprints:R_0603_1608Metric"
		(layer "F.Cu")
		(at 116.65 111.25 90)
		(descr "Resistor SMD 0603")
		(tags "resistor SMD 0603")
		(property "Reference" "R3"
			(at 0 -1.05 90)
			(layer "F.SilkS")
			(effects
				(font
					(size 0.7 0.7)
					(thickness 0.15)
				)
			)
		)
		(property "Value" "R_0R_22.4A_0603"
			(at 0 1.6 90)
			(layer "F.Fab")
			(effects
				(font
					(size 0.7 0.7)
					(thickness 0.15)
				)
				(justify left bottom)
			)
		)
		(property "Datasheet" "https://fscdn.rohm.com/en/products/databook/datasheet/passive/resistor/chip_resistor/pmr-jpw-e.pdf"
			(at 0 0 90)
			(layer "F.Fab")
			(hide yes)
			(effects
				(font
					(size 1.27 1.27)
					(thickness 0.15)
				)
			)
		)
		(property "Description" "SMD Chip Resistor"
			(at 0 0 90)
			(layer "F.Fab")
			(hide yes)
			(effects
				(font
					(size 1.27 1.27)
					(thickness 0.15)
				)
			)
		)
		(property "MPN" "PMR03EZPJ000"
			(at 0 0 90)
			(unlocked yes)
			(layer "F.Fab")
			(hide yes)
			(effects
				(font
					(size 1 1)
					(thickness 0.15)
				)
			)
		)
		(property "Manufacturer" "ROHM Semiconductor"
			(at 0 0 90)
			(unlocked yes)
			(layer "F.Fab")
			(hide yes)
			(effects
				(font
					(size 1 1)
					(thickness 0.15)
				)
			)
		)
		(property "Val" "0R"
			(at 0 0 90)
			(unlocked yes)
			(layer "F.Fab")
			(hide yes)
			(effects
				(font
					(size 1 1)
					(thickness 0.15)
				)
			)
		)
		(property "Max. Curr." "22.4A"
			(at 0 0 90)
			(unlocked yes)
			(layer "F.Fab")
			(hide yes)
			(effects
				(font
					(size 1 1)
					(thickness 0.15)
				)
			)
		)
		(property "Author" "Antmicro"
			(at 0 0 90)
			(unlocked yes)
			(layer "F.Fab")
			(hide yes)
			(effects
				(font
					(size 1 1)
					(thickness 0.15)
				)
			)
		)
		(property "License" "Apache-2.0"
			(at 0 0 90)
			(unlocked yes)
			(layer "F.Fab")
			(hide yes)
			(effects
				(font
					(size 1 1)
					(thickness 0.15)
				)
			)
		)
		(property "Tolerance" "template_tolerance"
			(at 0 0 90)
			(unlocked yes)
			(layer "F.Fab")
			(hide yes)
			(effects
				(font
					(size 1 1)
					(thickness 0.15)
				)
			)
		)
		(sheetname "/PD and TB DC-DC/")
		(sheetfile "PD_and_TB_DC_DC.kicad_sch")
		(attr smd)
		(fp_line
			(start -0.15 -0.4)
			(end 0.15 -0.4)
			(stroke
				(width 0.15)
				(type solid)
			)
			(layer "F.SilkS")
		)
		(fp_line
			(start -0.15 0.4)
			(end 0.15 0.4)
			(stroke
				(width 0.15)
				(type solid)
			)
			(layer "F.SilkS")
		)
		(fp_rect
			(start -1.25 -0.65)
			(end 1.25 0.65)
			(stroke
				(width 0.05)
				(type solid)
			)
			(fill no)
			(layer "F.CrtYd")
		)
		(fp_rect
			(start -0.8 -0.4)
			(end 0.8 0.4)
			(stroke
				(width 0.15)
				(type solid)
			)
			(fill no)
			(layer "F.Fab")
		)
		(fp_text user "${REFERENCE}"
			(at -1.25 3.898 90)
			(layer "F.Fab")
			(effects
				(font
					(size 0.7 0.7)
					(thickness 0.15)
				)
				(justify left bottom)
			)
		)
		(fp_text user "License: Apache-2.0"
			(at -1.25 5.9 90)
			(layer "F.Fab")
			(effects
				(font
					(size 0.7 0.7)
					(thickness 0.15)
				)
				(justify left bottom)
			)
		)
		(fp_text user "Author: Antmicro"
			(at -1.25 4.9 90)
			(layer "F.Fab")
			(effects
				(font
					(size 0.7 0.7)
					(thickness 0.15)
				)
				(justify left bottom)
			)
		)
		(pad "1" smd roundrect
			(at -0.7 0 90)
			(size 0.8 1)
			(layers "F.Cu" "F.Mask" "F.Paste")
			(roundrect_rratio 0.2)
			(net 53 "+5V_USB")
			(pintype "passive")
		)
		(pad "2" smd roundrect
			(at 0.7 0 90)
			(size 0.8 1)
			(layers "F.Cu" "F.Mask" "F.Paste")
			(roundrect_rratio 0.2)
			(net 161 "Net-(U2-VIN)")
			(pintype "passive")
		)
	)
	(footprint "antmicro-footprints:C_0402_1005Metric"
		(layer "F.Cu")
		(at 130.2 71.4 180)
		(descr "Capacitor SMD 0402")
		(tags "capacitor SMD 0402")
		(property "Reference" "C310"
			(at 1 2 180)
			(layer "F.SilkS")
			(effects
				(font
					(size 0.7 0.7)
					(thickness 0.15)
				)
				(justify left bottom)
			)
		)
		(property "Value" "C_100n_0402"
			(at -1.022927 2.155213 180)
			(layer "F.Fab")
			(effects
				(font
					(size 0.7 0.7)
					(thickness 0.15)
				)
				(justify left bottom)
			)
		)
		(property "Datasheet" "https://www.murata.com/products/productdetail?partno=GRM155R61H104KE14%23"
			(at 0 0 180)
			(layer "F.Fab")
			(hide yes)
			(effects
				(font
					(size 1.27 1.27)
					(thickness 0.15)
				)
			)
		)
		(property "Description" "SMD Multilayer Ceramic Capacitor, 0.1 µF, 50 V, 0402 [1005 Metric], ± 10%, X5R, GRM Series"
			(at 0 0 180)
			(layer "F.Fab")
			(hide yes)
			(effects
				(font
					(size 1.27 1.27)
					(thickness 0.15)
				)
			)
		)
		(property "MPN" "GRM155R61H104KE14D"
			(at 0 0 180)
			(unlocked yes)
			(layer "F.Fab")
			(hide yes)
			(effects
				(font
					(size 1 1)
					(thickness 0.15)
				)
			)
		)
		(property "Val" "100n"
			(at 0 0 180)
			(unlocked yes)
			(layer "F.Fab")
			(hide yes)
			(effects
				(font
					(size 1 1)
					(thickness 0.15)
				)
			)
		)
		(property "Voltage" "50V"
			(at 0 0 180)
			(unlocked yes)
			(layer "F.Fab")
			(hide yes)
			(effects
				(font
					(size 1 1)
					(thickness 0.15)
				)
			)
		)
		(property "Dielectric" "X5R"
			(at 0 0 180)
			(unlocked yes)
			(layer "F.Fab")
			(hide yes)
			(effects
				(font
					(size 1 1)
					(thickness 0.15)
				)
			)
		)
		(property "Manufacturer" "Murata"
			(at 0 0 180)
			(unlocked yes)
			(layer "F.Fab")
			(hide yes)
			(effects
				(font
					(size 1 1)
					(thickness 0.15)
				)
			)
		)
		(property "License" "Apache-2.0"
			(at 0 0 180)
			(unlocked yes)
			(layer "F.Fab")
			(hide yes)
			(effects
				(font
					(size 1 1)
					(thickness 0.15)
				)
			)
		)
		(property "Author" "Antmicro"
			(at 0 0 180)
			(unlocked yes)
			(layer "F.Fab")
			(hide yes)
			(effects
				(font
					(size 1 1)
					(thickness 0.15)
				)
			)
		)
		(sheetname "/X710 flash memory/")
		(sheetfile "flash_x710.kicad_sch")
		(attr smd)
		(fp_rect
			(start -0.925 -0.47)
			(end 0.925 0.47)
			(stroke
				(width 0.05)
				(type default)
			)
			(fill no)
			(layer "F.CrtYd")
		)
		(fp_line
			(start 0.504 0.248)
			(end -0.494 0.248)
			(stroke
				(width 0.15)
				(type solid)
			)
			(layer "F.Fab")
		)
		(fp_line
			(start 0.504 -0.25)
			(end 0.504 0.248)
			(stroke
				(width 0.15)
				(type solid)
			)
			(layer "F.Fab")
		)
		(fp_line
			(start -0.494 0.248)
			(end -0.494 -0.25)
			(stroke
				(width 0.15)
				(type solid)
			)
			(layer "F.Fab")
		)
		(fp_line
			(start -0.494 -0.25)
			(end 0.504 -0.25)
			(stroke
				(width 0.15)
				(type solid)
			)
			(layer "F.Fab")
		)
		(fp_text user "${REFERENCE}"
			(at -0.939 4.599 180)
			(layer "F.Fab")
			(effects
				(font
					(size 0.7 0.7)
					(thickness 0.15)
				)
				(justify left bottom)
			)
		)
		(fp_text user "License: Apache-2.0"
			(at -0.939 5.799 180)
			(layer "F.Fab")
			(effects
				(font
					(size 0.7 0.7)
					(thickness 0.15)
				)
				(justify left bottom)
			)
		)
		(fp_text user "Author: Antmicro"
			(at -0.939 3.399 180)
			(layer "F.Fab")
			(effects
				(font
					(size 0.7 0.7)
					(thickness 0.15)
				)
				(justify left bottom)
			)
		)
		(pad "1" smd roundrect
			(at -0.48 0 180)
			(size 0.59 0.64)
			(layers "F.Cu" "F.Mask" "F.Paste")
			(roundrect_rratio 0.25)
			(net 23 "GND")
			(pintype "passive")
		)
		(pad "2" smd roundrect
			(at 0.48 0 180)
			(size 0.59 0.64)
			(layers "F.Cu" "F.Mask" "F.Paste")
			(roundrect_rratio 0.25)
			(net 343 "/X710 flash memory/+3V3_FLASH")
			(pintype "passive")
		)
	)
	(footprint "antmicro-footprints:C_0603_1608Metric_EIA"
		(layer "F.Cu")
		(at 147.2 114.35)
		(descr "Capacitor SMD 0603, IPC-7351 Density Level A")
		(tags "Capacitor 0603")
		(property "Reference" "C113"
			(at 14.850002 16.550003 0)
			(layer "F.SilkS")
			(effects
				(font
					(size 0.7 0.7)
					(thickness 0.15)
				)
			)
		)
		(property "Value" "C_22u_16V_0603"
			(at -1.42757 1.770288 0)
			(layer "F.Fab")
			(effects
				(font
					(size 0.7 0.7)
					(thickness 0.15)
				)
				(justify left bottom)
			)
		)
		(property "Datasheet" "https://product.samsungsem.com/mlcc/CL10A226MO7JZN.do"
			(at 0 0 0)
			(layer "F.Fab")
			(hide yes)
			(effects
				(font
					(size 1.27 1.27)
					(thickness 0.15)
				)
			)
		)
		(property "Description" "SMD Multilayer Ceramic Capacitor"
			(at 0 0 0)
			(layer "F.Fab")
			(hide yes)
			(effects
				(font
					(size 1.27 1.27)
					(thickness 0.15)
				)
			)
		)
		(property "MPN" "CL10A226MO7JZNC"
			(at 0 0 0)
			(unlocked yes)
			(layer "F.Fab")
			(hide yes)
			(effects
				(font
					(size 1 1)
					(thickness 0.15)
				)
			)
		)
		(property "Manufacturer" "Samsung Electro-Mechanics"
			(at 0 0 0)
			(unlocked yes)
			(layer "F.Fab")
			(hide yes)
			(effects
				(font
					(size 1 1)
					(thickness 0.15)
				)
			)
		)
		(property "License" "Apache-2.0"
			(at 0 0 0)
			(unlocked yes)
			(layer "F.Fab")
			(hide yes)
			(effects
				(font
					(size 1 1)
					(thickness 0.15)
				)
			)
		)
		(property "Author" "Antmicro"
			(at 0 0 0)
			(unlocked yes)
			(layer "F.Fab")
			(hide yes)
			(effects
				(font
					(size 1 1)
					(thickness 0.15)
				)
			)
		)
		(property "Val" "22u"
			(at 0 0 0)
			(unlocked yes)
			(layer "F.Fab")
			(hide yes)
			(effects
				(font
					(size 1 1)
					(thickness 0.15)
				)
			)
		)
		(property "Voltage" "16V"
			(at 0 0 0)
			(unlocked yes)
			(layer "F.Fab")
			(hide yes)
			(effects
				(font
					(size 1 1)
					(thickness 0.15)
				)
			)
		)
		(property "Dielectric" ""
			(at 0 0 0)
			(unlocked yes)
			(layer "F.Fab")
			(hide yes)
			(effects
				(font
					(size 1 1)
					(thickness 0.15)
				)
			)
		)
		(sheetname "/X710 DCDC converters/")
		(sheetfile "DCDC_converters_X710.kicad_sch")
		(attr smd)
		(fp_line
			(start -0.15 -0.55)
			(end 0.15 -0.55)
			(stroke
				(width 0.15)
				(type solid)
			)
			(layer "F.SilkS")
		)
		(fp_line
			(start -0.15 0.55)
			(end 0.15 0.55)
			(stroke
				(width 0.15)
				(type solid)
			)
			(layer "F.SilkS")
		)
		(fp_rect
			(start -1.25 -0.65)
			(end 1.25 0.65)
			(stroke
				(width 0.05)
				(type solid)
			)
			(fill no)
			(layer "F.CrtYd")
		)
		(fp_rect
			(start -0.8 -0.45)
			(end 0.8 0.45)
			(stroke
				(width 0.15)
				(type solid)
			)
			(fill no)
			(layer "F.Fab")
		)
		(fp_text user "${REFERENCE}"
			(at -1.682 3.895 0)
			(layer "F.Fab")
			(effects
				(font
					(size 0.7 0.7)
					(thickness 0.15)
				)
				(justify left bottom)
			)
		)
		(fp_text user "Author: Antmicro"
			(at -1.682 4.894 0)
			(layer "F.Fab")
			(effects
				(font
					(size 0.7 0.7)
					(thickness 0.15)
				)
				(justify left bottom)
			)
		)
		(fp_text user "License: Apache-2.0"
			(at -1.682 5.895 0)
			(layer "F.Fab")
			(effects
				(font
					(size 0.7 0.7)
					(thickness 0.15)
				)
				(justify left bottom)
			)
		)
		(pad "1" smd roundrect
			(at -0.7 0)
			(size 0.8 1.1)
			(layers "F.Cu" "F.Mask" "F.Paste")
			(roundrect_rratio 0.2)
			(net 23 "GND")
			(pintype "passive")
		)
		(pad "2" smd roundrect
			(at 0.7 0)
			(size 0.8 1.1)
			(layers "F.Cu" "F.Mask" "F.Paste")
			(roundrect_rratio 0.2)
			(net 40 "+5V")
			(pintype "passive")
		)
	)
	(footprint "antmicro-footprints:C_0402_1005Metric"
		(layer "F.Cu")
		(at 138 73.25)
		(descr "Capacitor SMD 0402")
		(tags "capacitor SMD 0402")
		(property "Reference" "C266"
			(at -3.8 0.45 0)
			(layer "F.SilkS")
			(effects
				(font
					(size 0.7 0.7)
					(thickness 0.15)
				)
				(justify left bottom)
			)
		)
		(property "Value" "C_220n_16V_0402"
			(at -1.022927 2.155213 0)
			(layer "F.Fab")
			(effects
				(font
					(size 0.7 0.7)
					(thickness 0.15)
				)
				(justify left bottom)
			)
		)
		(property "Datasheet" "https://www.murata.com/products/productdetail?partno=GRM155R71C224KA12%23"
			(at 0 0 0)
			(layer "F.Fab")
			(hide yes)
			(effects
				(font
					(size 1.27 1.27)
					(thickness 0.15)
				)
			)
		)
		(property "Description" "SMD Multilayer Ceramic Capacitor, 0.22 µF, 16 V, 0402 [1005 Metric], ± 10%, X7R, GRM Series"
			(at 0 0 0)
			(layer "F.Fab")
			(hide yes)
			(effects
				(font
					(size 1.27 1.27)
					(thickness 0.15)
				)
			)
		)
		(property "MPN" "GRM155R71C224KA12D"
			(at 0 0 0)
			(unlocked yes)
			(layer "F.Fab")
			(hide yes)
			(effects
				(font
					(size 1 1)
					(thickness 0.15)
				)
			)
		)
		(property "Manufacturer" "Murata"
			(at 0 0 0)
			(unlocked yes)
			(layer "F.Fab")
			(hide yes)
			(effects
				(font
					(size 1 1)
					(thickness 0.15)
				)
			)
		)
		(property "License" "Apache-2.0"
			(at 0 0 0)
			(unlocked yes)
			(layer "F.Fab")
			(hide yes)
			(effects
				(font
					(size 1 1)
					(thickness 0.15)
				)
			)
		)
		(property "Author" "Antmicro"
			(at 0 0 0)
			(unlocked yes)
			(layer "F.Fab")
			(hide yes)
			(effects
				(font
					(size 1 1)
					(thickness 0.15)
				)
			)
		)
		(property "Val" "220n"
			(at 0 0 0)
			(unlocked yes)
			(layer "F.Fab")
			(hide yes)
			(effects
				(font
					(size 1 1)
					(thickness 0.15)
				)
			)
		)
		(property "Voltage" "16V"
			(at 0 0 0)
			(unlocked yes)
			(layer "F.Fab")
			(hide yes)
			(effects
				(font
					(size 1 1)
					(thickness 0.15)
				)
			)
		)
		(property "Dielectric" "X7R"
			(at 0 0 0)
			(unlocked yes)
			(layer "F.Fab")
			(hide yes)
			(effects
				(font
					(size 1 1)
					(thickness 0.15)
				)
			)
		)
		(sheetname "/X710-AT2 PCIe/")
		(sheetfile "x710-at2-pcie.kicad_sch")
		(attr smd)
		(fp_rect
			(start -0.925 -0.47)
			(end 0.925 0.47)
			(stroke
				(width 0.05)
				(type default)
			)
			(fill no)
			(layer "F.CrtYd")
		)
		(fp_line
			(start -0.494 -0.25)
			(end 0.504 -0.25)
			(stroke
				(width 0.15)
				(type solid)
			)
			(layer "F.Fab")
		)
		(fp_line
			(start -0.494 0.248)
			(end -0.494 -0.25)
			(stroke
				(width 0.15)
				(type solid)
			)
			(layer "F.Fab")
		)
		(fp_line
			(start 0.504 -0.25)
			(end 0.504 0.248)
			(stroke
				(width 0.15)
				(type solid)
			)
			(layer "F.Fab")
		)
		(fp_line
			(start 0.504 0.248)
			(end -0.494 0.248)
			(stroke
				(width 0.15)
				(type solid)
			)
			(layer "F.Fab")
		)
		(fp_text user "${REFERENCE}"
			(at -0.939 4.599 0)
			(layer "F.Fab")
			(effects
				(font
					(size 0.7 0.7)
					(thickness 0.15)
				)
				(justify left bottom)
			)
		)
		(fp_text user "Author: Antmicro"
			(at -0.939 3.399 0)
			(layer "F.Fab")
			(effects
				(font
					(size 0.7 0.7)
					(thickness 0.15)
				)
				(justify left bottom)
			)
		)
		(fp_text user "License: Apache-2.0"
			(at -0.939 5.799 0)
			(layer "F.Fab")
			(effects
				(font
					(size 0.7 0.7)
					(thickness 0.15)
				)
				(justify left bottom)
			)
		)
		(pad "1" smd roundrect
			(at -0.48 0)
			(size 0.59 0.64)
			(layers "F.Cu" "F.Mask" "F.Paste")
			(roundrect_rratio 0.25)
			(net 597 "/TB Controller/PCIex4.TX0-")
			(pintype "passive")
		)
		(pad "2" smd roundrect
			(at 0.48 0)
			(size 0.59 0.64)
			(layers "F.Cu" "F.Mask" "F.Paste")
			(roundrect_rratio 0.25)
			(net 28 "/X710-AT2 PCIe/PCIe_{x4}_AC.TX0-")
			(pintype "passive")
		)
	)
	(footprint "antmicro-footprints:R_0402_1005Metric"
		(layer "F.Cu")
		(at 161.104999 67.124999 -90)
		(descr "Resistor SMD 0402")
		(tags "resistor SMD 0402")
		(property "Reference" "R193"
			(at -12.324999 -20.295 270)
			(layer "F.SilkS")
			(effects
				(font
					(size 0.7 0.7)
					(thickness 0.15)
				)
			)
		)
		(property "Value" "R_150R_0402"
			(at -1.011843 1.772047 270)
			(layer "F.Fab")
			(effects
				(font
					(size 0.7 0.7)
					(thickness 0.15)
				)
				(justify left bottom)
			)
		)
		(property "Datasheet" "https://www.bourns.com/docs/product-datasheets/cr.pdf"
			(at 0 0 270)
			(layer "F.Fab")
			(hide yes)
			(effects
				(font
					(size 1.27 1.27)
					(thickness 0.15)
				)
			)
		)
		(property "Description" "SMD Chip Resistor, 150 ohm, ± 1%, 62.5 mW, 0402 [1005 Metric], Thick Film, General Purpose"
			(at 0 0 270)
			(layer "F.Fab")
			(hide yes)
			(effects
				(font
					(size 1.27 1.27)
					(thickness 0.15)
				)
			)
		)
		(property "MPN" "CR0402-FX-1500GLF"
			(at 0 0 270)
			(unlocked yes)
			(layer "F.Fab")
			(hide yes)
			(effects
				(font
					(size 1 1)
					(thickness 0.15)
				)
			)
		)
		(property "Manufacturer" "Bourns"
			(at 0 0 270)
			(unlocked yes)
			(layer "F.Fab")
			(hide yes)
			(effects
				(font
					(size 1 1)
					(thickness 0.15)
				)
			)
		)
		(property "License" "Apache-2.0"
			(at 0 0 270)
			(unlocked yes)
			(layer "F.Fab")
			(hide yes)
			(effects
				(font
					(size 1 1)
					(thickness 0.15)
				)
			)
		)
		(property "Author" "Antmicro"
			(at 0 0 270)
			(unlocked yes)
			(layer "F.Fab")
			(hide yes)
			(effects
				(font
					(size 1 1)
					(thickness 0.15)
				)
			)
		)
		(property "Val" "150R"
			(at 0 0 270)
			(unlocked yes)
			(layer "F.Fab")
			(hide yes)
			(effects
				(font
					(size 1 1)
					(thickness 0.15)
				)
			)
		)
		(property "Tolerance" "1%"
			(at 0 0 270)
			(unlocked yes)
			(layer "F.Fab")
			(hide yes)
			(effects
				(font
					(size 1 1)
					(thickness 0.15)
				)
			)
		)
		(sheetname "/X710-AT2 10GbE/")
		(sheetfile "x710-at2-10gbe.kicad_sch")
		(attr smd)
		(fp_rect
			(start -0.925 -0.47)
			(end 0.925 0.47)
			(stroke
				(width 0.05)
				(type default)
			)
			(fill no)
			(layer "F.CrtYd")
		)
		(fp_rect
			(start -0.5 -0.25)
			(end 0.5 0.25)
			(stroke
				(width 0.15)
				(type solid)
			)
			(fill no)
			(layer "F.Fab")
		)
		(fp_text user "${REFERENCE}"
			(at -0.95 3.168 270)
			(layer "F.Fab")
			(effects
				(font
					(size 0.7 0.7)
					(thickness 0.15)
				)
				(justify left bottom)
			)
		)
		(fp_text user "License: Apache-2.0"
			(at -0.95 5.169 270)
			(layer "F.Fab")
			(effects
				(font
					(size 0.7 0.7)
					(thickness 0.15)
				)
				(justify left bottom)
			)
		)
		(fp_text user "Author: Antmicro"
			(at -0.95 4.169 270)
			(layer "F.Fab")
			(effects
				(font
					(size 0.7 0.7)
					(thickness 0.15)
				)
				(justify left bottom)
			)
		)
		(pad "1" smd roundrect
			(at -0.48 0 270)
			(size 0.59 0.64)
			(layers "F.Cu" "F.Mask" "F.Paste")
			(roundrect_rratio 0.25)
			(net 23 "GND")
			(pintype "passive")
		)
		(pad "2" smd roundrect
			(at 0.48 0 270)
			(size 0.59 0.64)
			(layers "F.Cu" "F.Mask" "F.Paste")
			(roundrect_rratio 0.25)
			(net 55 "/X710-AT2 10GbE/25MHZ_OSC_AC.-")
			(pintype "passive")
		)
	)
	(footprint "antmicro-footprints:L_Bourns-SRP4021HMT"
		(layer "F.Cu")
		(at 145.405 66.925 -90)
		(property "Reference" "L11"
			(at -12.424999 -21.944998 270)
			(layer "F.SilkS")
			(effects
				(font
					(size 0.7 0.7)
					(thickness 0.15)
				)
			)
		)
		(property "Value" "L_1u_10A_Bourns-SRP4021HMT"
			(at -2.85 3.4 270)
			(layer "F.Fab")
			(effects
				(font
					(size 0.7 0.7)
					(thickness 0.15)
				)
				(justify left bottom)
			)
		)
		(property "Datasheet" "https://www.mouser.com/datasheet/2/54/Bourns_04_01_2025_SRP4021HMT_Datasheet-3580094.pdf"
			(at 0 0 270)
			(layer "F.Fab")
			(effects
				(font
					(size 0.7 0.7)
					(thickness 0.15)
				)
				(justify left bottom)
			)
		)
		(property "Description" "Power Inductors - SMD Ind,4.1x4.2x1.9mm,1uH+/-20%,10A, Shielded"
			(at 0 0 270)
			(layer "F.Fab")
			(effects
				(font
					(size 0.7 0.7)
					(thickness 0.15)
				)
				(justify left bottom)
			)
		)
		(property "Val" "1u/10A"
			(at 0 0 270)
			(unlocked yes)
			(layer "F.Fab")
			(hide yes)
			(effects
				(font
					(size 1 1)
					(thickness 0.15)
				)
			)
		)
		(property "Manufacturer" "Bourns"
			(at 0 0 270)
			(unlocked yes)
			(layer "F.Fab")
			(hide yes)
			(effects
				(font
					(size 1 1)
					(thickness 0.15)
				)
			)
		)
		(property "MPN" "SRP4021HMT-1R0M"
			(at 0 0 270)
			(unlocked yes)
			(layer "F.Fab")
			(hide yes)
			(effects
				(font
					(size 1 1)
					(thickness 0.15)
				)
			)
		)
		(property "ISat" ""
			(at 0 0 270)
			(unlocked yes)
			(layer "F.Fab")
			(hide yes)
			(effects
				(font
					(size 1 1)
					(thickness 0.15)
				)
			)
		)
		(property "Isat" "8A"
			(at 0 0 270)
			(unlocked yes)
			(layer "F.Fab")
			(hide yes)
			(effects
				(font
					(size 1 1)
					(thickness 0.15)
				)
			)
		)
		(property "IMax" ""
			(at 0 0 270)
			(unlocked yes)
			(layer "F.Fab")
			(hide yes)
			(effects
				(font
					(size 1 1)
					(thickness 0.15)
				)
			)
		)
		(property "Imax" "10A"
			(at 0 0 270)
			(unlocked yes)
			(layer "F.Fab")
			(hide yes)
			(effects
				(font
					(size 1 1)
					(thickness 0.15)
				)
			)
		)
		(property "Size" "4.2x4.1"
			(at 0 0 270)
			(unlocked yes)
			(layer "F.Fab")
			(hide yes)
			(effects
				(font
					(size 1 1)
					(thickness 0.15)
				)
			)
		)
		(property "Author" "Antmicro"
			(at 0 0 270)
			(unlocked yes)
			(layer "F.Fab")
			(hide yes)
			(effects
				(font
					(size 1 1)
					(thickness 0.15)
				)
			)
		)
		(property "License" "Apache-2.0"
			(at 0 0 270)
			(unlocked yes)
			(layer "F.Fab")
			(hide yes)
			(effects
				(font
					(size 1 1)
					(thickness 0.15)
				)
			)
		)
		(sheetname "/X710-AT2 power/")
		(sheetfile "x710-at2-power.kicad_sch")
		(attr smd)
		(fp_line
			(start -0.8 2.05)
			(end 0.8 2.05)
			(stroke
				(width 0.15)
				(type solid)
			)
			(layer "F.SilkS")
		)
		(fp_line
			(start -0.8 -2.05)
			(end 0.8 -2.05)
			(stroke
				(width 0.15)
				(type solid)
			)
			(layer "F.SilkS")
		)
		(fp_rect
			(start -2.85 -2.3)
			(end 2.85 2.3)
			(stroke
				(width 0.05)
				(type solid)
			)
			(fill no)
			(layer "F.CrtYd")
		)
		(fp_rect
			(start -2 -2.05)
			(end 2 2.05)
			(stroke
				(width 0.15)
				(type solid)
			)
			(fill no)
			(layer "F.Fab")
		)
		(fp_text user "${REFERENCE}"
			(at -2.85 5.8 270)
			(layer "F.Fab")
			(effects
				(font
					(size 0.7 0.7)
					(thickness 0.15)
				)
				(justify left bottom)
			)
		)
		(fp_text user "License: Apache-2.0"
			(at -2.85 7 270)
			(layer "F.Fab")
			(effects
				(font
					(size 0.7 0.7)
					(thickness 0.15)
				)
				(justify left bottom)
			)
		)
		(fp_text user "Author: Antmicro"
			(at -2.85 4.6 270)
			(layer "F.Fab")
			(effects
				(font
					(size 0.7 0.7)
					(thickness 0.15)
				)
				(justify left bottom)
			)
		)
		(pad "1" smd rect
			(at 1.85 0 90)
			(size 1.5 3.5)
			(layers "F.Cu" "F.Mask" "F.Paste")
			(net 427 "Net-(U14H-SVR_IND)")
			(pintype "passive")
		)
		(pad "2" smd rect
			(at -1.85 0 90)
			(size 1.5 3.5)
			(layers "F.Cu" "F.Mask" "F.Paste")
			(net 1 "VCCA")
			(pintype "passive")
		)
	)
	(footprint "antmicro-footprints:R_0402_1005Metric"
		(layer "F.Cu")
		(at 154.305 69.074999 -90)
		(descr "Resistor SMD 0402")
		(tags "resistor SMD 0402")
		(property "Reference" "R155"
			(at -11.574999 -20.295 270)
			(layer "F.SilkS")
			(effects
				(font
					(size 0.7 0.7)
					(thickness 0.15)
				)
			)
		)
		(property "Value" "R_100R_0402"
			(at -1.011843 1.772047 270)
			(layer "F.Fab")
			(effects
				(font
					(size 0.7 0.7)
					(thickness 0.15)
				)
				(justify left bottom)
			)
		)
		(property "Datasheet" "https://www.bourns.com/docs/product-datasheets/cr.pdf"
			(at 0 0 270)
			(layer "F.Fab")
			(hide yes)
			(effects
				(font
					(size 1.27 1.27)
					(thickness 0.15)
				)
			)
		)
		(property "Description" "SMD Chip Resistor, 100 ohm, ± 1%, 62.5 mW, 0402 [1005 Metric], Thick Film, General Purpose"
			(at 0 0 270)
			(layer "F.Fab")
			(hide yes)
			(effects
				(font
					(size 1.27 1.27)
					(thickness 0.15)
				)
			)
		)
		(property "MPN" "CR0402-FX-1000GLF"
			(at 0 0 270)
			(unlocked yes)
			(layer "F.Fab")
			(hide yes)
			(effects
				(font
					(size 1 1)
					(thickness 0.15)
				)
			)
		)
		(property "Manufacturer" "Bourns"
			(at 0 0 270)
			(unlocked yes)
			(layer "F.Fab")
			(hide yes)
			(effects
				(font
					(size 1 1)
					(thickness 0.15)
				)
			)
		)
		(property "License" "Apache-2.0"
			(at 0 0 270)
			(unlocked yes)
			(layer "F.Fab")
			(hide yes)
			(effects
				(font
					(size 1 1)
					(thickness 0.15)
				)
			)
		)
		(property "Author" "Antmicro"
			(at 0 0 270)
			(unlocked yes)
			(layer "F.Fab")
			(hide yes)
			(effects
				(font
					(size 1 1)
					(thickness 0.15)
				)
			)
		)
		(property "Val" "100R"
			(at 0 0 270)
			(unlocked yes)
			(layer "F.Fab")
			(hide yes)
			(effects
				(font
					(size 1 1)
					(thickness 0.15)
				)
			)
		)
		(property "Tolerance" "1%"
			(at 0 0 270)
			(unlocked yes)
			(layer "F.Fab")
			(hide yes)
			(effects
				(font
					(size 1 1)
					(thickness 0.15)
				)
			)
		)
		(sheetname "/X710-AT2 Misc/")
		(sheetfile "x710-at2-mics.kicad_sch")
		(attr smd dnp)
		(fp_rect
			(start -0.925 -0.47)
			(end 0.925 0.47)
			(stroke
				(width 0.05)
				(type default)
			)
			(fill no)
			(layer "F.CrtYd")
		)
		(fp_rect
			(start -0.5 -0.25)
			(end 0.5 0.25)
			(stroke
				(width 0.15)
				(type solid)
			)
			(fill no)
			(layer "F.Fab")
		)
		(fp_text user "Author: Antmicro"
			(at -0.95 4.169 270)
			(layer "F.Fab")
			(effects
				(font
					(size 0.7 0.7)
					(thickness 0.15)
				)
				(justify left bottom)
			)
		)
		(fp_text user "${REFERENCE}"
			(at -0.95 3.168 270)
			(layer "F.Fab")
			(effects
				(font
					(size 0.7 0.7)
					(thickness 0.15)
				)
				(justify left bottom)
			)
		)
		(fp_text user "License: Apache-2.0"
			(at -0.95 5.169 270)
			(layer "F.Fab")
			(effects
				(font
					(size 0.7 0.7)
					(thickness 0.15)
				)
				(justify left bottom)
			)
		)
		(pad "1" smd roundrect
			(at -0.48 0 270)
			(size 0.59 0.64)
			(layers "F.Cu" "F.Mask" "F.Paste")
			(roundrect_rratio 0.25)
			(net 23 "GND")
			(pintype "passive")
		)
		(pad "2" smd roundrect
			(at 0.48 0 270)
			(size 0.59 0.64)
			(layers "F.Cu" "F.Mask" "F.Paste")
			(roundrect_rratio 0.25)
			(net 75 "/X710-AT2 Misc/AUX_PWR")
			(pintype "passive")
		)
	)
	(footprint "antmicro-footprints:R_0402_1005Metric"
		(layer "F.Cu")
		(at 129.52 93.2)
		(descr "Resistor SMD 0402")
		(tags "resistor SMD 0402")
		(property "Reference" "R98"
			(at 38.914999 -9.199999 0)
			(layer "F.SilkS")
			(effects
				(font
					(size 0.7 0.7)
					(thickness 0.15)
				)
			)
		)
		(property "Value" "R_90k9_0402"
			(at -1.011843 1.772047 0)
			(layer "F.Fab")
			(effects
				(font
					(size 0.7 0.7)
					(thickness 0.15)
				)
				(justify left bottom)
			)
		)
		(property "Datasheet" "https://www.bourns.com/docs/product-datasheets/cr.pdf"
			(at 0 0 0)
			(layer "F.Fab")
			(hide yes)
			(effects
				(font
					(size 1.27 1.27)
					(thickness 0.15)
				)
			)
		)
		(property "Description" "SMD Chip Resistor"
			(at 0 0 0)
			(layer "F.Fab")
			(hide yes)
			(effects
				(font
					(size 1.27 1.27)
					(thickness 0.15)
				)
			)
		)
		(property "MPN" "CR0402-FX-9092GLF"
			(at 0 0 0)
			(unlocked yes)
			(layer "F.Fab")
			(hide yes)
			(effects
				(font
					(size 1 1)
					(thickness 0.15)
				)
			)
		)
		(property "Manufacturer" "Bourns"
			(at 0 0 0)
			(unlocked yes)
			(layer "F.Fab")
			(hide yes)
			(effects
				(font
					(size 1 1)
					(thickness 0.15)
				)
			)
		)
		(property "License" "Apache-2.0"
			(at 0 0 0)
			(unlocked yes)
			(layer "F.Fab")
			(hide yes)
			(effects
				(font
					(size 1 1)
					(thickness 0.15)
				)
			)
		)
		(property "Author" "Antmicro"
			(at 0 0 0)
			(unlocked yes)
			(layer "F.Fab")
			(hide yes)
			(effects
				(font
					(size 1 1)
					(thickness 0.15)
				)
			)
		)
		(property "Val" "90k9"
			(at 0 0 0)
			(unlocked yes)
			(layer "F.Fab")
			(hide yes)
			(effects
				(font
					(size 1 1)
					(thickness 0.15)
				)
			)
		)
		(property "Tolerance" "1%"
			(at 0 0 0)
			(unlocked yes)
			(layer "F.Fab")
			(hide yes)
			(effects
				(font
					(size 1 1)
					(thickness 0.15)
				)
			)
		)
		(sheetname "/X710 DCDC converters/")
		(sheetfile "DCDC_converters_X710.kicad_sch")
		(attr smd)
		(fp_rect
			(start -0.925 -0.47)
			(end 0.925 0.47)
			(stroke
				(width 0.05)
				(type default)
			)
			(fill no)
			(layer "F.CrtYd")
		)
		(fp_rect
			(start -0.5 -0.25)
			(end 0.5 0.25)
			(stroke
				(width 0.15)
				(type solid)
			)
			(fill no)
			(layer "F.Fab")
		)
		(fp_text user "License: Apache-2.0"
			(at -0.95 5.169 0)
			(layer "F.Fab")
			(effects
				(font
					(size 0.7 0.7)
					(thickness 0.15)
				)
				(justify left bottom)
			)
		)
		(fp_text user "Author: Antmicro"
			(at -0.95 4.169 0)
			(layer "F.Fab")
			(effects
				(font
					(size 0.7 0.7)
					(thickness 0.15)
				)
				(justify left bottom)
			)
		)
		(fp_text user "${REFERENCE}"
			(at -0.95 3.168 0)
			(layer "F.Fab")
			(effects
				(font
					(size 0.7 0.7)
					(thickness 0.15)
				)
				(justify left bottom)
			)
		)
		(pad "1" smd roundrect
			(at -0.48 0)
			(size 0.59 0.64)
			(layers "F.Cu" "F.Mask" "F.Paste")
			(roundrect_rratio 0.25)
			(net 333 "/X710 DCDC converters/3V3_FB")
			(pintype "passive")
		)
		(pad "2" smd roundrect
			(at 0.48 0)
			(size 0.59 0.64)
			(layers "F.Cu" "F.Mask" "F.Paste")
			(roundrect_rratio 0.25)
			(net 334 "/X710 DCDC converters/+3V3_OUT")
			(pintype "passive")
		)
	)
	(footprint "antmicro-footprints:C_0402_1005Metric"
		(layer "F.Cu")
		(at 159.105 69.075 90)
		(descr "Capacitor SMD 0402")
		(tags "capacitor SMD 0402")
		(property "Reference" "C287"
			(at 11.574999 20.295 90)
			(layer "F.SilkS")
			(effects
				(font
					(size 0.7 0.7)
					(thickness 0.15)
				)
			)
		)
		(property "Value" "C_100n_0402"
			(at -1.022927 2.155213 90)
			(layer "F.Fab")
			(effects
				(font
					(size 0.7 0.7)
					(thickness 0.15)
				)
				(justify left bottom)
			)
		)
		(property "Datasheet" "https://www.murata.com/products/productdetail?partno=GRM155R61H104KE14%23"
			(at 0 0 90)
			(layer "F.Fab")
			(hide yes)
			(effects
				(font
					(size 1.27 1.27)
					(thickness 0.15)
				)
			)
		)
		(property "Description" "SMD Multilayer Ceramic Capacitor, 0.1 µF, 50 V, 0402 [1005 Metric], ± 10%, X5R, GRM Series"
			(at 0 0 90)
			(layer "F.Fab")
			(hide yes)
			(effects
				(font
					(size 1.27 1.27)
					(thickness 0.15)
				)
			)
		)
		(property "MPN" "GRM155R61H104KE14D"
			(at 0 0 90)
			(unlocked yes)
			(layer "F.Fab")
			(hide yes)
			(effects
				(font
					(size 1 1)
					(thickness 0.15)
				)
			)
		)
		(property "Val" "100n"
			(at 0 0 90)
			(unlocked yes)
			(layer "F.Fab")
			(hide yes)
			(effects
				(font
					(size 1 1)
					(thickness 0.15)
				)
			)
		)
		(property "Voltage" "50V"
			(at 0 0 90)
			(unlocked yes)
			(layer "F.Fab")
			(hide yes)
			(effects
				(font
					(size 1 1)
					(thickness 0.15)
				)
			)
		)
		(property "Dielectric" "X5R"
			(at 0 0 90)
			(unlocked yes)
			(layer "F.Fab")
			(hide yes)
			(effects
				(font
					(size 1 1)
					(thickness 0.15)
				)
			)
		)
		(property "Manufacturer" "Murata"
			(at 0 0 90)
			(unlocked yes)
			(layer "F.Fab")
			(hide yes)
			(effects
				(font
					(size 1 1)
					(thickness 0.15)
				)
			)
		)
		(property "License" "Apache-2.0"
			(at 0 0 90)
			(unlocked yes)
			(layer "F.Fab")
			(hide yes)
			(effects
				(font
					(size 1 1)
					(thickness 0.15)
				)
			)
		)
		(property "Author" "Antmicro"
			(at 0 0 90)
			(unlocked yes)
			(layer "F.Fab")
			(hide yes)
			(effects
				(font
					(size 1 1)
					(thickness 0.15)
				)
			)
		)
		(sheetname "/X710-AT2 10GbE/")
		(sheetfile "x710-at2-10gbe.kicad_sch")
		(attr smd)
		(fp_rect
			(start -0.925 -0.47)
			(end 0.925 0.47)
			(stroke
				(width 0.05)
				(type default)
			)
			(fill no)
			(layer "F.CrtYd")
		)
		(fp_line
			(start 0.504 -0.25)
			(end 0.504 0.248)
			(stroke
				(width 0.15)
				(type solid)
			)
			(layer "F.Fab")
		)
		(fp_line
			(start -0.494 -0.25)
			(end 0.504 -0.25)
			(stroke
				(width 0.15)
				(type solid)
			)
			(layer "F.Fab")
		)
		(fp_line
			(start 0.504 0.248)
			(end -0.494 0.248)
			(stroke
				(width 0.15)
				(type solid)
			)
			(layer "F.Fab")
		)
		(fp_line
			(start -0.494 0.248)
			(end -0.494 -0.25)
			(stroke
				(width 0.15)
				(type solid)
			)
			(layer "F.Fab")
		)
		(fp_text user "License: Apache-2.0"
			(at -0.939 5.799 90)
			(layer "F.Fab")
			(effects
				(font
					(size 0.7 0.7)
					(thickness 0.15)
				)
				(justify left bottom)
			)
		)
		(fp_text user "${REFERENCE}"
			(at -0.939 4.599 90)
			(layer "F.Fab")
			(effects
				(font
					(size 0.7 0.7)
					(thickness 0.15)
				)
				(justify left bottom)
			)
		)
		(fp_text user "Author: Antmicro"
			(at -0.939 3.399 90)
			(layer "F.Fab")
			(effects
				(font
					(size 0.7 0.7)
					(thickness 0.15)
				)
				(justify left bottom)
			)
		)
		(pad "1" smd roundrect
			(at -0.48 0 90)
			(size 0.59 0.64)
			(layers "F.Cu" "F.Mask" "F.Paste")
			(roundrect_rratio 0.25)
			(net 24 "/X710-AT2 10GbE/25MHZ_OSC.+")
			(pintype "passive")
		)
		(pad "2" smd roundrect
			(at 0.48 0 90)
			(size 0.59 0.64)
			(layers "F.Cu" "F.Mask" "F.Paste")
			(roundrect_rratio 0.25)
			(net 25 "/X710-AT2 10GbE/25MHZ_OSC_AC.+")
			(pintype "passive")
		)
	)
	(footprint "antmicro-footprints:C_0402_1005Metric"
		(layer "F.Cu")
		(at 117.8 125 180)
		(descr "Capacitor SMD 0402")
		(tags "capacitor SMD 0402")
		(property "Reference" "C50"
			(at -0.8 -0.2 180)
			(layer "F.SilkS")
			(effects
				(font
					(size 0.7 0.7)
					(thickness 0.15)
				)
				(justify left bottom)
			)
		)
		(property "Value" "C_220n_0402"
			(at -1.022927 2.155213 180)
			(layer "F.Fab")
			(effects
				(font
					(size 0.7 0.7)
					(thickness 0.15)
				)
				(justify left bottom)
			)
		)
		(property "Datasheet" "https://www.yageo.com/en/Chart/Download/pdf/CC0402KRX5R6BB224"
			(at 0 0 180)
			(layer "F.Fab")
			(hide yes)
			(effects
				(font
					(size 1.27 1.27)
					(thickness 0.15)
				)
			)
		)
		(property "Description" "SMD Multilayer Ceramic Capacitor, 0.22 µF, 10 V, 0402 [1005 Metric], ± 10%, X5R, CC Series"
			(at 0 0 180)
			(layer "F.Fab")
			(hide yes)
			(effects
				(font
					(size 1.27 1.27)
					(thickness 0.15)
				)
			)
		)
		(property "MPN" "CC0402KRX5R6BB224"
			(at 0 0 180)
			(unlocked yes)
			(layer "F.Fab")
			(hide yes)
			(effects
				(font
					(size 1 1)
					(thickness 0.15)
				)
			)
		)
		(property "Manufacturer" "YAGEO"
			(at 0 0 180)
			(unlocked yes)
			(layer "F.Fab")
			(hide yes)
			(effects
				(font
					(size 1 1)
					(thickness 0.15)
				)
			)
		)
		(property "License" "Apache-2.0"
			(at 0 0 180)
			(unlocked yes)
			(layer "F.Fab")
			(hide yes)
			(effects
				(font
					(size 1 1)
					(thickness 0.15)
				)
			)
		)
		(property "Val" "220n"
			(at 0 0 180)
			(unlocked yes)
			(layer "F.Fab")
			(hide yes)
			(effects
				(font
					(size 1 1)
					(thickness 0.15)
				)
			)
		)
		(property "Voltage" ""
			(at 0 0 180)
			(unlocked yes)
			(layer "F.Fab")
			(hide yes)
			(effects
				(font
					(size 1 1)
					(thickness 0.15)
				)
			)
		)
		(property "Dielectric" ""
			(at 0 0 180)
			(unlocked yes)
			(layer "F.Fab")
			(hide yes)
			(effects
				(font
					(size 1 1)
					(thickness 0.15)
				)
			)
		)
		(property "Author" "Antmicro"
			(at 0 0 180)
			(unlocked yes)
			(layer "F.Fab")
			(hide yes)
			(effects
				(font
					(size 1 1)
					(thickness 0.15)
				)
			)
		)
		(sheetname "/TB Controller/")
		(sheetfile "tb.kicad_sch")
		(attr smd)
		(fp_rect
			(start -0.925 -0.47)
			(end 0.925 0.47)
			(stroke
				(width 0.05)
				(type default)
			)
			(fill no)
			(layer "F.CrtYd")
		)
		(fp_line
			(start 0.504 0.248)
			(end -0.494 0.248)
			(stroke
				(width 0.15)
				(type solid)
			)
			(layer "F.Fab")
		)
		(fp_line
			(start 0.504 -0.25)
			(end 0.504 0.248)
			(stroke
				(width 0.15)
				(type solid)
			)
			(layer "F.Fab")
		)
		(fp_line
			(start -0.494 0.248)
			(end -0.494 -0.25)
			(stroke
				(width 0.15)
				(type solid)
			)
			(layer "F.Fab")
		)
		(fp_line
			(start -0.494 -0.25)
			(end 0.504 -0.25)
			(stroke
				(width 0.15)
				(type solid)
			)
			(layer "F.Fab")
		)
		(fp_text user "License: Apache-2.0"
			(at -0.939 5.799 180)
			(layer "F.Fab")
			(effects
				(font
					(size 0.7 0.7)
					(thickness 0.15)
				)
				(justify left bottom)
			)
		)
		(fp_text user "Author: Antmicro"
			(at -0.939 3.399 180)
			(layer "F.Fab")
			(effects
				(font
					(size 0.7 0.7)
					(thickness 0.15)
				)
				(justify left bottom)
			)
		)
		(fp_text user "${REFERENCE}"
			(at -0.939 4.599 180)
			(layer "F.Fab")
			(effects
				(font
					(size 0.7 0.7)
					(thickness 0.15)
				)
				(justify left bottom)
			)
		)
		(pad "1" smd roundrect
			(at -0.48 0 180)
			(size 0.59 0.64)
			(layers "F.Cu" "F.Mask" "F.Paste")
			(roundrect_rratio 0.25)
			(net 318 "/TB Controller/TB_PCIE_TX2_N")
			(pintype "passive")
		)
		(pad "2" smd roundrect
			(at 0.48 0 180)
			(size 0.59 0.64)
			(layers "F.Cu" "F.Mask" "F.Paste")
			(roundrect_rratio 0.25)
			(net 326 "/TB Controller/PCIex4.RX2-")
			(pintype "passive")
		)
	)
	(footprint "antmicro-footprints:C_0402_1005Metric"
		(layer "F.Cu")
		(at 143.849999 109.150002)
		(descr "Capacitor SMD 0402")
		(tags "capacitor SMD 0402")
		(property "Reference" "C123"
			(at 15.349999 17.25 0)
			(layer "F.SilkS")
			(effects
				(font
					(size 0.7 0.7)
					(thickness 0.15)
				)
			)
		)
		(property "Value" "C_1u_25V_0402"
			(at -1.022927 2.155213 0)
			(layer "F.Fab")
			(effects
				(font
					(size 0.7 0.7)
					(thickness 0.15)
				)
				(justify left bottom)
			)
		)
		(property "Datasheet" "https://www.murata.com/products/productdetail?partno=GRM155R61E105KE11%23"
			(at 0 0 0)
			(layer "F.Fab")
			(hide yes)
			(effects
				(font
					(size 1.27 1.27)
					(thickness 0.15)
				)
			)
		)
		(property "Description" "SMD Multilayer Ceramic Capacitor, 1 µF, 25 V, 0402 [1005 Metric], ± 10%, X5R, GRM Series"
			(at 0 0 0)
			(layer "F.Fab")
			(hide yes)
			(effects
				(font
					(size 1.27 1.27)
					(thickness 0.15)
				)
			)
		)
		(property "MPN" "GRM155R61E105KE11J"
			(at 0 0 0)
			(unlocked yes)
			(layer "F.Fab")
			(hide yes)
			(effects
				(font
					(size 1 1)
					(thickness 0.15)
				)
			)
		)
		(property "Manufacturer" "Murata"
			(at 0 0 0)
			(unlocked yes)
			(layer "F.Fab")
			(hide yes)
			(effects
				(font
					(size 1 1)
					(thickness 0.15)
				)
			)
		)
		(property "License" "Apache-2.0"
			(at 0 0 0)
			(unlocked yes)
			(layer "F.Fab")
			(hide yes)
			(effects
				(font
					(size 1 1)
					(thickness 0.15)
				)
			)
		)
		(property "Author" "Antmicro"
			(at 0 0 0)
			(unlocked yes)
			(layer "F.Fab")
			(hide yes)
			(effects
				(font
					(size 1 1)
					(thickness 0.15)
				)
			)
		)
		(property "Val" "1u"
			(at 0 0 0)
			(unlocked yes)
			(layer "F.Fab")
			(hide yes)
			(effects
				(font
					(size 1 1)
					(thickness 0.15)
				)
			)
		)
		(property "Voltage" "25V"
			(at 0 0 0)
			(unlocked yes)
			(layer "F.Fab")
			(hide yes)
			(effects
				(font
					(size 1 1)
					(thickness 0.15)
				)
			)
		)
		(property "Dielectric" "X5R"
			(at 0 0 0)
			(unlocked yes)
			(layer "F.Fab")
			(hide yes)
			(effects
				(font
					(size 1 1)
					(thickness 0.15)
				)
			)
		)
		(sheetname "/X710 DCDC converters/")
		(sheetfile "DCDC_converters_X710.kicad_sch")
		(attr smd)
		(fp_rect
			(start -0.925 -0.47)
			(end 0.925 0.47)
			(stroke
				(width 0.05)
				(type default)
			)
			(fill no)
			(layer "F.CrtYd")
		)
		(fp_line
			(start -0.494 -0.25)
			(end 0.504 -0.25)
			(stroke
				(width 0.15)
				(type solid)
			)
			(layer "F.Fab")
		)
		(fp_line
			(start -0.494 0.248)
			(end -0.494 -0.25)
			(stroke
				(width 0.15)
				(type solid)
			)
			(layer "F.Fab")
		)
		(fp_line
			(start 0.504 -0.25)
			(end 0.504 0.248)
			(stroke
				(width 0.15)
				(type solid)
			)
			(layer "F.Fab")
		)
		(fp_line
			(start 0.504 0.248)
			(end -0.494 0.248)
			(stroke
				(width 0.15)
				(type solid)
			)
			(layer "F.Fab")
		)
		(fp_text user "Author: Antmicro"
			(at -0.939 3.399 0)
			(layer "F.Fab")
			(effects
				(font
					(size 0.7 0.7)
					(thickness 0.15)
				)
				(justify left bottom)
			)
		)
		(fp_text user "License: Apache-2.0"
			(at -0.939 5.799 0)
			(layer "F.Fab")
			(effects
				(font
					(size 0.7 0.7)
					(thickness 0.15)
				)
				(justify left bottom)
			)
		)
		(fp_text user "${REFERENCE}"
			(at -0.939 4.599 0)
			(layer "F.Fab")
			(effects
				(font
					(size 0.7 0.7)
					(thickness 0.15)
				)
				(justify left bottom)
			)
		)
		(pad "1" smd roundrect
			(at -0.48 0)
			(size 0.59 0.64)
			(layers "F.Cu" "F.Mask" "F.Paste")
			(roundrect_rratio 0.25)
			(net 23 "GND")
			(pintype "passive")
		)
		(pad "2" smd roundrect
			(at 0.48 0)
			(size 0.59 0.64)
			(layers "F.Cu" "F.Mask" "F.Paste")
			(roundrect_rratio 0.25)
			(net 116 "/X710 DCDC converters/DVDD_VCC")
			(pintype "passive")
		)
	)
	(footprint "antmicro-footprints:L_Coilcraft-XAL5030"
		(layer "F.Cu")
		(at 120.25 98.5)
		(property "Reference" "L1"
			(at -0.05 -3.5 0)
			(layer "F.SilkS")
			(effects
				(font
					(size 0.7 0.7)
					(thickness 0.15)
				)
			)
		)
		(property "Value" "L_2u2_9.7A_Coilcraft-XAL5030"
			(at 0 4.241 0)
			(layer "F.Fab")
			(effects
				(font
					(size 0.7 0.7)
					(thickness 0.15)
				)
				(justify left bottom)
			)
		)
		(property "Datasheet" "https://www.coilcraft.com/getmedia/49bc46c8-4b2c-45b9-9b6c-2eaa235ea698/xal50xx.pdf"
			(at 0 0 0)
			(layer "F.Fab")
			(hide yes)
			(effects
				(font
					(size 1.27 1.27)
					(thickness 0.15)
				)
			)
		)
		(property "Description" "Power Inductor (SMT), 2.2 µH, 9.7 A, Shielded, 9.2 A, XAL5030"
			(at 0 0 0)
			(layer "F.Fab")
			(hide yes)
			(effects
				(font
					(size 1.27 1.27)
					(thickness 0.15)
				)
			)
		)
		(property "Val" "2u2/9.7A"
			(at 0 0 0)
			(unlocked yes)
			(layer "F.Fab")
			(hide yes)
			(effects
				(font
					(size 1 1)
					(thickness 0.15)
				)
			)
		)
		(property "Manufacturer" "Coilcraft"
			(at 0 0 0)
			(unlocked yes)
			(layer "F.Fab")
			(hide yes)
			(effects
				(font
					(size 1 1)
					(thickness 0.15)
				)
			)
		)
		(property "MPN" "XAL5030-222MEC"
			(at 0 0 0)
			(unlocked yes)
			(layer "F.Fab")
			(hide yes)
			(effects
				(font
					(size 1 1)
					(thickness 0.15)
				)
			)
		)
		(property "ISat" "9.2 A"
			(at 0 0 0)
			(unlocked yes)
			(layer "F.Fab")
			(hide yes)
			(effects
				(font
					(size 1 1)
					(thickness 0.15)
				)
			)
		)
		(property "IMax" "9.7 A"
			(at 0 0 0)
			(unlocked yes)
			(layer "F.Fab")
			(hide yes)
			(effects
				(font
					(size 1 1)
					(thickness 0.15)
				)
			)
		)
		(property "Size" "5.28x5.48"
			(at 0 0 0)
			(unlocked yes)
			(layer "F.Fab")
			(hide yes)
			(effects
				(font
					(size 1 1)
					(thickness 0.15)
				)
			)
		)
		(property "Author" "Antmicro"
			(at 0 0 0)
			(unlocked yes)
			(layer "F.Fab")
			(hide yes)
			(effects
				(font
					(size 1 1)
					(thickness 0.15)
				)
			)
		)
		(property "License" "Apache-2.0"
			(at 0 0 0)
			(unlocked yes)
			(layer "F.Fab")
			(hide yes)
			(effects
				(font
					(size 1 1)
					(thickness 0.15)
				)
			)
		)
		(sheetname "/PD and TB DC-DC/")
		(sheetfile "PD_and_TB_DC_DC.kicad_sch")
		(attr smd)
		(fp_line
			(start -2.74 -2.84)
			(end 2.74 -2.84)
			(stroke
				(width 0.15)
				(type solid)
			)
			(layer "F.SilkS")
		)
		(fp_line
			(start -2.74 2.84)
			(end -2.74 -2.84)
			(stroke
				(width 0.15)
				(type solid)
			)
			(layer "F.SilkS")
		)
		(fp_line
			(start -2.74 2.84)
			(end 2.74 2.84)
			(stroke
				(width 0.15)
				(type solid)
			)
			(layer "F.SilkS")
		)
		(fp_line
			(start 2.74 2.84)
			(end 2.74 -2.84)
			(stroke
				(width 0.15)
				(type solid)
			)
			(layer "F.SilkS")
		)
		(fp_rect
			(start -2.89 -2.99)
			(end 2.89 2.99)
			(stroke
				(width 0.05)
				(type solid)
			)
			(fill no)
			(layer "F.CrtYd")
		)
		(fp_line
			(start -2.74 -2.84)
			(end 2.74 -2.84)
			(stroke
				(width 0.15)
				(type solid)
			)
			(layer "F.Fab")
		)
		(fp_line
			(start -2.74 2.84)
			(end -2.74 -2.84)
			(stroke
				(width 0.15)
				(type solid)
			)
			(layer "F.Fab")
		)
		(fp_line
			(start 2.74 -2.84)
			(end 2.74 2.84)
			(stroke
				(width 0.15)
				(type solid)
			)
			(layer "F.Fab")
		)
		(fp_line
			(start 2.74 2.84)
			(end -2.74 2.84)
			(stroke
				(width 0.15)
				(type solid)
			)
			(layer "F.Fab")
		)
		(fp_text user "License: Apache-2.0"
			(at -2.89 6.241 0)
			(layer "F.Fab")
			(effects
				(font
					(size 0.7 0.7)
					(thickness 0.15)
				)
				(justify left bottom)
			)
		)
		(fp_text user "Author: Antmicro"
			(at -2.89 7.441 0)
			(layer "F.Fab")
			(effects
				(font
					(size 0.7 0.7)
					(thickness 0.15)
				)
				(justify left bottom)
			)
		)
		(fp_text user "${REFERENCE}"
			(at -2.89 8.641 0)
			(layer "F.Fab")
			(effects
				(font
					(size 0.7 0.7)
					(thickness 0.15)
				)
				(justify left bottom)
			)
		)
		(pad "1" smd roundrect
			(at -1.655 0)
			(size 1.18 4.7)
			(layers "F.Cu" "F.Mask" "F.Paste")
			(roundrect_rratio 0.1)
			(net 163 "Net-(U2-SW)")
			(pintype "passive")
		)
		(pad "2" smd roundrect
			(at 1.655 0)
			(size 1.18 4.7)
			(layers "F.Cu" "F.Mask" "F.Paste")
			(roundrect_rratio 0.1)
			(net 399 "Net-(D4-A)")
			(pintype "passive")
		)
	)
	(footprint "antmicro-footprints:R_0402_1005Metric"
		(layer "F.Cu")
		(at 117 65.5 180)
		(descr "Resistor SMD 0402")
		(tags "resistor SMD 0402")
		(property "Reference" "R131"
			(at -3 -1.4 180)
			(layer "F.SilkS")
			(effects
				(font
					(size 0.7 0.7)
					(thickness 0.15)
				)
				(justify left bottom)
			)
		)
		(property "Value" "R_1k_0402"
			(at -1.011843 1.772047 180)
			(layer "F.Fab")
			(effects
				(font
					(size 0.7 0.7)
					(thickness 0.15)
				)
				(justify left bottom)
			)
		)
		(property "Datasheet" "https://www.bourns.com/docs/product-datasheets/cr.pdf"
			(at 0 0 180)
			(layer "F.Fab")
			(hide yes)
			(effects
				(font
					(size 1.27 1.27)
					(thickness 0.15)
				)
			)
		)
		(property "Description" "SMD Chip Resistor, 1 kohm, ± 1%, 63 mW, 0402 [1005 Metric], Thick Film, General Purpose"
			(at 0 0 180)
			(layer "F.Fab")
			(hide yes)
			(effects
				(font
					(size 1.27 1.27)
					(thickness 0.15)
				)
			)
		)
		(property "MPN" "CR0402-FX-1001GLF"
			(at 0 0 180)
			(unlocked yes)
			(layer "F.Fab")
			(hide yes)
			(effects
				(font
					(size 1 1)
					(thickness 0.15)
				)
			)
		)
		(property "Manufacturer" "Bourns"
			(at 0 0 180)
			(unlocked yes)
			(layer "F.Fab")
			(hide yes)
			(effects
				(font
					(size 1 1)
					(thickness 0.15)
				)
			)
		)
		(property "License" "Apache-2.0"
			(at 0 0 180)
			(unlocked yes)
			(layer "F.Fab")
			(hide yes)
			(effects
				(font
					(size 1 1)
					(thickness 0.15)
				)
			)
		)
		(property "Author" "Antmicro"
			(at 0 0 180)
			(unlocked yes)
			(layer "F.Fab")
			(hide yes)
			(effects
				(font
					(size 1 1)
					(thickness 0.15)
				)
			)
		)
		(property "Val" "1k"
			(at 0 0 180)
			(unlocked yes)
			(layer "F.Fab")
			(hide yes)
			(effects
				(font
					(size 1 1)
					(thickness 0.15)
				)
			)
		)
		(property "Tolerance" "1%"
			(at 0 0 180)
			(unlocked yes)
			(layer "F.Fab")
			(hide yes)
			(effects
				(font
					(size 1 1)
					(thickness 0.15)
				)
			)
		)
		(sheetname "/X710-AT2 RSVD/")
		(sheetfile "x710-at2-rsvd.kicad_sch")
		(attr smd)
		(fp_rect
			(start -0.925 -0.47)
			(end 0.925 0.47)
			(stroke
				(width 0.05)
				(type default)
			)
			(fill no)
			(layer "F.CrtYd")
		)
		(fp_rect
			(start -0.5 -0.25)
			(end 0.5 0.25)
			(stroke
				(width 0.15)
				(type solid)
			)
			(fill no)
			(layer "F.Fab")
		)
		(fp_text user "Author: Antmicro"
			(at -0.95 4.169 180)
			(layer "F.Fab")
			(effects
				(font
					(size 0.7 0.7)
					(thickness 0.15)
				)
				(justify left bottom)
			)
		)
		(fp_text user "${REFERENCE}"
			(at -0.95 3.168 180)
			(layer "F.Fab")
			(effects
				(font
					(size 0.7 0.7)
					(thickness 0.15)
				)
				(justify left bottom)
			)
		)
		(fp_text user "License: Apache-2.0"
			(at -0.95 5.169 180)
			(layer "F.Fab")
			(effects
				(font
					(size 0.7 0.7)
					(thickness 0.15)
				)
				(justify left bottom)
			)
		)
		(pad "1" smd roundrect
			(at -0.48 0 180)
			(size 0.59 0.64)
			(layers "F.Cu" "F.Mask" "F.Paste")
			(roundrect_rratio 0.25)
			(net 89 "/X710-AT2 RSVD/DEBUG_Y20")
			(pintype "passive")
		)
		(pad "2" smd roundrect
			(at 0.48 0 180)
			(size 0.59 0.64)
			(layers "F.Cu" "F.Mask" "F.Paste")
			(roundrect_rratio 0.25)
			(net 86 "/X710-AT2 RSVD/DEBUG_EN")
			(pintype "passive")
		)
	)
	(footprint "antmicro-footprints:C_0805_2012Metric"
		(layer "F.Cu")
		(at 151.1 56.8 -90)
		(descr "Capacitor SMD 0805")
		(tags "capacitor SMD 0805")
		(property "Reference" "C320"
			(at 4.6 -0.65 270)
			(layer "F.SilkS")
			(effects
				(font
					(size 0.7 0.7)
					(thickness 0.15)
				)
				(justify left bottom)
			)
		)
		(property "Value" "C_22u_25V_0805"
			(at -2.055717 1.963152 270)
			(layer "F.Fab")
			(effects
				(font
					(size 0.7 0.7)
					(thickness 0.15)
				)
				(justify left bottom)
			)
		)
		(property "Datasheet" "https://product.samsungsem.com/mlcc/CL21A226MAYNNN.do"
			(at 0 0 270)
			(layer "F.Fab")
			(hide yes)
			(effects
				(font
					(size 1.27 1.27)
					(thickness 0.15)
				)
			)
		)
		(property "Description" "SMT Multilayer Ceramic Capacitor, 22uF, +/-20%, 25V, X5R, 0805 [2012 Metric]"
			(at 0 0 270)
			(layer "F.Fab")
			(hide yes)
			(effects
				(font
					(size 1.27 1.27)
					(thickness 0.15)
				)
			)
		)
		(property "MPN" "CL21A226MAYNNNE"
			(at 0 0 270)
			(unlocked yes)
			(layer "F.Fab")
			(hide yes)
			(effects
				(font
					(size 1 1)
					(thickness 0.15)
				)
			)
		)
		(property "Manufacturer" "Samsung Electro-Mechanics"
			(at 0 0 270)
			(unlocked yes)
			(layer "F.Fab")
			(hide yes)
			(effects
				(font
					(size 1 1)
					(thickness 0.15)
				)
			)
		)
		(property "License" "Apache-2.0"
			(at 0 0 270)
			(unlocked yes)
			(layer "F.Fab")
			(hide yes)
			(effects
				(font
					(size 1 1)
					(thickness 0.15)
				)
			)
		)
		(property "Author" "Antmicro"
			(at 0 0 270)
			(unlocked yes)
			(layer "F.Fab")
			(hide yes)
			(effects
				(font
					(size 1 1)
					(thickness 0.15)
				)
			)
		)
		(property "Val" "22u"
			(at 0 0 270)
			(unlocked yes)
			(layer "F.Fab")
			(hide yes)
			(effects
				(font
					(size 1 1)
					(thickness 0.15)
				)
			)
		)
		(property "Voltage" "25V"
			(at 0 0 270)
			(unlocked yes)
			(layer "F.Fab")
			(hide yes)
			(effects
				(font
					(size 1 1)
					(thickness 0.15)
				)
			)
		)
		(property "Dielectric" "X5R"
			(at 0 0 270)
			(unlocked yes)
			(layer "F.Fab")
			(hide yes)
			(effects
				(font
					(size 1 1)
					(thickness 0.15)
				)
			)
		)
		(property "Public" "False"
			(at 0 0 270)
			(unlocked yes)
			(layer "F.Fab")
			(hide yes)
			(effects
				(font
					(size 1 1)
					(thickness 0.15)
				)
			)
		)
		(sheetname "/Power input/")
		(sheetfile "power_input.kicad_sch")
		(attr smd)
		(fp_line
			(start -0.3 0.7)
			(end 0.3 0.7)
			(stroke
				(width 0.15)
				(type solid)
			)
			(layer "F.SilkS")
		)
		(fp_line
			(start -0.3 -0.7)
			(end 0.3 -0.7)
			(stroke
				(width 0.15)
				(type solid)
			)
			(layer "F.SilkS")
		)
		(fp_rect
			(start 1.95 -0.9)
			(end -1.95 0.9)
			(stroke
				(width 0.05)
				(type default)
			)
			(fill no)
			(layer "F.CrtYd")
		)
		(fp_rect
			(start -0.95 -0.675)
			(end 0.95 0.675)
			(stroke
				(width 0.15)
				(type solid)
			)
			(fill no)
			(layer "F.Fab")
		)
		(fp_text user "${REFERENCE}"
			(at -1.9 3.947 270)
			(layer "F.Fab")
			(effects
				(font
					(size 0.7 0.7)
					(thickness 0.15)
				)
				(justify left bottom)
			)
		)
		(fp_text user "License: Apache-2.0"
			(at -1.9 4.947 270)
			(layer "F.Fab")
			(effects
				(font
					(size 0.7 0.7)
					(thickness 0.15)
				)
				(justify left bottom)
			)
		)
		(fp_text user "Author: Antmicro"
			(at -1.9 5.947 270)
			(layer "F.Fab")
			(effects
				(font
					(size 0.7 0.7)
					(thickness 0.15)
				)
				(justify left bottom)
			)
		)
		(pad "1" smd roundrect
			(at -1.1 0 270)
			(size 1.2 1.3)
			(layers "F.Cu" "F.Mask" "F.Paste")
			(roundrect_rratio 0.25)
			(net 23 "GND")
			(pintype "passive")
		)
		(pad "2" smd roundrect
			(at 1.1 0 270)
			(size 1.2 1.3)
			(layers "F.Cu" "F.Mask" "F.Paste")
			(roundrect_rratio 0.25)
			(net 349 "/Power input/5V_OUT")
			(pintype "passive")
		)
	)
	(footprint "antmicro-footprints:C_0402_1005Metric"
		(layer "F.Cu")
		(at 138 75.75)
		(descr "Capacitor SMD 0402")
		(tags "capacitor SMD 0402")
		(property "Reference" "C267"
			(at -3.8 0.45 0)
			(layer "F.SilkS")
			(effects
				(font
					(size 0.7 0.7)
					(thickness 0.15)
				)
				(justify left bottom)
			)
		)
		(property "Value" "C_220n_16V_0402"
			(at -1.022927 2.155213 0)
			(layer "F.Fab")
			(effects
				(font
					(size 0.7 0.7)
					(thickness 0.15)
				)
				(justify left bottom)
			)
		)
		(property "Datasheet" "https://www.murata.com/products/productdetail?partno=GRM155R71C224KA12%23"
			(at 0 0 0)
			(layer "F.Fab")
			(hide yes)
			(effects
				(font
					(size 1.27 1.27)
					(thickness 0.15)
				)
			)
		)
		(property "Description" "SMD Multilayer Ceramic Capacitor, 0.22 µF, 16 V, 0402 [1005 Metric], ± 10%, X7R, GRM Series"
			(at 0 0 0)
			(layer "F.Fab")
			(hide yes)
			(effects
				(font
					(size 1.27 1.27)
					(thickness 0.15)
				)
			)
		)
		(property "MPN" "GRM155R71C224KA12D"
			(at 0 0 0)
			(unlocked yes)
			(layer "F.Fab")
			(hide yes)
			(effects
				(font
					(size 1 1)
					(thickness 0.15)
				)
			)
		)
		(property "Manufacturer" "Murata"
			(at 0 0 0)
			(unlocked yes)
			(layer "F.Fab")
			(hide yes)
			(effects
				(font
					(size 1 1)
					(thickness 0.15)
				)
			)
		)
		(property "License" "Apache-2.0"
			(at 0 0 0)
			(unlocked yes)
			(layer "F.Fab")
			(hide yes)
			(effects
				(font
					(size 1 1)
					(thickness 0.15)
				)
			)
		)
		(property "Author" "Antmicro"
			(at 0 0 0)
			(unlocked yes)
			(layer "F.Fab")
			(hide yes)
			(effects
				(font
					(size 1 1)
					(thickness 0.15)
				)
			)
		)
		(property "Val" "220n"
			(at 0 0 0)
			(unlocked yes)
			(layer "F.Fab")
			(hide yes)
			(effects
				(font
					(size 1 1)
					(thickness 0.15)
				)
			)
		)
		(property "Voltage" "16V"
			(at 0 0 0)
			(unlocked yes)
			(layer "F.Fab")
			(hide yes)
			(effects
				(font
					(size 1 1)
					(thickness 0.15)
				)
			)
		)
		(property "Dielectric" "X7R"
			(at 0 0 0)
			(unlocked yes)
			(layer "F.Fab")
			(hide yes)
			(effects
				(font
					(size 1 1)
					(thickness 0.15)
				)
			)
		)
		(sheetname "/X710-AT2 PCIe/")
		(sheetfile "x710-at2-pcie.kicad_sch")
		(attr smd)
		(fp_rect
			(start -0.925 -0.47)
			(end 0.925 0.47)
			(stroke
				(width 0.05)
				(type default)
			)
			(fill no)
			(layer "F.CrtYd")
		)
		(fp_line
			(start -0.494 -0.25)
			(end 0.504 -0.25)
			(stroke
				(width 0.15)
				(type solid)
			)
			(layer "F.Fab")
		)
		(fp_line
			(start -0.494 0.248)
			(end -0.494 -0.25)
			(stroke
				(width 0.15)
				(type solid)
			)
			(layer "F.Fab")
		)
		(fp_line
			(start 0.504 -0.25)
			(end 0.504 0.248)
			(stroke
				(width 0.15)
				(type solid)
			)
			(layer "F.Fab")
		)
		(fp_line
			(start 0.504 0.248)
			(end -0.494 0.248)
			(stroke
				(width 0.15)
				(type solid)
			)
			(layer "F.Fab")
		)
		(fp_text user "License: Apache-2.0"
			(at -0.939 5.799 0)
			(layer "F.Fab")
			(effects
				(font
					(size 0.7 0.7)
					(thickness 0.15)
				)
				(justify left bottom)
			)
		)
		(fp_text user "${REFERENCE}"
			(at -0.939 4.599 0)
			(layer "F.Fab")
			(effects
				(font
					(size 0.7 0.7)
					(thickness 0.15)
				)
				(justify left bottom)
			)
		)
		(fp_text user "Author: Antmicro"
			(at -0.939 3.399 0)
			(layer "F.Fab")
			(effects
				(font
					(size 0.7 0.7)
					(thickness 0.15)
				)
				(justify left bottom)
			)
		)
		(pad "1" smd roundrect
			(at -0.48 0)
			(size 0.59 0.64)
			(layers "F.Cu" "F.Mask" "F.Paste")
			(roundrect_rratio 0.25)
			(net 599 "/TB Controller/PCIex4.TX1-")
			(pintype "passive")
		)
		(pad "2" smd roundrect
			(at 0.48 0)
			(size 0.59 0.64)
			(layers "F.Cu" "F.Mask" "F.Paste")
			(roundrect_rratio 0.25)
			(net 30 "/X710-AT2 PCIe/PCIe_{x4}_AC.TX1-")
			(pintype "passive")
		)
	)
	(footprint "antmicro-footprints:SOT-23-3"
		(layer "F.Cu")
		(at 155 117.5 180)
		(property "Reference" "Q6"
			(at 2.4 0.5 180)
			(layer "F.SilkS")
			(effects
				(font
					(size 0.7 0.7)
					(thickness 0.15)
				)
				(justify left bottom)
			)
		)
		(property "Value" "2N7002_SOT-23-3"
			(at -1.9 2.7 180)
			(layer "F.Fab")
			(effects
				(font
					(size 0.7 0.7)
					(thickness 0.15)
				)
				(justify left bottom)
			)
		)
		(property "Datasheet" "https://www.onsemi.com/pub/Collateral/NDS7002A-D.PDF"
			(at 0 0 180)
			(layer "F.Fab")
			(hide yes)
			(effects
				(font
					(size 1.27 1.27)
					(thickness 0.15)
				)
			)
		)
		(property "Description" "Power MOSFET, N Channel, 60 V, 115 mA, 1.2 ohm, SOT-23, Surface Mount"
			(at 0 0 180)
			(layer "F.Fab")
			(hide yes)
			(effects
				(font
					(size 1.27 1.27)
					(thickness 0.15)
				)
			)
		)
		(property "MPN" "2N7002"
			(at 0 0 180)
			(unlocked yes)
			(layer "F.Fab")
			(hide yes)
			(effects
				(font
					(size 1 1)
					(thickness 0.15)
				)
			)
		)
		(property "Manufacturer" "ON Semiconductor"
			(at 0 0 180)
			(unlocked yes)
			(layer "F.Fab")
			(hide yes)
			(effects
				(font
					(size 1 1)
					(thickness 0.15)
				)
			)
		)
		(property "Author" "Antmicro"
			(at 0 0 180)
			(unlocked yes)
			(layer "F.Fab")
			(hide yes)
			(effects
				(font
					(size 1 1)
					(thickness 0.15)
				)
			)
		)
		(property "License" "Apache-2.0"
			(at 0 0 180)
			(unlocked yes)
			(layer "F.Fab")
			(hide yes)
			(effects
				(font
					(size 1 1)
					(thickness 0.15)
				)
			)
		)
		(sheetname "/X710 DCDC converters/")
		(sheetfile "DCDC_converters_X710.kicad_sch")
		(attr smd)
		(fp_line
			(start 0.7 1.5)
			(end -0.7 1.5)
			(stroke
				(width 0.15)
				(type solid)
			)
			(layer "F.SilkS")
		)
		(fp_line
			(start 0.7 0.4)
			(end 0.7 1.5)
			(stroke
				(width 0.15)
				(type solid)
			)
			(layer "F.SilkS")
		)
		(fp_line
			(start 0.7 -0.4)
			(end 0.7 -1.5)
			(stroke
				(width 0.15)
				(type solid)
			)
			(layer "F.SilkS")
		)
		(fp_line
			(start 0.7 -1.5)
			(end -0.7 -1.5)
			(stroke
				(width 0.15)
				(type solid)
			)
			(layer "F.SilkS")
		)
		(fp_line
			(start -0.7 1.5)
			(end -0.7 1.35)
			(stroke
				(width 0.15)
				(type solid)
			)
			(layer "F.SilkS")
		)
		(fp_line
			(start -0.85 -1.35)
			(end -0.7 -1.5)
			(stroke
				(width 0.15)
				(type solid)
			)
			(layer "F.SilkS")
		)
		(fp_line
			(start -1.45 -1.35)
			(end -0.85 -1.35)
			(stroke
				(width 0.15)
				(type solid)
			)
			(layer "F.SilkS")
		)
		(fp_line
			(start 1.75 0.45)
			(end 0.85 0.45)
			(stroke
				(width 0.05)
				(type solid)
			)
			(layer "F.CrtYd")
		)
		(fp_line
			(start 1.75 -0.45)
			(end 1.75 0.45)
			(stroke
				(width 0.05)
				(type solid)
			)
			(layer "F.CrtYd")
		)
		(fp_line
			(start 0.85 1.65)
			(end -0.85 1.65)
			(stroke
				(width 0.05)
				(type solid)
			)
			(layer "F.CrtYd")
		)
		(fp_line
			(start 0.85 0.45)
			(end 0.85 1.65)
			(stroke
				(width 0.05)
				(type solid)
			)
			(layer "F.CrtYd")
		)
		(fp_line
			(start 0.825 -0.45)
			(end 1.75 -0.45)
			(stroke
				(width 0.05)
				(type solid)
			)
			(layer "F.CrtYd")
		)
		(fp_line
			(start 0.825 -1.6)
			(end 0.825 -0.45)
			(stroke
				(width 0.05)
				(type solid)
			)
			(layer "F.CrtYd")
		)
		(fp_line
			(start -0.85 1.65)
			(end -0.85 1.4)
			(stroke
				(width 0.05)
				(type solid)
			)
			(layer "F.CrtYd")
		)
		(fp_line
			(start -0.85 1.4)
			(end -1.75 1.4)
			(stroke
				(width 0.05)
				(type solid)
			)
			(layer "F.CrtYd")
		)
		(fp_line
			(start -0.85 0.5)
			(end -0.85 -0.5)
			(stroke
				(width 0.05)
				(type solid)
			)
			(layer "F.CrtYd")
		)
		(fp_line
			(start -0.85 -0.5)
			(end -1.75 -0.5)
			(stroke
				(width 0.05)
				(type solid)
			)
			(layer "F.CrtYd")
		)
		(fp_line
			(start -0.9 -1.4)
			(end -1.75 -1.4)
			(stroke
				(width 0.05)
				(type solid)
			)
			(layer "F.CrtYd")
		)
		(fp_line
			(start -0.9 -1.6)
			(end 0.825 -1.6)
			(stroke
				(width 0.05)
				(type solid)
			)
			(layer "F.CrtYd")
		)
		(fp_line
			(start -0.9 -1.6)
			(end -0.9 -1.4)
			(stroke
				(width 0.05)
				(type solid)
			)
			(layer "F.CrtYd")
		)
		(fp_line
			(start -1.75 1.4)
			(end -1.75 0.5)
			(stroke
				(width 0.05)
				(type solid)
			)
			(layer "F.CrtYd")
		)
		(fp_line
			(start -1.75 0.5)
			(end -0.85 0.5)
			(stroke
				(width 0.05)
				(type solid)
			)
			(layer "F.CrtYd")
		)
		(fp_line
			(start -1.75 -0.5)
			(end -1.75 -1.4)
			(stroke
				(width 0.05)
				(type solid)
			)
			(layer "F.CrtYd")
		)
		(fp_line
			(start 0.688 1.519)
			(end 0.688 -1.52)
			(stroke
				(width 0.15)
				(type solid)
			)
			(layer "F.Fab")
		)
		(fp_line
			(start -0.437 -1.526)
			(end 0.688 -1.526)
			(stroke
				(width 0.15)
				(type solid)
			)
			(layer "F.Fab")
		)
		(fp_line
			(start -0.437 -1.526)
			(end -0.712 -1.325)
			(stroke
				(width 0.15)
				(type solid)
			)
			(layer "F.Fab")
		)
		(fp_line
			(start -0.712 1.519)
			(end 0.688 1.519)
			(stroke
				(width 0.15)
				(type solid)
			)
			(layer "F.Fab")
		)
		(fp_line
			(start -0.712 -1.325)
			(end -0.712 1.523)
			(stroke
				(width 0.15)
				(type solid)
			)
			(layer "F.Fab")
		)
		(fp_text user "Author: Antmicro"
			(at -1.837 5.3 180)
			(layer "F.Fab")
			(effects
				(font
					(size 0.7 0.7)
					(thickness 0.15)
				)
				(justify left bottom)
			)
		)
		(fp_text user "${REFERENCE}"
			(at -1.837 4 180)
			(layer "F.Fab")
			(effects
				(font
					(size 0.7 0.7)
					(thickness 0.15)
				)
				(justify left bottom)
			)
		)
		(fp_text user "License: Apache-2.0"
			(at -1.8 6.8 180)
			(layer "F.Fab")
			(effects
				(font
					(size 0.7 0.7)
					(thickness 0.15)
				)
				(justify left bottom)
			)
		)
		(pad "1" smd roundrect
			(at -1.1 -0.951 180)
			(size 1 0.6)
			(layers "F.Cu" "F.Mask" "F.Paste")
			(roundrect_rratio 0.15)
			(net 355 "/X710 DCDC converters/DVDD_PG")
			(pinfunction "G")
			(pintype "input")
		)
		(pad "2" smd roundrect
			(at -1.1 0.949 180)
			(size 1 0.6)
			(layers "F.Cu" "F.Mask" "F.Paste")
			(roundrect_rratio 0.15)
			(net 23 "GND")
			(pinfunction "S")
			(pintype "passive")
		)
		(pad "3" smd roundrect
			(at 1.1 -0.0005 180)
			(size 1 0.6)
			(layers "F.Cu" "F.Mask" "F.Paste")
			(roundrect_rratio 0.15)
			(net 418 "Net-(D11-C)")
			(pinfunction "D")
			(pintype "passive")
		)
	)
	(footprint "antmicro-footprints:C_0402_1005Metric"
		(layer "F.Cu")
		(at 136.25 93.75)
		(descr "Capacitor SMD 0402")
		(tags "capacitor SMD 0402")
		(property "Reference" "C149"
			(at 37.604999 -9.199999 0)
			(layer "F.SilkS")
			(effects
				(font
					(size 0.7 0.7)
					(thickness 0.15)
				)
			)
		)
		(property "Value" "C_100n_0402"
			(at -1.022927 2.155213 0)
			(layer "F.Fab")
			(effects
				(font
					(size 0.7 0.7)
					(thickness 0.15)
				)
				(justify left bottom)
			)
		)
		(property "Datasheet" "https://www.murata.com/products/productdetail?partno=GRM155R61H104KE14%23"
			(at 0 0 0)
			(layer "F.Fab")
			(hide yes)
			(effects
				(font
					(size 1.27 1.27)
					(thickness 0.15)
				)
			)
		)
		(property "Description" "SMD Multilayer Ceramic Capacitor, 0.1 µF, 50 V, 0402 [1005 Metric], ± 10%, X5R, GRM Series"
			(at 0 0 0)
			(layer "F.Fab")
			(hide yes)
			(effects
				(font
					(size 1.27 1.27)
					(thickness 0.15)
				)
			)
		)
		(property "MPN" "GRM155R61H104KE14D"
			(at 0 0 0)
			(unlocked yes)
			(layer "F.Fab")
			(hide yes)
			(effects
				(font
					(size 1 1)
					(thickness 0.15)
				)
			)
		)
		(property "Manufacturer" "Murata"
			(at 0 0 0)
			(unlocked yes)
			(layer "F.Fab")
			(hide yes)
			(effects
				(font
					(size 1 1)
					(thickness 0.15)
				)
			)
		)
		(property "License" "Apache-2.0"
			(at 0 0 0)
			(unlocked yes)
			(layer "F.Fab")
			(hide yes)
			(effects
				(font
					(size 1 1)
					(thickness 0.15)
				)
			)
		)
		(property "Author" "Antmicro"
			(at 0 0 0)
			(unlocked yes)
			(layer "F.Fab")
			(hide yes)
			(effects
				(font
					(size 1 1)
					(thickness 0.15)
				)
			)
		)
		(property "Val" "100n"
			(at 0 0 0)
			(unlocked yes)
			(layer "F.Fab")
			(hide yes)
			(effects
				(font
					(size 1 1)
					(thickness 0.15)
				)
			)
		)
		(property "Voltage" "50V"
			(at 0 0 0)
			(unlocked yes)
			(layer "F.Fab")
			(hide yes)
			(effects
				(font
					(size 1 1)
					(thickness 0.15)
				)
			)
		)
		(property "Dielectric" "X5R"
			(at 0 0 0)
			(unlocked yes)
			(layer "F.Fab")
			(hide yes)
			(effects
				(font
					(size 1 1)
					(thickness 0.15)
				)
			)
		)
		(sheetname "/X710 DCDC converters/")
		(sheetfile "DCDC_converters_X710.kicad_sch")
		(attr smd)
		(fp_rect
			(start -0.925 -0.47)
			(end 0.925 0.47)
			(stroke
				(width 0.05)
				(type default)
			)
			(fill no)
			(layer "F.CrtYd")
		)
		(fp_line
			(start -0.494 -0.25)
			(end 0.504 -0.25)
			(stroke
				(width 0.15)
				(type solid)
			)
			(layer "F.Fab")
		)
		(fp_line
			(start -0.494 0.248)
			(end -0.494 -0.25)
			(stroke
				(width 0.15)
				(type solid)
			)
			(layer "F.Fab")
		)
		(fp_line
			(start 0.504 -0.25)
			(end 0.504 0.248)
			(stroke
				(width 0.15)
				(type solid)
			)
			(layer "F.Fab")
		)
		(fp_line
			(start 0.504 0.248)
			(end -0.494 0.248)
			(stroke
				(width 0.15)
				(type solid)
			)
			(layer "F.Fab")
		)
		(fp_text user "${REFERENCE}"
			(at -0.939 4.599 0)
			(layer "F.Fab")
			(effects
				(font
					(size 0.7 0.7)
					(thickness 0.15)
				)
				(justify left bottom)
			)
		)
		(fp_text user "Author: Antmicro"
			(at -0.939 3.399 0)
			(layer "F.Fab")
			(effects
				(font
					(size 0.7 0.7)
					(thickness 0.15)
				)
				(justify left bottom)
			)
		)
		(fp_text user "License: Apache-2.0"
			(at -0.939 5.799 0)
			(layer "F.Fab")
			(effects
				(font
					(size 0.7 0.7)
					(thickness 0.15)
				)
				(justify left bottom)
			)
		)
		(pad "1" smd roundrect
			(at -0.48 0)
			(size 0.59 0.64)
			(layers "F.Cu" "F.Mask" "F.Paste")
			(roundrect_rratio 0.25)
			(net 23 "GND")
			(pintype "passive")
		)
		(pad "2" smd roundrect
			(at 0.48 0)
			(size 0.59 0.64)
			(layers "F.Cu" "F.Mask" "F.Paste")
			(roundrect_rratio 0.25)
			(net 334 "/X710 DCDC converters/+3V3_OUT")
			(pintype "passive")
		)
	)
	(footprint "antmicro-footprints:C_0603_1608Metric"
		(layer "F.Cu")
		(at 122.15 106.1)
		(descr "Capacitor SMD 0603")
		(tags "capacitor 0603")
		(property "Reference" "C27"
			(at 2.35 -1.1 0)
			(layer "F.SilkS")
			(effects
				(font
					(size 0.7 0.7)
					(thickness 0.15)
				)
			)
		)
		(property "Value" "C_22u_0603"
			(at -1.42757 1.770288 0)
			(layer "F.Fab")
			(effects
				(font
					(size 0.7 0.7)
					(thickness 0.15)
				)
				(justify left bottom)
			)
		)
		(property "Datasheet" "https://www.murata.com/products/productdetail?partno=GRM188R60J226MEA0%23"
			(at 0 0 0)
			(layer "F.Fab")
			(hide yes)
			(effects
				(font
					(size 1.27 1.27)
					(thickness 0.15)
				)
			)
		)
		(property "Description" "SMD Multilayer Ceramic Capacitor, 22 µF, 6.3 V, 0603 [1608 Metric], ± 20%, X5R, GRM Series"
			(at 0 0 0)
			(layer "F.Fab")
			(hide yes)
			(effects
				(font
					(size 1.27 1.27)
					(thickness 0.15)
				)
			)
		)
		(property "MPN" "GRM188R60J226MEA0D"
			(at 0 0 0)
			(unlocked yes)
			(layer "F.Fab")
			(hide yes)
			(effects
				(font
					(size 1 1)
					(thickness 0.15)
				)
			)
		)
		(property "Manufacturer" "Murata"
			(at 0 0 0)
			(unlocked yes)
			(layer "F.Fab")
			(hide yes)
			(effects
				(font
					(size 1 1)
					(thickness 0.15)
				)
			)
		)
		(property "License" "Apache-2.0"
			(at 0 0 0)
			(unlocked yes)
			(layer "F.Fab")
			(hide yes)
			(effects
				(font
					(size 1 1)
					(thickness 0.15)
				)
			)
		)
		(property "Val" "22u"
			(at 0 0 0)
			(unlocked yes)
			(layer "F.Fab")
			(hide yes)
			(effects
				(font
					(size 1 1)
					(thickness 0.15)
				)
			)
		)
		(property "Voltage" ""
			(at 0 0 0)
			(unlocked yes)
			(layer "F.Fab")
			(hide yes)
			(effects
				(font
					(size 1 1)
					(thickness 0.15)
				)
			)
		)
		(property "Dielectric" ""
			(at 0 0 0)
			(unlocked yes)
			(layer "F.Fab")
			(hide yes)
			(effects
				(font
					(size 1 1)
					(thickness 0.15)
				)
			)
		)
		(property "Author" "Antmicro"
			(at 0 0 0)
			(unlocked yes)
			(layer "F.Fab")
			(hide yes)
			(effects
				(font
					(size 1 1)
					(thickness 0.15)
				)
			)
		)
		(sheetname "/PD and TB DC-DC/")
		(sheetfile "PD_and_TB_DC_DC.kicad_sch")
		(attr smd)
		(fp_line
			(start -0.15 -0.4)
			(end 0.15 -0.4)
			(stroke
				(width 0.15)
				(type solid)
			)
			(layer "F.SilkS")
		)
		(fp_line
			(start -0.15 0.4)
			(end 0.15 0.4)
			(stroke
				(width 0.15)
				(type solid)
			)
			(layer "F.SilkS")
		)
		(fp_rect
			(start -1.25 -0.65)
			(end 1.25 0.65)
			(stroke
				(width 0.05)
				(type solid)
			)
			(fill no)
			(layer "F.CrtYd")
		)
		(fp_rect
			(start -0.8 -0.4)
			(end 0.8 0.4)
			(stroke
				(width 0.15)
				(type solid)
			)
			(fill no)
			(layer "F.Fab")
		)
		(fp_text user "${REFERENCE}"
			(at -1.682 3.895 0)
			(layer "F.Fab")
			(effects
				(font
					(size 0.7 0.7)
					(thickness 0.15)
				)
				(justify left bottom)
			)
		)
		(fp_text user "License: Apache-2.0"
			(at -1.682 5.895 0)
			(layer "F.Fab")
			(effects
				(font
					(size 0.7 0.7)
					(thickness 0.15)
				)
				(justify left bottom)
			)
		)
		(fp_text user "Author: Antmicro"
			(at -1.682 4.894 0)
			(layer "F.Fab")
			(effects
				(font
					(size 0.7 0.7)
					(thickness 0.15)
				)
				(justify left bottom)
			)
		)
		(pad "1" smd roundrect
			(at -0.7 0)
			(size 0.8 1)
			(layers "F.Cu" "F.Mask" "F.Paste")
			(roundrect_rratio 0.2)
			(net 23 "GND")
			(pintype "passive")
		)
		(pad "2" smd roundrect
			(at 0.7 0)
			(size 0.8 1)
			(layers "F.Cu" "F.Mask" "F.Paste")
			(roundrect_rratio 0.2)
			(net 399 "Net-(D4-A)")
			(pintype "passive")
		)
	)
	(footprint "antmicro-footprints:C_0603_1608Metric"
		(layer "F.Cu")
		(at 151.955 94.024999)
		(descr "Capacitor SMD 0603")
		(tags "capacitor 0603")
		(property "Reference" "C172"
			(at 23.294999 19.625001 0)
			(layer "F.SilkS")
			(effects
				(font
					(size 0.7 0.7)
					(thickness 0.15)
				)
			)
		)
		(property "Value" "C_47u_0603"
			(at -1.42757 1.770288 0)
			(layer "F.Fab")
			(effects
				(font
					(size 0.7 0.7)
					(thickness 0.15)
				)
				(justify left bottom)
			)
		)
		(property "Datasheet" "https://www.murata.com/products/productdetail?partno=GRM188R60J476ME15%23"
			(at 0 0 0)
			(layer "F.Fab")
			(hide yes)
			(effects
				(font
					(size 1.27 1.27)
					(thickness 0.15)
				)
			)
		)
		(property "Description" "SMD Multilayer Ceramic Capacitor, 47 µF, 6.3 V, 0603 [1608 Metric], ± 20%, X5R, GRM Series"
			(at 0 0 0)
			(layer "F.Fab")
			(hide yes)
			(effects
				(font
					(size 1.27 1.27)
					(thickness 0.15)
				)
			)
		)
		(property "MPN" "GRM188R60J476ME15D"
			(at 0 0 0)
			(unlocked yes)
			(layer "F.Fab")
			(hide yes)
			(effects
				(font
					(size 1 1)
					(thickness 0.15)
				)
			)
		)
		(property "Manufacturer" "Murata"
			(at 0 0 0)
			(unlocked yes)
			(layer "F.Fab")
			(hide yes)
			(effects
				(font
					(size 1 1)
					(thickness 0.15)
				)
			)
		)
		(property "License" "Apache-2.0"
			(at 0 0 0)
			(unlocked yes)
			(layer "F.Fab")
			(hide yes)
			(effects
				(font
					(size 1 1)
					(thickness 0.15)
				)
			)
		)
		(property "Author" "Antmicro"
			(at 0 0 0)
			(unlocked yes)
			(layer "F.Fab")
			(hide yes)
			(effects
				(font
					(size 1 1)
					(thickness 0.15)
				)
			)
		)
		(property "Val" "47u"
			(at 0 0 0)
			(unlocked yes)
			(layer "F.Fab")
			(hide yes)
			(effects
				(font
					(size 1 1)
					(thickness 0.15)
				)
			)
		)
		(property "Voltage" ""
			(at 0 0 0)
			(unlocked yes)
			(layer "F.Fab")
			(hide yes)
			(effects
				(font
					(size 1 1)
					(thickness 0.15)
				)
			)
		)
		(property "Dielectric" ""
			(at 0 0 0)
			(unlocked yes)
			(layer "F.Fab")
			(hide yes)
			(effects
				(font
					(size 1 1)
					(thickness 0.15)
				)
			)
		)
		(sheetname "/X710-AT2 power/")
		(sheetfile "x710-at2-power.kicad_sch")
		(attr smd)
		(fp_line
			(start -0.15 -0.4)
			(end 0.15 -0.4)
			(stroke
				(width 0.15)
				(type solid)
			)
			(layer "F.SilkS")
		)
		(fp_line
			(start -0.15 0.4)
			(end 0.15 0.4)
			(stroke
				(width 0.15)
				(type solid)
			)
			(layer "F.SilkS")
		)
		(fp_rect
			(start -1.25 -0.65)
			(end 1.25 0.65)
			(stroke
				(width 0.05)
				(type solid)
			)
			(fill no)
			(layer "F.CrtYd")
		)
		(fp_rect
			(start -0.8 -0.4)
			(end 0.8 0.4)
			(stroke
				(width 0.15)
				(type solid)
			)
			(fill no)
			(layer "F.Fab")
		)
		(fp_text user "License: Apache-2.0"
			(at -1.682 5.895 0)
			(layer "F.Fab")
			(effects
				(font
					(size 0.7 0.7)
					(thickness 0.15)
				)
				(justify left bottom)
			)
		)
		(fp_text user "Author: Antmicro"
			(at -1.682 4.894 0)
			(layer "F.Fab")
			(effects
				(font
					(size 0.7 0.7)
					(thickness 0.15)
				)
				(justify left bottom)
			)
		)
		(fp_text user "${REFERENCE}"
			(at -1.682 3.895 0)
			(layer "F.Fab")
			(effects
				(font
					(size 0.7 0.7)
					(thickness 0.15)
				)
				(justify left bottom)
			)
		)
		(pad "1" smd roundrect
			(at -0.7 0)
			(size 0.8 1)
			(layers "F.Cu" "F.Mask" "F.Paste")
			(roundrect_rratio 0.2)
			(net 23 "GND")
			(pintype "passive")
		)
		(pad "2" smd roundrect
			(at 0.7 0)
			(size 0.8 1)
			(layers "F.Cu" "F.Mask" "F.Paste")
			(roundrect_rratio 0.2)
			(net 12 "XFI_VDD")
			(pintype "passive")
		)
	)
	(footprint "antmicro-footprints:TSSOP-8_3x3mm_P0.65mm"
		(layer "F.Cu")
		(at 172 77)
		(property "Reference" "U16"
			(at -3.4 -1.8 0)
			(layer "F.SilkS")
			(effects
				(font
					(size 0.7 0.7)
					(thickness 0.15)
				)
				(justify left bottom)
			)
		)
		(property "Value" "NTS0102_TSSOP"
			(at 0 2.8 0)
			(layer "F.Fab")
			(effects
				(font
					(size 0.7 0.7)
					(thickness 0.15)
				)
				(justify left bottom)
			)
		)
		(property "Datasheet" "https://www.mouser.com/datasheet/2/302/NTS0102-1127324.pdf"
			(at 0 0 0)
			(layer "F.Fab")
			(hide yes)
			(effects
				(font
					(size 1.27 1.27)
					(thickness 0.15)
				)
			)
		)
		(property "Description" "Transceiver, 1.65 V to 3.6 V, TSSOP-8"
			(at 0 0 0)
			(layer "F.Fab")
			(hide yes)
			(effects
				(font
					(size 1.27 1.27)
					(thickness 0.15)
				)
			)
		)
		(property "MPN" "NTS0102DP"
			(at 0 0 0)
			(unlocked yes)
			(layer "F.Fab")
			(hide yes)
			(effects
				(font
					(size 1 1)
					(thickness 0.15)
				)
			)
		)
		(property "Manufacturer" "NXP"
			(at 0 0 0)
			(unlocked yes)
			(layer "F.Fab")
			(hide yes)
			(effects
				(font
					(size 1 1)
					(thickness 0.15)
				)
			)
		)
		(property "Author" "Antmicro"
			(at 0 0 0)
			(unlocked yes)
			(layer "F.Fab")
			(hide yes)
			(effects
				(font
					(size 1 1)
					(thickness 0.15)
				)
			)
		)
		(property "License" "Apache-2.0"
			(at 0 0 0)
			(unlocked yes)
			(layer "F.Fab")
			(hide yes)
			(effects
				(font
					(size 1 1)
					(thickness 0.15)
				)
			)
		)
		(sheetname "/X710-AT2 Misc/")
		(sheetfile "x710-at2-mics.kicad_sch")
		(attr smd)
		(fp_line
			(start -1.55 1.561)
			(end 1.552 1.561)
			(stroke
				(width 0.15)
				(type solid)
			)
			(layer "F.SilkS")
		)
		(fp_line
			(start -1.525 -1.537)
			(end 1.552 -1.539)
			(stroke
				(width 0.15)
				(type solid)
			)
			(layer "F.SilkS")
		)
		(fp_circle
			(center -1.87 -1.4)
			(end -1.82 -1.4)
			(stroke
				(width 0.15)
				(type solid)
			)
			(fill yes)
			(layer "F.SilkS")
		)
		(fp_rect
			(start -3.15 -1.789)
			(end 3.15 1.811)
			(stroke
				(width 0.05)
				(type solid)
			)
			(fill no)
			(layer "F.CrtYd")
		)
		(fp_line
			(start -1.55 -0.937)
			(end -1.55 1.561)
			(stroke
				(width 0.15)
				(type solid)
			)
			(layer "F.Fab")
		)
		(fp_line
			(start -1.55 -0.937)
			(end -0.949 -1.539)
			(stroke
				(width 0.15)
				(type solid)
			)
			(layer "F.Fab")
		)
		(fp_line
			(start -1.55 1.561)
			(end 1.552 1.561)
			(stroke
				(width 0.15)
				(type solid)
			)
			(layer "F.Fab")
		)
		(fp_line
			(start -0.949 -1.539)
			(end 1.552 -1.539)
			(stroke
				(width 0.15)
				(type solid)
			)
			(layer "F.Fab")
		)
		(fp_line
			(start 1.552 -1.539)
			(end 1.552 1.561)
			(stroke
				(width 0.15)
				(type solid)
			)
			(layer "F.Fab")
		)
		(fp_text user "${REFERENCE}"
			(at -1.789 6.58 0)
			(layer "F.Fab")
			(effects
				(font
					(size 0.7 0.7)
					(thickness 0.15)
				)
				(justify left bottom)
			)
		)
		(fp_text user "License: Apache-2.0"
			(at -1.789 8.98 0)
			(layer "F.Fab")
			(effects
				(font
					(size 0.7 0.7)
					(thickness 0.15)
				)
				(justify left bottom)
			)
		)
		(fp_text user "Author: Antmicro"
			(at -1.789 7.78 0)
			(layer "F.Fab")
			(effects
				(font
					(size 0.7 0.7)
					(thickness 0.15)
				)
				(justify left bottom)
			)
		)
		(pad "1" smd roundrect
			(at -2.148 -0.962)
			(size 1.47 0.4)
			(layers "F.Cu" "F.Mask" "F.Paste")
			(roundrect_rratio 0.25)
			(net 122 "/X710-AT2 10GbE/MDIO0_I2C0.MDIO")
			(pinfunction "B_{2}")
			(pintype "bidirectional")
		)
		(pad "2" smd roundrect
			(at -2.148 -0.313)
			(size 1.47 0.4)
			(layers "F.Cu" "F.Mask" "F.Paste")
			(roundrect_rratio 0.25)
			(net 23 "GND")
			(pinfunction "GND")
			(pintype "power_in")
		)
		(pad "3" smd roundrect
			(at -2.148 0.338)
			(size 1.47 0.4)
			(layers "F.Cu" "F.Mask" "F.Paste")
			(roundrect_rratio 0.25)
			(net 18 "+1V88")
			(pinfunction "VCC_{A}")
			(pintype "power_in")
		)
		(pad "4" smd roundrect
			(at -2.148 0.987)
			(size 1.47 0.4)
			(layers "F.Cu" "F.Mask" "F.Paste")
			(roundrect_rratio 0.25)
			(net 147 "/X710-AT2 Misc/MDIO.MDIO")
			(pinfunction "A_{2}")
			(pintype "bidirectional")
		)
		(pad "5" smd roundrect
			(at 2.151 0.987)
			(size 1.47 0.4)
			(layers "F.Cu" "F.Mask" "F.Paste")
			(roundrect_rratio 0.25)
			(net 148 "/X710-AT2 Misc/MDIO.MDC")
			(pinfunction "A_{1}")
			(pintype "bidirectional")
		)
		(pad "6" smd roundrect
			(at 2.151 0.338)
			(size 1.47 0.4)
			(layers "F.Cu" "F.Mask" "F.Paste")
			(roundrect_rratio 0.25)
			(net 18 "+1V88")
			(pinfunction "OE")
			(pintype "input")
		)
		(pad "7" smd roundrect
			(at 2.151 -0.313)
			(size 1.47 0.4)
			(layers "F.Cu" "F.Mask" "F.Paste")
			(roundrect_rratio 0.25)
			(net 7 "+3V3")
			(pinfunction "VCC_{B}")
			(pintype "power_in")
		)
		(pad "8" smd roundrect
			(at 2.151 -0.962)
			(size 1.47 0.4)
			(layers "F.Cu" "F.Mask" "F.Paste")
			(roundrect_rratio 0.25)
			(net 125 "/X710-AT2 10GbE/MDIO0_I2C0.MDC")
			(pinfunction "B_{1}")
			(pintype "bidirectional")
		)
	)
	(footprint "antmicro-footprints:C_0603_1608Metric"
		(layer "F.Cu")
		(at 149.305 94.024999 180)
		(descr "Capacitor SMD 0603")
		(tags "capacitor 0603")
		(property "Reference" "C177"
			(at -23.294999 -19.625001 180)
			(layer "F.SilkS")
			(effects
				(font
					(size 0.7 0.7)
					(thickness 0.15)
				)
			)
		)
		(property "Value" "C_10u_10V_X7R_0603"
			(at -1.42757 1.770288 180)
			(layer "F.Fab")
			(effects
				(font
					(size 0.7 0.7)
					(thickness 0.15)
				)
				(justify left bottom)
			)
		)
		(property "Datasheet" "https://www.murata.com/products/productdetail?partno=GRM188Z71A106KA73%23"
			(at 0 0 180)
			(layer "F.Fab")
			(hide yes)
			(effects
				(font
					(size 1.27 1.27)
					(thickness 0.15)
				)
			)
		)
		(property "Description" "SMD Multilayer Ceramic Capacitor,  10µF, 10V, 0603, ±10%, X7R"
			(at 0 0 180)
			(layer "F.Fab")
			(hide yes)
			(effects
				(font
					(size 1.27 1.27)
					(thickness 0.15)
				)
			)
		)
		(property "MPN" "GRM188Z71A106KA73D"
			(at 0 0 180)
			(unlocked yes)
			(layer "F.Fab")
			(hide yes)
			(effects
				(font
					(size 1 1)
					(thickness 0.15)
				)
			)
		)
		(property "Val" "10u"
			(at 0 0 180)
			(unlocked yes)
			(layer "F.Fab")
			(hide yes)
			(effects
				(font
					(size 1 1)
					(thickness 0.15)
				)
			)
		)
		(property "Voltage" "10V"
			(at 0 0 180)
			(unlocked yes)
			(layer "F.Fab")
			(hide yes)
			(effects
				(font
					(size 1 1)
					(thickness 0.15)
				)
			)
		)
		(property "Dielectric" "X7R"
			(at 0 0 180)
			(unlocked yes)
			(layer "F.Fab")
			(hide yes)
			(effects
				(font
					(size 1 1)
					(thickness 0.15)
				)
			)
		)
		(property "Manufacturer" "Murata"
			(at 0 0 180)
			(unlocked yes)
			(layer "F.Fab")
			(hide yes)
			(effects
				(font
					(size 1 1)
					(thickness 0.15)
				)
			)
		)
		(property "License" "Apache-2.0"
			(at 0 0 180)
			(unlocked yes)
			(layer "F.Fab")
			(hide yes)
			(effects
				(font
					(size 1 1)
					(thickness 0.15)
				)
			)
		)
		(property "Author" "Antmicro"
			(at 0 0 180)
			(unlocked yes)
			(layer "F.Fab")
			(hide yes)
			(effects
				(font
					(size 1 1)
					(thickness 0.15)
				)
			)
		)
		(sheetname "/X710-AT2 power/")
		(sheetfile "x710-at2-power.kicad_sch")
		(attr smd)
		(fp_line
			(start -0.15 0.4)
			(end 0.15 0.4)
			(stroke
				(width 0.15)
				(type solid)
			)
			(layer "F.SilkS")
		)
		(fp_line
			(start -0.15 -0.4)
			(end 0.15 -0.4)
			(stroke
				(width 0.15)
				(type solid)
			)
			(layer "F.SilkS")
		)
		(fp_rect
			(start -1.25 -0.65)
			(end 1.25 0.65)
			(stroke
				(width 0.05)
				(type solid)
			)
			(fill no)
			(layer "F.CrtYd")
		)
		(fp_rect
			(start -0.8 -0.4)
			(end 0.8 0.4)
			(stroke
				(width 0.15)
				(type solid)
			)
			(fill no)
			(layer "F.Fab")
		)
		(fp_text user "License: Apache-2.0"
			(at -1.682 5.895 180)
			(layer "F.Fab")
			(effects
				(font
					(size 0.7 0.7)
					(thickness 0.15)
				)
				(justify left bottom)
			)
		)
		(fp_text user "${REFERENCE}"
			(at -1.682 3.895 180)
			(layer "F.Fab")
			(effects
				(font
					(size 0.7 0.7)
					(thickness 0.15)
				)
				(justify left bottom)
			)
		)
		(fp_text user "Author: Antmicro"
			(at -1.682 4.894 180)
			(layer "F.Fab")
			(effects
				(font
					(size 0.7 0.7)
					(thickness 0.15)
				)
				(justify left bottom)
			)
		)
		(pad "1" smd roundrect
			(at -0.7 0 180)
			(size 0.8 1)
			(layers "F.Cu" "F.Mask" "F.Paste")
			(roundrect_rratio 0.2)
			(net 23 "GND")
			(pintype "passive")
		)
		(pad "2" smd roundrect
			(at 0.7 0 180)
			(size 0.8 1)
			(layers "F.Cu" "F.Mask" "F.Paste")
			(roundrect_rratio 0.2)
			(net 10 "AVDDH")
			(pintype "passive")
		)
	)
	(footprint "antmicro-footprints:C_0402_1005Metric"
		(layer "F.Cu")
		(at 147.555 97.375 -90)
		(descr "Capacitor SMD 0402")
		(tags "capacitor SMD 0402")
		(property "Reference" "C161"
			(at 19.625001 -23.294999 270)
			(layer "F.SilkS")
			(effects
				(font
					(size 0.7 0.7)
					(thickness 0.15)
				)
			)
		)
		(property "Value" "C_100n_0402"
			(at -1.022927 2.155213 270)
			(layer "F.Fab")
			(effects
				(font
					(size 0.7 0.7)
					(thickness 0.15)
				)
				(justify left bottom)
			)
		)
		(property "Datasheet" "https://www.murata.com/products/productdetail?partno=GRM155R61H104KE14%23"
			(at 0 0 270)
			(layer "F.Fab")
			(hide yes)
			(effects
				(font
					(size 1.27 1.27)
					(thickness 0.15)
				)
			)
		)
		(property "Description" "SMD Multilayer Ceramic Capacitor, 0.1 µF, 50 V, 0402 [1005 Metric], ± 10%, X5R, GRM Series"
			(at 0 0 270)
			(layer "F.Fab")
			(hide yes)
			(effects
				(font
					(size 1.27 1.27)
					(thickness 0.15)
				)
			)
		)
		(property "MPN" "GRM155R61H104KE14D"
			(at 0 0 270)
			(unlocked yes)
			(layer "F.Fab")
			(hide yes)
			(effects
				(font
					(size 1 1)
					(thickness 0.15)
				)
			)
		)
		(property "Val" "100n"
			(at 0 0 270)
			(unlocked yes)
			(layer "F.Fab")
			(hide yes)
			(effects
				(font
					(size 1 1)
					(thickness 0.15)
				)
			)
		)
		(property "Voltage" "50V"
			(at 0 0 270)
			(unlocked yes)
			(layer "F.Fab")
			(hide yes)
			(effects
				(font
					(size 1 1)
					(thickness 0.15)
				)
			)
		)
		(property "Dielectric" "X5R"
			(at 0 0 270)
			(unlocked yes)
			(layer "F.Fab")
			(hide yes)
			(effects
				(font
					(size 1 1)
					(thickness 0.15)
				)
			)
		)
		(property "Manufacturer" "Murata"
			(at 0 0 270)
			(unlocked yes)
			(layer "F.Fab")
			(hide yes)
			(effects
				(font
					(size 1 1)
					(thickness 0.15)
				)
			)
		)
		(property "License" "Apache-2.0"
			(at 0 0 270)
			(unlocked yes)
			(layer "F.Fab")
			(hide yes)
			(effects
				(font
					(size 1 1)
					(thickness 0.15)
				)
			)
		)
		(property "Author" "Antmicro"
			(at 0 0 270)
			(unlocked yes)
			(layer "F.Fab")
			(hide yes)
			(effects
				(font
					(size 1 1)
					(thickness 0.15)
				)
			)
		)
		(sheetname "/X710-AT2 power/")
		(sheetfile "x710-at2-power.kicad_sch")
		(attr smd)
		(fp_rect
			(start -0.925 -0.47)
			(end 0.925 0.47)
			(stroke
				(width 0.05)
				(type default)
			)
			(fill no)
			(layer "F.CrtYd")
		)
		(fp_line
			(start -0.494 0.248)
			(end -0.494 -0.25)
			(stroke
				(width 0.15)
				(type solid)
			)
			(layer "F.Fab")
		)
		(fp_line
			(start 0.504 0.248)
			(end -0.494 0.248)
			(stroke
				(width 0.15)
				(type solid)
			)
			(layer "F.Fab")
		)
		(fp_line
			(start -0.494 -0.25)
			(end 0.504 -0.25)
			(stroke
				(width 0.15)
				(type solid)
			)
			(layer "F.Fab")
		)
		(fp_line
			(start 0.504 -0.25)
			(end 0.504 0.248)
			(stroke
				(width 0.15)
				(type solid)
			)
			(layer "F.Fab")
		)
		(fp_text user "Author: Antmicro"
			(at -0.939 3.399 270)
			(layer "F.Fab")
			(effects
				(font
					(size 0.7 0.7)
					(thickness 0.15)
				)
				(justify left bottom)
			)
		)
		(fp_text user "${REFERENCE}"
			(at -0.939 4.599 270)
			(layer "F.Fab")
			(effects
				(font
					(size 0.7 0.7)
					(thickness 0.15)
				)
				(justify left bottom)
			)
		)
		(fp_text user "License: Apache-2.0"
			(at -0.939 5.799 270)
			(layer "F.Fab")
			(effects
				(font
					(size 0.7 0.7)
					(thickness 0.15)
				)
				(justify left bottom)
			)
		)
		(pad "1" smd roundrect
			(at -0.48 0 270)
			(size 0.59 0.64)
			(layers "F.Cu" "F.Mask" "F.Paste")
			(roundrect_rratio 0.25)
			(net 23 "GND")
			(pintype "passive")
		)
		(pad "2" smd roundrect
			(at 0.48 0 270)
			(size 0.59 0.64)
			(layers "F.Cu" "F.Mask" "F.Paste")
			(roundrect_rratio 0.25)
			(net 18 "+1V88")
			(pintype "passive")
		)
	)
	(footprint "antmicro-footprints:C_0603_1608Metric"
		(layer "F.Cu")
		(at 141.5 122.95 90)
		(descr "Capacitor SMD 0603")
		(tags "capacitor 0603")
		(property "Reference" "C89"
			(at -2.15 1.6 90)
			(layer "F.SilkS")
			(effects
				(font
					(size 0.7 0.7)
					(thickness 0.15)
				)
				(justify left bottom)
			)
		)
		(property "Value" "C_22u_0603"
			(at -1.42757 1.770288 90)
			(layer "F.Fab")
			(effects
				(font
					(size 0.7 0.7)
					(thickness 0.15)
				)
				(justify left bottom)
			)
		)
		(property "Datasheet" "https://www.murata.com/products/productdetail?partno=GRM188R60J226MEA0%23"
			(at 0 0 90)
			(layer "F.Fab")
			(hide yes)
			(effects
				(font
					(size 1.27 1.27)
					(thickness 0.15)
				)
			)
		)
		(property "Description" "SMD Multilayer Ceramic Capacitor, 22 µF, 6.3 V, 0603 [1608 Metric], ± 20%, X5R, GRM Series"
			(at 0 0 90)
			(layer "F.Fab")
			(hide yes)
			(effects
				(font
					(size 1.27 1.27)
					(thickness 0.15)
				)
			)
		)
		(property "MPN" "GRM188R60J226MEA0D"
			(at 0 0 90)
			(unlocked yes)
			(layer "F.Fab")
			(hide yes)
			(effects
				(font
					(size 1 1)
					(thickness 0.15)
				)
			)
		)
		(property "Manufacturer" "Murata"
			(at 0 0 90)
			(unlocked yes)
			(layer "F.Fab")
			(hide yes)
			(effects
				(font
					(size 1 1)
					(thickness 0.15)
				)
			)
		)
		(property "License" "Apache-2.0"
			(at 0 0 90)
			(unlocked yes)
			(layer "F.Fab")
			(hide yes)
			(effects
				(font
					(size 1 1)
					(thickness 0.15)
				)
			)
		)
		(property "Val" "22u"
			(at 0 0 90)
			(unlocked yes)
			(layer "F.Fab")
			(hide yes)
			(effects
				(font
					(size 1 1)
					(thickness 0.15)
				)
			)
		)
		(property "Voltage" ""
			(at 0 0 90)
			(unlocked yes)
			(layer "F.Fab")
			(hide yes)
			(effects
				(font
					(size 1 1)
					(thickness 0.15)
				)
			)
		)
		(property "Dielectric" ""
			(at 0 0 90)
			(unlocked yes)
			(layer "F.Fab")
			(hide yes)
			(effects
				(font
					(size 1 1)
					(thickness 0.15)
				)
			)
		)
		(property "Author" "Antmicro"
			(at 0 0 90)
			(unlocked yes)
			(layer "F.Fab")
			(hide yes)
			(effects
				(font
					(size 1 1)
					(thickness 0.15)
				)
			)
		)
		(sheetname "/TB Controller - Power/")
		(sheetfile "tb-power.kicad_sch")
		(attr smd)
		(fp_line
			(start -0.15 -0.4)
			(end 0.15 -0.4)
			(stroke
				(width 0.15)
				(type solid)
			)
			(layer "F.SilkS")
		)
		(fp_line
			(start -0.15 0.4)
			(end 0.15 0.4)
			(stroke
				(width 0.15)
				(type solid)
			)
			(layer "F.SilkS")
		)
		(fp_rect
			(start -1.25 -0.65)
			(end 1.25 0.65)
			(stroke
				(width 0.05)
				(type solid)
			)
			(fill no)
			(layer "F.CrtYd")
		)
		(fp_rect
			(start -0.8 -0.4)
			(end 0.8 0.4)
			(stroke
				(width 0.15)
				(type solid)
			)
			(fill no)
			(layer "F.Fab")
		)
		(fp_text user "License: Apache-2.0"
			(at -1.682 5.895 90)
			(layer "F.Fab")
			(effects
				(font
					(size 0.7 0.7)
					(thickness 0.15)
				)
				(justify left bottom)
			)
		)
		(fp_text user "${REFERENCE}"
			(at -1.682 3.895 90)
			(layer "F.Fab")
			(effects
				(font
					(size 0.7 0.7)
					(thickness 0.15)
				)
				(justify left bottom)
			)
		)
		(fp_text user "Author: Antmicro"
			(at -1.682 4.894 90)
			(layer "F.Fab")
			(effects
				(font
					(size 0.7 0.7)
					(thickness 0.15)
				)
				(justify left bottom)
			)
		)
		(pad "1" smd roundrect
			(at -0.7 0 90)
			(size 0.8 1)
			(layers "F.Cu" "F.Mask" "F.Paste")
			(roundrect_rratio 0.2)
			(net 23 "GND")
			(pintype "passive")
		)
		(pad "2" smd roundrect
			(at 0.7 0 90)
			(size 0.8 1)
			(layers "F.Cu" "F.Mask" "F.Paste")
			(roundrect_rratio 0.2)
			(net 68 "/TB Controller - Power/VCC_0P9")
			(pintype "passive")
		)
	)
	(footprint "antmicro-footprints:MP_Pad6mm_Drill3.2mm"
		(layer "F.Cu")
		(at 172 108.000001 90)
		(property "Reference" "MP7"
			(at 3.400001 -1.2 180)
			(layer "F.SilkS")
			(effects
				(font
					(size 0.7 0.7)
					(thickness 0.15)
				)
				(justify left bottom)
			)
		)
		(property "Value" "MP_Pad6mm_Drill3.2mm"
			(at 0 3.9 90)
			(layer "F.Fab")
			(effects
				(font
					(size 0.7 0.7)
					(thickness 0.15)
				)
				(justify left bottom)
			)
		)
		(property "Description" "Mechanical part"
			(at 0 0 90)
			(layer "F.Fab")
			(hide yes)
			(effects
				(font
					(size 1.27 1.27)
					(thickness 0.15)
				)
			)
		)
		(property "Author" "Antmicro"
			(at 0 0 90)
			(unlocked yes)
			(layer "F.Fab")
			(hide yes)
			(effects
				(font
					(size 1 1)
					(thickness 0.15)
				)
			)
		)
		(property "License" "Apache-2.0"
			(at 0 0 90)
			(unlocked yes)
			(layer "F.Fab")
			(hide yes)
			(effects
				(font
					(size 1 1)
					(thickness 0.15)
				)
			)
		)
		(sheetname "/")
		(sheetfile "thunderbolt-to-10gbe-adapter.kicad_sch")
		(attr exclude_from_pos_files exclude_from_bom)
		(fp_circle
			(center 0 0)
			(end 3.25 0)
			(stroke
				(width 0.05)
				(type default)
			)
			(fill no)
			(layer "F.CrtYd")
		)
		(fp_text user "${REFERENCE}"
			(at -0.178 6.025 90)
			(layer "F.Fab")
			(effects
				(font
					(size 0.7 0.7)
					(thickness 0.15)
				)
				(justify left bottom)
			)
		)
		(fp_text user "License: Apache-2.0"
			(at -0.178 8.425 90)
			(layer "F.Fab")
			(effects
				(font
					(size 0.7 0.7)
					(thickness 0.15)
				)
				(justify left bottom)
			)
		)
		(fp_text user "Author: Antmicro"
			(at -0.178 7.225 90)
			(layer "F.Fab")
			(effects
				(font
					(size 0.7 0.7)
					(thickness 0.15)
				)
				(justify left bottom)
			)
		)
		(pad "1" thru_hole circle
			(at 0 0 90)
			(size 6 6)
			(drill 3.2)
			(layers "*.Cu" "*.Mask")
			(remove_unused_layers no)
			(net 23 "GND")
			(pintype "passive")
		)
	)
	(footprint "antmicro-footprints:C_0402_1005Metric"
		(layer "F.Cu")
		(at 135.85 129.150004 -90)
		(descr "Capacitor SMD 0402")
		(tags "capacitor SMD 0402")
		(property "Reference" "C98"
			(at -0.450004 -7.15 270)
			(layer "F.SilkS")
			(effects
				(font
					(size 0.7 0.7)
					(thickness 0.15)
				)
				(justify left bottom)
			)
		)
		(property "Value" "C_10u_0402"
			(at -1.022927 2.155213 270)
			(layer "F.Fab")
			(effects
				(font
					(size 0.7 0.7)
					(thickness 0.15)
				)
				(justify left bottom)
			)
		)
		(property "Datasheet" "https://www.yageo.com/en/Chart/Download/pdf/CC0402MRX5R5BB106"
			(at 0 0 270)
			(layer "F.Fab")
			(hide yes)
			(effects
				(font
					(size 1.27 1.27)
					(thickness 0.15)
				)
			)
		)
		(property "Description" "SMD Multilayer Ceramic Capacitor, 10 µF, 6.3 V, 0402 [1005 Metric], ± 20%, X5R, CC Series"
			(at 0 0 270)
			(layer "F.Fab")
			(hide yes)
			(effects
				(font
					(size 1.27 1.27)
					(thickness 0.15)
				)
			)
		)
		(property "MPN" "CC0402MRX5R5BB106"
			(at 0 0 270)
			(unlocked yes)
			(layer "F.Fab")
			(hide yes)
			(effects
				(font
					(size 1 1)
					(thickness 0.15)
				)
			)
		)
		(property "Manufacturer" "YAGEO"
			(at 0 0 270)
			(unlocked yes)
			(layer "F.Fab")
			(hide yes)
			(effects
				(font
					(size 1 1)
					(thickness 0.15)
				)
			)
		)
		(property "License" "Apache-2.0"
			(at 0 0 270)
			(unlocked yes)
			(layer "F.Fab")
			(hide yes)
			(effects
				(font
					(size 1 1)
					(thickness 0.15)
				)
			)
		)
		(property "Val" "10u"
			(at 0 0 270)
			(unlocked yes)
			(layer "F.Fab")
			(hide yes)
			(effects
				(font
					(size 1 1)
					(thickness 0.15)
				)
			)
		)
		(property "Voltage" ""
			(at 0 0 270)
			(unlocked yes)
			(layer "F.Fab")
			(hide yes)
			(effects
				(font
					(size 1 1)
					(thickness 0.15)
				)
			)
		)
		(property "Dielectric" ""
			(at 0 0 270)
			(unlocked yes)
			(layer "F.Fab")
			(hide yes)
			(effects
				(font
					(size 1 1)
					(thickness 0.15)
				)
			)
		)
		(property "Author" "Antmicro"
			(at 0 0 270)
			(unlocked yes)
			(layer "F.Fab")
			(hide yes)
			(effects
				(font
					(size 1 1)
					(thickness 0.15)
				)
			)
		)
		(sheetname "/TB Controller - Power/")
		(sheetfile "tb-power.kicad_sch")
		(attr smd)
		(fp_rect
			(start -0.925 -0.47)
			(end 0.925 0.47)
			(stroke
				(width 0.05)
				(type default)
			)
			(fill no)
			(layer "F.CrtYd")
		)
		(fp_line
			(start -0.494 0.248)
			(end -0.494 -0.25)
			(stroke
				(width 0.15)
				(type solid)
			)
			(layer "F.Fab")
		)
		(fp_line
			(start 0.504 0.248)
			(end -0.494 0.248)
			(stroke
				(width 0.15)
				(type solid)
			)
			(layer "F.Fab")
		)
		(fp_line
			(start -0.494 -0.25)
			(end 0.504 -0.25)
			(stroke
				(width 0.15)
				(type solid)
			)
			(layer "F.Fab")
		)
		(fp_line
			(start 0.504 -0.25)
			(end 0.504 0.248)
			(stroke
				(width 0.15)
				(type solid)
			)
			(layer "F.Fab")
		)
		(fp_text user "Author: Antmicro"
			(at -0.939 3.399 270)
			(layer "F.Fab")
			(effects
				(font
					(size 0.7 0.7)
					(thickness 0.15)
				)
				(justify left bottom)
			)
		)
		(fp_text user "${REFERENCE}"
			(at -0.939 4.599 270)
			(layer "F.Fab")
			(effects
				(font
					(size 0.7 0.7)
					(thickness 0.15)
				)
				(justify left bottom)
			)
		)
		(fp_text user "License: Apache-2.0"
			(at -0.939 5.799 270)
			(layer "F.Fab")
			(effects
				(font
					(size 0.7 0.7)
					(thickness 0.15)
				)
				(justify left bottom)
			)
		)
		(pad "1" smd roundrect
			(at -0.48 0 270)
			(size 0.59 0.64)
			(layers "F.Cu" "F.Mask" "F.Paste")
			(roundrect_rratio 0.25)
			(net 23 "GND")
			(pintype "passive")
		)
		(pad "2" smd roundrect
			(at 0.48 0 270)
			(size 0.59 0.64)
			(layers "F.Cu" "F.Mask" "F.Paste")
			(roundrect_rratio 0.25)
			(net 57 "+3V3_TB")
			(pintype "passive")
		)
	)
	(footprint "antmicro-footprints:C_0402_1005Metric"
		(layer "F.Cu")
		(at 134.249999 97.849998)
		(descr "Capacitor SMD 0402")
		(tags "capacitor SMD 0402")
		(property "Reference" "C124"
			(at 37.385 -9.199999 0)
			(layer "F.SilkS")
			(effects
				(font
					(size 0.7 0.7)
					(thickness 0.15)
				)
			)
		)
		(property "Value" "C_100n_0402"
			(at -1.022927 2.155213 0)
			(layer "F.Fab")
			(effects
				(font
					(size 0.7 0.7)
					(thickness 0.15)
				)
				(justify left bottom)
			)
		)
		(property "Datasheet" "https://www.murata.com/products/productdetail?partno=GRM155R61H104KE14%23"
			(at 0 0 0)
			(layer "F.Fab")
			(hide yes)
			(effects
				(font
					(size 1.27 1.27)
					(thickness 0.15)
				)
			)
		)
		(property "Description" "SMD Multilayer Ceramic Capacitor, 0.1 µF, 50 V, 0402 [1005 Metric], ± 10%, X5R, GRM Series"
			(at 0 0 0)
			(layer "F.Fab")
			(hide yes)
			(effects
				(font
					(size 1.27 1.27)
					(thickness 0.15)
				)
			)
		)
		(property "MPN" "GRM155R61H104KE14D"
			(at 0 0 0)
			(unlocked yes)
			(layer "F.Fab")
			(hide yes)
			(effects
				(font
					(size 1 1)
					(thickness 0.15)
				)
			)
		)
		(property "Manufacturer" "Murata"
			(at 0 0 0)
			(unlocked yes)
			(layer "F.Fab")
			(hide yes)
			(effects
				(font
					(size 1 1)
					(thickness 0.15)
				)
			)
		)
		(property "License" "Apache-2.0"
			(at 0 0 0)
			(unlocked yes)
			(layer "F.Fab")
			(hide yes)
			(effects
				(font
					(size 1 1)
					(thickness 0.15)
				)
			)
		)
		(property "Author" "Antmicro"
			(at 0 0 0)
			(unlocked yes)
			(layer "F.Fab")
			(hide yes)
			(effects
				(font
					(size 1 1)
					(thickness 0.15)
				)
			)
		)
		(property "Val" "100n"
			(at 0 0 0)
			(unlocked yes)
			(layer "F.Fab")
			(hide yes)
			(effects
				(font
					(size 1 1)
					(thickness 0.15)
				)
			)
		)
		(property "Voltage" "50V"
			(at 0 0 0)
			(unlocked yes)
			(layer "F.Fab")
			(hide yes)
			(effects
				(font
					(size 1 1)
					(thickness 0.15)
				)
			)
		)
		(property "Dielectric" "X5R"
			(at 0 0 0)
			(unlocked yes)
			(layer "F.Fab")
			(hide yes)
			(effects
				(font
					(size 1 1)
					(thickness 0.15)
				)
			)
		)
		(sheetname "/X710 DCDC converters/")
		(sheetfile "DCDC_converters_X710.kicad_sch")
		(attr smd)
		(fp_rect
			(start -0.925 -0.47)
			(end 0.925 0.47)
			(stroke
				(width 0.05)
				(type default)
			)
			(fill no)
			(layer "F.CrtYd")
		)
		(fp_line
			(start -0.494 -0.25)
			(end 0.504 -0.25)
			(stroke
				(width 0.15)
				(type solid)
			)
			(layer "F.Fab")
		)
		(fp_line
			(start -0.494 0.248)
			(end -0.494 -0.25)
			(stroke
				(width 0.15)
				(type solid)
			)
			(layer "F.Fab")
		)
		(fp_line
			(start 0.504 -0.25)
			(end 0.504 0.248)
			(stroke
				(width 0.15)
				(type solid)
			)
			(layer "F.Fab")
		)
		(fp_line
			(start 0.504 0.248)
			(end -0.494 0.248)
			(stroke
				(width 0.15)
				(type solid)
			)
			(layer "F.Fab")
		)
		(fp_text user "Author: Antmicro"
			(at -0.939 3.399 0)
			(layer "F.Fab")
			(effects
				(font
					(size 0.7 0.7)
					(thickness 0.15)
				)
				(justify left bottom)
			)
		)
		(fp_text user "${REFERENCE}"
			(at -0.939 4.599 0)
			(layer "F.Fab")
			(effects
				(font
					(size 0.7 0.7)
					(thickness 0.15)
				)
				(justify left bottom)
			)
		)
		(fp_text user "License: Apache-2.0"
			(at -0.939 5.799 0)
			(layer "F.Fab")
			(effects
				(font
					(size 0.7 0.7)
					(thickness 0.15)
				)
				(justify left bottom)
			)
		)
		(pad "1" smd roundrect
			(at -0.48 0)
			(size 0.59 0.64)
			(layers "F.Cu" "F.Mask" "F.Paste")
			(roundrect_rratio 0.25)
			(net 118 "/X710 DCDC converters/3V3_BST")
			(pintype "passive")
		)
		(pad "2" smd roundrect
			(at 0.48 0)
			(size 0.59 0.64)
			(layers "F.Cu" "F.Mask" "F.Paste")
			(roundrect_rratio 0.25)
			(net 117 "/X710 DCDC converters/3V3_SW")
			(pintype "passive")
		)
	)
	(footprint "antmicro-footprints:C_0603_1608Metric_EIA"
		(layer "F.Cu")
		(at 134.655 89.274999 -90)
		(descr "Capacitor SMD 0603, IPC-7351 Density Level A")
		(tags "Capacitor 0603")
		(property "Reference" "C254"
			(at 4.225001 16.405 270)
			(layer "F.SilkS")
			(effects
				(font
					(size 0.7 0.7)
					(thickness 0.15)
				)
				(justify left bottom)
			)
		)
		(property "Value" "C_22u_16V_0603"
			(at -1.42757 1.770288 270)
			(layer "F.Fab")
			(effects
				(font
					(size 0.7 0.7)
					(thickness 0.15)
				)
				(justify left bottom)
			)
		)
		(property "Datasheet" "https://product.samsungsem.com/mlcc/CL10A226MO7JZN.do"
			(at 0 0 270)
			(layer "F.Fab")
			(hide yes)
			(effects
				(font
					(size 1.27 1.27)
					(thickness 0.15)
				)
			)
		)
		(property "Description" "SMD Multilayer Ceramic Capacitor"
			(at 0 0 270)
			(layer "F.Fab")
			(hide yes)
			(effects
				(font
					(size 1.27 1.27)
					(thickness 0.15)
				)
			)
		)
		(property "MPN" "CL10A226MO7JZNC"
			(at 0 0 270)
			(unlocked yes)
			(layer "F.Fab")
			(hide yes)
			(effects
				(font
					(size 1 1)
					(thickness 0.15)
				)
			)
		)
		(property "Manufacturer" "Samsung Electro-Mechanics"
			(at 0 0 270)
			(unlocked yes)
			(layer "F.Fab")
			(hide yes)
			(effects
				(font
					(size 1 1)
					(thickness 0.15)
				)
			)
		)
		(property "License" "Apache-2.0"
			(at 0 0 270)
			(unlocked yes)
			(layer "F.Fab")
			(hide yes)
			(effects
				(font
					(size 1 1)
					(thickness 0.15)
				)
			)
		)
		(property "Author" "Antmicro"
			(at 0 0 270)
			(unlocked yes)
			(layer "F.Fab")
			(hide yes)
			(effects
				(font
					(size 1 1)
					(thickness 0.15)
				)
			)
		)
		(property "Val" "22u"
			(at 0 0 270)
			(unlocked yes)
			(layer "F.Fab")
			(hide yes)
			(effects
				(font
					(size 1 1)
					(thickness 0.15)
				)
			)
		)
		(property "Voltage" "16V"
			(at 0 0 270)
			(unlocked yes)
			(layer "F.Fab")
			(hide yes)
			(effects
				(font
					(size 1 1)
					(thickness 0.15)
				)
			)
		)
		(property "Dielectric" ""
			(at 0 0 270)
			(unlocked yes)
			(layer "F.Fab")
			(hide yes)
			(effects
				(font
					(size 1 1)
					(thickness 0.15)
				)
			)
		)
		(sheetname "/X710-AT2 power/")
		(sheetfile "x710-at2-power.kicad_sch")
		(attr smd)
		(fp_line
			(start -0.15 0.55)
			(end 0.15 0.55)
			(stroke
				(width 0.15)
				(type solid)
			)
			(layer "F.SilkS")
		)
		(fp_line
			(start -0.15 -0.55)
			(end 0.15 -0.55)
			(stroke
				(width 0.15)
				(type solid)
			)
			(layer "F.SilkS")
		)
		(fp_rect
			(start -1.25 -0.65)
			(end 1.25 0.65)
			(stroke
				(width 0.05)
				(type solid)
			)
			(fill no)
			(layer "F.CrtYd")
		)
		(fp_rect
			(start -0.8 -0.45)
			(end 0.8 0.45)
			(stroke
				(width 0.15)
				(type solid)
			)
			(fill no)
			(layer "F.Fab")
		)
		(fp_text user "License: Apache-2.0"
			(at -1.682 5.895 270)
			(layer "F.Fab")
			(effects
				(font
					(size 0.7 0.7)
					(thickness 0.15)
				)
				(justify left bottom)
			)
		)
		(fp_text user "Author: Antmicro"
			(at -1.682 4.894 270)
			(layer "F.Fab")
			(effects
				(font
					(size 0.7 0.7)
					(thickness 0.15)
				)
				(justify left bottom)
			)
		)
		(fp_text user "${REFERENCE}"
			(at -1.682 3.895 270)
			(layer "F.Fab")
			(effects
				(font
					(size 0.7 0.7)
					(thickness 0.15)
				)
				(justify left bottom)
			)
		)
		(pad "1" smd roundrect
			(at -0.7 0 270)
			(size 0.8 1.1)
			(layers "F.Cu" "F.Mask" "F.Paste")
			(roundrect_rratio 0.2)
			(net 23 "GND")
			(pintype "passive")
		)
		(pad "2" smd roundrect
			(at 0.7 0 270)
			(size 0.8 1.1)
			(layers "F.Cu" "F.Mask" "F.Paste")
			(roundrect_rratio 0.2)
			(net 7 "+3V3")
			(pintype "passive")
		)
	)
	(footprint "antmicro-footprints:C_0402_1005Metric"
		(layer "F.Cu")
		(at 138 81.75)
		(descr "Capacitor SMD 0402")
		(tags "capacitor SMD 0402")
		(property "Reference" "C269"
			(at -3.8 0.45 0)
			(layer "F.SilkS")
			(effects
				(font
					(size 0.7 0.7)
					(thickness 0.15)
				)
				(justify left bottom)
			)
		)
		(property "Value" "C_220n_16V_0402"
			(at -1.022927 2.155213 0)
			(layer "F.Fab")
			(effects
				(font
					(size 0.7 0.7)
					(thickness 0.15)
				)
				(justify left bottom)
			)
		)
		(property "Datasheet" "https://www.murata.com/products/productdetail?partno=GRM155R71C224KA12%23"
			(at 0 0 0)
			(layer "F.Fab")
			(hide yes)
			(effects
				(font
					(size 1.27 1.27)
					(thickness 0.15)
				)
			)
		)
		(property "Description" "SMD Multilayer Ceramic Capacitor, 0.22 µF, 16 V, 0402 [1005 Metric], ± 10%, X7R, GRM Series"
			(at 0 0 0)
			(layer "F.Fab")
			(hide yes)
			(effects
				(font
					(size 1.27 1.27)
					(thickness 0.15)
				)
			)
		)
		(property "MPN" "GRM155R71C224KA12D"
			(at 0 0 0)
			(unlocked yes)
			(layer "F.Fab")
			(hide yes)
			(effects
				(font
					(size 1 1)
					(thickness 0.15)
				)
			)
		)
		(property "Manufacturer" "Murata"
			(at 0 0 0)
			(unlocked yes)
			(layer "F.Fab")
			(hide yes)
			(effects
				(font
					(size 1 1)
					(thickness 0.15)
				)
			)
		)
		(property "License" "Apache-2.0"
			(at 0 0 0)
			(unlocked yes)
			(layer "F.Fab")
			(hide yes)
			(effects
				(font
					(size 1 1)
					(thickness 0.15)
				)
			)
		)
		(property "Author" "Antmicro"
			(at 0 0 0)
			(unlocked yes)
			(layer "F.Fab")
			(hide yes)
			(effects
				(font
					(size 1 1)
					(thickness 0.15)
				)
			)
		)
		(property "Val" "220n"
			(at 0 0 0)
			(unlocked yes)
			(layer "F.Fab")
			(hide yes)
			(effects
				(font
					(size 1 1)
					(thickness 0.15)
				)
			)
		)
		(property "Voltage" "16V"
			(at 0 0 0)
			(unlocked yes)
			(layer "F.Fab")
			(hide yes)
			(effects
				(font
					(size 1 1)
					(thickness 0.15)
				)
			)
		)
		(property "Dielectric" "X7R"
			(at 0 0 0)
			(unlocked yes)
			(layer "F.Fab")
			(hide yes)
			(effects
				(font
					(size 1 1)
					(thickness 0.15)
				)
			)
		)
		(sheetname "/X710-AT2 PCIe/")
		(sheetfile "x710-at2-pcie.kicad_sch")
		(attr smd)
		(fp_rect
			(start -0.925 -0.47)
			(end 0.925 0.47)
			(stroke
				(width 0.05)
				(type default)
			)
			(fill no)
			(layer "F.CrtYd")
		)
		(fp_line
			(start -0.494 -0.25)
			(end 0.504 -0.25)
			(stroke
				(width 0.15)
				(type solid)
			)
			(layer "F.Fab")
		)
		(fp_line
			(start -0.494 0.248)
			(end -0.494 -0.25)
			(stroke
				(width 0.15)
				(type solid)
			)
			(layer "F.Fab")
		)
		(fp_line
			(start 0.504 -0.25)
			(end 0.504 0.248)
			(stroke
				(width 0.15)
				(type solid)
			)
			(layer "F.Fab")
		)
		(fp_line
			(start 0.504 0.248)
			(end -0.494 0.248)
			(stroke
				(width 0.15)
				(type solid)
			)
			(layer "F.Fab")
		)
		(fp_text user "License: Apache-2.0"
			(at -0.939 5.799 0)
			(layer "F.Fab")
			(effects
				(font
					(size 0.7 0.7)
					(thickness 0.15)
				)
				(justify left bottom)
			)
		)
		(fp_text user "${REFERENCE}"
			(at -0.939 4.599 0)
			(layer "F.Fab")
			(effects
				(font
					(size 0.7 0.7)
					(thickness 0.15)
				)
				(justify left bottom)
			)
		)
		(fp_text user "Author: Antmicro"
			(at -0.939 3.399 0)
			(layer "F.Fab")
			(effects
				(font
					(size 0.7 0.7)
					(thickness 0.15)
				)
				(justify left bottom)
			)
		)
		(pad "1" smd roundrect
			(at -0.48 0)
			(size 0.59 0.64)
			(layers "F.Cu" "F.Mask" "F.Paste")
			(roundrect_rratio 0.25)
			(net 595 "/TB Controller/PCIex4.TX3-")
			(pintype "passive")
		)
		(pad "2" smd roundrect
			(at 0.48 0)
			(size 0.59 0.64)
			(layers "F.Cu" "F.Mask" "F.Paste")
			(roundrect_rratio 0.25)
			(net 34 "/X710-AT2 PCIe/PCIe_{x4}_AC.TX3-")
			(pintype "passive")
		)
	)
	(footprint "antmicro-footprints:RJ45_JTH-0024NL"
		(layer "F.Cu")
		(at 179.15 135.865 180)
		(property "Reference" "J4"
			(at -2.35 4.365 0)
			(unlocked yes)
			(layer "F.SilkS")
			(effects
				(font
					(size 0.7 0.7)
					(thickness 0.15)
				)
				(justify left bottom)
			)
		)
		(property "Value" "Bus_RJ45_JTH-0024NL"
			(at 5.06 1 180)
			(unlocked yes)
			(layer "F.Fab")
			(effects
				(font
					(size 0.7 0.7)
					(thickness 0.15)
				)
				(justify left bottom)
			)
		)
		(property "Datasheet" "https://www.mouser.com/datasheet/2/447/JTH_0024NL-3072047.pdf"
			(at 0 0 180)
			(layer "F.Fab")
			(hide yes)
			(effects
				(font
					(size 1.27 1.27)
					(thickness 0.15)
				)
			)
		)
		(property "Description" "Modular Connectors / Ethernet Connectors 1X1 TAB DOWN W/LED'S ETHERNET (NON PoE)"
			(at 0 0 180)
			(layer "F.Fab")
			(hide yes)
			(effects
				(font
					(size 1.27 1.27)
					(thickness 0.15)
				)
			)
		)
		(property "MPN" "JTH-0024NL"
			(at 0 0 180)
			(unlocked yes)
			(layer "F.Fab")
			(hide yes)
			(effects
				(font
					(size 1 1)
					(thickness 0.15)
				)
			)
		)
		(property "Manufacturer" "Pulse Electronics"
			(at 0 0 180)
			(unlocked yes)
			(layer "F.Fab")
			(hide yes)
			(effects
				(font
					(size 1 1)
					(thickness 0.15)
				)
			)
		)
		(property "Author" "Antmicro"
			(at 0 0 180)
			(unlocked yes)
			(layer "F.Fab")
			(hide yes)
			(effects
				(font
					(size 1 1)
					(thickness 0.15)
				)
			)
		)
		(property "License" "Apache-2.0"
			(at 0 0 180)
			(unlocked yes)
			(layer "F.Fab")
			(hide yes)
			(effects
				(font
					(size 1 1)
					(thickness 0.15)
				)
			)
		)
		(property ki_fp_filters "CONN18_5-2337992-8_TEC")
		(sheetname "/2xRJ45/")
		(sheetfile "2xrj45.kicad_sch")
		(attr through_hole)
		(fp_line
			(start 14 4)
			(end 14 -5.25)
			(stroke
				(width 0.1)
				(type default)
			)
			(layer "F.SilkS")
		)
		(fp_line
			(start -3.75 4)
			(end 14 4)
			(stroke
				(width 0.1)
				(type default)
			)
			(layer "F.SilkS")
		)
		(fp_line
			(start -3.75 -5.25)
			(end -3.75 4)
			(stroke
				(width 0.1)
				(type default)
			)
			(layer "F.SilkS")
		)
		(fp_rect
			(start -5.4 -20.72)
			(end 15.58 4.45)
			(stroke
				(width 0.05)
				(type solid)
			)
			(fill no)
			(layer "F.CrtYd")
		)
		(fp_text user "${REFERENCE}"
			(at -5.75 6.45 180)
			(unlocked yes)
			(layer "F.Fab")
			(effects
				(font
					(size 0.7 0.7)
					(thickness 0.15)
				)
				(justify left bottom)
			)
		)
		(fp_text user "License: Apache-2.0"
			(at -5.75 7.65 180)
			(layer "F.Fab")
			(effects
				(font
					(size 0.7 0.7)
					(thickness 0.15)
				)
				(justify left bottom)
			)
		)
		(fp_text user "Author: Antmicro"
			(at -5.75 8.85 180)
			(layer "F.Fab")
			(effects
				(font
					(size 0.7 0.7)
					(thickness 0.15)
				)
				(justify left bottom)
			)
		)
		(pad "" np_thru_hole circle
			(at 0.245 -6.6 180)
			(size 3.2 3.2)
			(drill 3.2)
			(layers "*.Cu" "*.Mask")
		)
		(pad "" np_thru_hole circle
			(at 9.895 -6.6 180)
			(size 3.2 3.2)
			(drill 3.2)
			(layers "*.Cu" "*.Mask")
		)
		(pad "1" thru_hole circle
			(at 0 0 180)
			(size 1.39 1.39)
			(drill 0.89)
			(layers "*.Cu" "*.Mask")
			(remove_unused_layers no)
			(net 134 "/2xRJ45/P1_CT")
			(pinfunction "CT3")
			(pintype "bidirectional")
		)
		(pad "2" thru_hole circle
			(at 2.03 0 180)
			(size 1.39 1.39)
			(drill 0.89)
			(layers "*.Cu" "*.Mask")
			(remove_unused_layers no)
			(net 46 "/2xRJ45/Ethernet_P1.D2-")
			(pinfunction "T2-")
			(pintype "bidirectional")
		)
		(pad "3" thru_hole circle
			(at 4.06 0 180)
			(size 1.39 1.39)
			(drill 0.89)
			(layers "*.Cu" "*.Mask")
			(remove_unused_layers no)
			(net 47 "/2xRJ45/Ethernet_P1.D2+")
			(pinfunction "T2+")
			(pintype "bidirectional")
		)
		(pad "4" thru_hole circle
			(at 6.09 0 180)
			(size 1.39 1.39)
			(drill 0.89)
			(layers "*.Cu" "*.Mask")
			(remove_unused_layers no)
			(net 48 "/2xRJ45/Ethernet_P1.D3+")
			(pinfunction "T3+")
			(pintype "bidirectional")
		)
		(pad "5" thru_hole circle
			(at 8.12 0 180)
			(size 1.39 1.39)
			(drill 0.89)
			(layers "*.Cu" "*.Mask")
			(remove_unused_layers no)
			(net 49 "/2xRJ45/Ethernet_P1.D3-")
			(pinfunction "T3-")
			(pintype "bidirectional")
		)
		(pad "6" thru_hole circle
			(at 10.15 0 180)
			(size 1.39 1.39)
			(drill 0.89)
			(layers "*.Cu" "*.Mask")
			(remove_unused_layers no)
			(net 134 "/2xRJ45/P1_CT")
			(pinfunction "CT2")
			(pintype "bidirectional")
		)
		(pad "7" thru_hole circle
			(at -1.02 2.54 180)
			(size 1.39 1.39)
			(drill 0.89)
			(layers "*.Cu" "*.Mask")
			(remove_unused_layers no)
			(net 134 "/2xRJ45/P1_CT")
			(pinfunction "CT4")
			(pintype "bidirectional")
		)
		(pad "8" thru_hole circle
			(at 1.01 2.54 180)
			(size 1.39 1.39)
			(drill 0.89)
			(layers "*.Cu" "*.Mask")
			(remove_unused_layers no)
			(net 52 "/2xRJ45/Ethernet_P1.D1+")
			(pinfunction "T1+")
			(pintype "bidirectional")
		)
		(pad "9" thru_hole circle
			(at 3.04 2.54 180)
			(size 1.39 1.39)
			(drill 0.89)
			(layers "*.Cu" "*.Mask")
			(remove_unused_layers no)
			(net 45 "/2xRJ45/Ethernet_P1.D1-")
			(pinfunction "T1-")
			(pintype "bidirectional")
		)
		(pad "10" thru_hole circle
			(at 7.11 2.54 180)
			(size 1.39 1.39)
			(drill 0.89)
			(layers "*.Cu" "*.Mask")
			(remove_unused_layers no)
			(net 51 "/2xRJ45/Ethernet_P1.D4-")
			(pinfunction "T4-")
			(pintype "bidirectional")
		)
		(pad "11" thru_hole circle
			(at 9.14 2.54 180)
			(size 1.39 1.39)
			(drill 0.89)
			(layers "*.Cu" "*.Mask")
			(remove_unused_layers no)
			(net 50 "/2xRJ45/Ethernet_P1.D4+")
			(pinfunction "T4+")
			(pintype "bidirectional")
		)
		(pad "12" thru_hole circle
			(at 11.17 2.54 180)
			(size 1.39 1.39)
			(drill 0.89)
			(layers "*.Cu" "*.Mask")
			(remove_unused_layers no)
			(net 134 "/2xRJ45/P1_CT")
			(pinfunction "CT1")
			(pintype "bidirectional")
		)
		(pad "13" thru_hole circle
			(at 12.59 -12.95 180)
			(size 1.77 1.77)
			(drill 1.27)
			(layers "*.Cu" "*.Mask")
			(remove_unused_layers no)
			(net 411 "Net-(J4-LED_GRN-)")
			(pinfunction "LED_GRN-")
			(pintype "passive")
		)
		(pad "14" thru_hole circle
			(at 12.59 -15.49 180)
			(size 1.77 1.77)
			(drill 1.27)
			(layers "*.Cu" "*.Mask")
			(remove_unused_layers no)
			(net 7 "+3V3")
			(pinfunction "LED_GRN+")
			(pintype "passive")
		)
		(pad "15" thru_hole circle
			(at -2.45 -10.41 180)
			(size 1.77 1.77)
			(drill 1.27)
			(layers "*.Cu" "*.Mask")
			(remove_unused_layers no)
			(net 407 "Net-(J4-LED_YG_Y-)")
			(pinfunction "LED_YG_Y-")
			(pintype "passive")
		)
		(pad "16" thru_hole circle
			(at -2.45 -12.95 180)
			(size 1.77 1.77)
			(drill 1.27)
			(layers "*.Cu" "*.Mask")
			(remove_unused_layers no)
			(net 7 "+3V3")
			(pinfunction "LED_COM+")
			(pintype "passive")
		)
		(pad "17" thru_hole circle
			(at -2.45 -15.49 180)
			(size 1.77 1.77)
			(drill 1.27)
			(layers "*.Cu" "*.Mask")
			(remove_unused_layers no)
			(net 409 "Net-(J4-LED_YG_G-)")
			(pinfunction "LED_YG_G-")
			(pintype "passive")
		)
		(pad "SH" thru_hole circle
			(at -3.72 -6.6 180)
			(size 2.07 2.07)
			(drill 1.57)
			(layers "*.Cu" "*.Mask")
			(remove_unused_layers no)
			(net 23 "GND")
			(pinfunction "SHIELD")
			(pintype "passive")
		)
		(pad "SH" thru_hole circle
			(at 13.86 -6.6 180)
			(size 2.07 2.07)
			(drill 1.57)
			(layers "*.Cu" "*.Mask")
			(remove_unused_layers no)
			(net 23 "GND")
			(pinfunction "SHIELD")
			(pintype "passive")
		)
	)
	(footprint "antmicro-footprints:R_0402_1005Metric"
		(layer "F.Cu")
		(at 158.355 94.054999 90)
		(descr "Resistor SMD 0402")
		(tags "resistor SMD 0402")
		(property "Reference" "R164"
			(at -19.145001 23.294999 90)
			(layer "F.SilkS")
			(effects
				(font
					(size 0.7 0.7)
					(thickness 0.15)
				)
			)
		)
		(property "Value" "R_10R_0402"
			(at -1.011843 1.772047 90)
			(layer "F.Fab")
			(effects
				(font
					(size 0.7 0.7)
					(thickness 0.15)
				)
				(justify left bottom)
			)
		)
		(property "Datasheet" "https://www.bourns.com/docs/product-datasheets/cr.pdf"
			(at 0 0 90)
			(layer "F.Fab")
			(hide yes)
			(effects
				(font
					(size 1.27 1.27)
					(thickness 0.15)
				)
			)
		)
		(property "Description" "SMD Chip Resistor, 10 ohm, ± 1%, 62.5 mW, 0402 [1005 Metric], Thick Film, General Purpose"
			(at 0 0 90)
			(layer "F.Fab")
			(hide yes)
			(effects
				(font
					(size 1.27 1.27)
					(thickness 0.15)
				)
			)
		)
		(property "MPN" "CR0402-FX-10R0GLF"
			(at 0 0 90)
			(unlocked yes)
			(layer "F.Fab")
			(hide yes)
			(effects
				(font
					(size 1 1)
					(thickness 0.15)
				)
			)
		)
		(property "Manufacturer" "Bourns"
			(at 0 0 90)
			(unlocked yes)
			(layer "F.Fab")
			(hide yes)
			(effects
				(font
					(size 1 1)
					(thickness 0.15)
				)
			)
		)
		(property "License" "Apache-2.0"
			(at 0 0 90)
			(unlocked yes)
			(layer "F.Fab")
			(hide yes)
			(effects
				(font
					(size 1 1)
					(thickness 0.15)
				)
			)
		)
		(property "Author" "Antmicro"
			(at 0 0 90)
			(unlocked yes)
			(layer "F.Fab")
			(hide yes)
			(effects
				(font
					(size 1 1)
					(thickness 0.15)
				)
			)
		)
		(property "Val" "10R"
			(at 0 0 90)
			(unlocked yes)
			(layer "F.Fab")
			(hide yes)
			(effects
				(font
					(size 1 1)
					(thickness 0.15)
				)
			)
		)
		(property "Tolerance" "1%"
			(at 0 0 90)
			(unlocked yes)
			(layer "F.Fab")
			(hide yes)
			(effects
				(font
					(size 1 1)
					(thickness 0.15)
				)
			)
		)
		(sheetname "/X710-AT2 Misc/")
		(sheetfile "x710-at2-mics.kicad_sch")
		(attr smd)
		(fp_rect
			(start -0.925 -0.47)
			(end 0.925 0.47)
			(stroke
				(width 0.05)
				(type default)
			)
			(fill no)
			(layer "F.CrtYd")
		)
		(fp_rect
			(start -0.5 -0.25)
			(end 0.5 0.25)
			(stroke
				(width 0.15)
				(type solid)
			)
			(fill no)
			(layer "F.Fab")
		)
		(fp_text user "License: Apache-2.0"
			(at -0.95 5.169 90)
			(layer "F.Fab")
			(effects
				(font
					(size 0.7 0.7)
					(thickness 0.15)
				)
				(justify left bottom)
			)
		)
		(fp_text user "Author: Antmicro"
			(at -0.95 4.169 90)
			(layer "F.Fab")
			(effects
				(font
					(size 0.7 0.7)
					(thickness 0.15)
				)
				(justify left bottom)
			)
		)
		(fp_text user "${REFERENCE}"
			(at -0.95 3.168 90)
			(layer "F.Fab")
			(effects
				(font
					(size 0.7 0.7)
					(thickness 0.15)
				)
				(justify left bottom)
			)
		)
		(pad "1" smd roundrect
			(at -0.48 0 90)
			(size 0.59 0.64)
			(layers "F.Cu" "F.Mask" "F.Paste")
			(roundrect_rratio 0.25)
			(net 58 "/X710-AT2 Misc/50MHZ_XTAL_R.+")
			(pintype "passive")
		)
		(pad "2" smd roundrect
			(at 0.48 0 90)
			(size 0.59 0.64)
			(layers "F.Cu" "F.Mask" "F.Paste")
			(roundrect_rratio 0.25)
			(net 115 "/X710-AT2 Misc/50MHZ_XTAL.+")
			(pintype "passive")
		)
	)
	(footprint "antmicro-footprints:C_0603_1608Metric"
		(layer "F.Cu")
		(at 141.49142 120.15 -90)
		(descr "Capacitor SMD 0603")
		(tags "capacitor 0603")
		(property "Reference" "C84"
			(at -1.35 -0.55 270)
			(layer "F.SilkS")
			(effects
				(font
					(size 0.7 0.7)
					(thickness 0.15)
				)
				(justify left bottom)
			)
		)
		(property "Value" "C_22u_0603"
			(at -1.42757 1.770288 270)
			(layer "F.Fab")
			(effects
				(font
					(size 0.7 0.7)
					(thickness 0.15)
				)
				(justify left bottom)
			)
		)
		(property "Datasheet" "https://www.murata.com/products/productdetail?partno=GRM188R60J226MEA0%23"
			(at 0 0 270)
			(layer "F.Fab")
			(hide yes)
			(effects
				(font
					(size 1.27 1.27)
					(thickness 0.15)
				)
			)
		)
		(property "Description" "SMD Multilayer Ceramic Capacitor, 22 µF, 6.3 V, 0603 [1608 Metric], ± 20%, X5R, GRM Series"
			(at 0 0 270)
			(layer "F.Fab")
			(hide yes)
			(effects
				(font
					(size 1.27 1.27)
					(thickness 0.15)
				)
			)
		)
		(property "MPN" "GRM188R60J226MEA0D"
			(at 0 0 270)
			(unlocked yes)
			(layer "F.Fab")
			(hide yes)
			(effects
				(font
					(size 1 1)
					(thickness 0.15)
				)
			)
		)
		(property "Manufacturer" "Murata"
			(at 0 0 270)
			(unlocked yes)
			(layer "F.Fab")
			(hide yes)
			(effects
				(font
					(size 1 1)
					(thickness 0.15)
				)
			)
		)
		(property "License" "Apache-2.0"
			(at 0 0 270)
			(unlocked yes)
			(layer "F.Fab")
			(hide yes)
			(effects
				(font
					(size 1 1)
					(thickness 0.15)
				)
			)
		)
		(property "Val" "22u"
			(at 0 0 270)
			(unlocked yes)
			(layer "F.Fab")
			(hide yes)
			(effects
				(font
					(size 1 1)
					(thickness 0.15)
				)
			)
		)
		(property "Voltage" ""
			(at 0 0 270)
			(unlocked yes)
			(layer "F.Fab")
			(hide yes)
			(effects
				(font
					(size 1 1)
					(thickness 0.15)
				)
			)
		)
		(property "Dielectric" ""
			(at 0 0 270)
			(unlocked yes)
			(layer "F.Fab")
			(hide yes)
			(effects
				(font
					(size 1 1)
					(thickness 0.15)
				)
			)
		)
		(property "Author" "Antmicro"
			(at 0 0 270)
			(unlocked yes)
			(layer "F.Fab")
			(hide yes)
			(effects
				(font
					(size 1 1)
					(thickness 0.15)
				)
			)
		)
		(sheetname "/TB Controller - Power/")
		(sheetfile "tb-power.kicad_sch")
		(attr smd)
		(fp_line
			(start -0.15 0.4)
			(end 0.15 0.4)
			(stroke
				(width 0.15)
				(type solid)
			)
			(layer "F.SilkS")
		)
		(fp_line
			(start -0.15 -0.4)
			(end 0.15 -0.4)
			(stroke
				(width 0.15)
				(type solid)
			)
			(layer "F.SilkS")
		)
		(fp_rect
			(start -1.25 -0.65)
			(end 1.25 0.65)
			(stroke
				(width 0.05)
				(type solid)
			)
			(fill no)
			(layer "F.CrtYd")
		)
		(fp_rect
			(start -0.8 -0.4)
			(end 0.8 0.4)
			(stroke
				(width 0.15)
				(type solid)
			)
			(fill no)
			(layer "F.Fab")
		)
		(fp_text user "License: Apache-2.0"
			(at -1.682 5.895 270)
			(layer "F.Fab")
			(effects
				(font
					(size 0.7 0.7)
					(thickness 0.15)
				)
				(justify left bottom)
			)
		)
		(fp_text user "${REFERENCE}"
			(at -1.682 3.895 270)
			(layer "F.Fab")
			(effects
				(font
					(size 0.7 0.7)
					(thickness 0.15)
				)
				(justify left bottom)
			)
		)
		(fp_text user "Author: Antmicro"
			(at -1.682 4.894 270)
			(layer "F.Fab")
			(effects
				(font
					(size 0.7 0.7)
					(thickness 0.15)
				)
				(justify left bottom)
			)
		)
		(pad "1" smd roundrect
			(at -0.7 0 270)
			(size 0.8 1)
			(layers "F.Cu" "F.Mask" "F.Paste")
			(roundrect_rratio 0.2)
			(net 23 "GND")
			(pintype "passive")
		)
		(pad "2" smd roundrect
			(at 0.7 0 270)
			(size 0.8 1)
			(layers "F.Cu" "F.Mask" "F.Paste")
			(roundrect_rratio 0.2)
			(net 68 "/TB Controller - Power/VCC_0P9")
			(pintype "passive")
		)
	)
	(footprint "antmicro-footprints:R_0402_1005Metric"
		(layer "F.Cu")
		(at 145.8 128.2 -90)
		(descr "Resistor SMD 0402")
		(tags "resistor SMD 0402")
		(property "Reference" "R82"
			(at 3.2 -0.4 270)
			(layer "F.SilkS")
			(effects
				(font
					(size 0.7 0.7)
					(thickness 0.15)
				)
				(justify left bottom)
			)
		)
		(property "Value" "R_3k3_0402"
			(at -1.011843 1.772047 270)
			(layer "F.Fab")
			(effects
				(font
					(size 0.7 0.7)
					(thickness 0.15)
				)
				(justify left bottom)
			)
		)
		(property "Datasheet" "https://www.bourns.com/docs/product-datasheets/cr.pdf"
			(at 0 0 270)
			(layer "F.Fab")
			(hide yes)
			(effects
				(font
					(size 1.27 1.27)
					(thickness 0.15)
				)
			)
		)
		(property "Description" "SMD Chip Resistor, 3.3 kohm, ± 1%, 63 mW, 0402 [1005 Metric], Thick Film, General Purpose"
			(at 0 0 270)
			(layer "F.Fab")
			(hide yes)
			(effects
				(font
					(size 1.27 1.27)
					(thickness 0.15)
				)
			)
		)
		(property "MPN" "CR0402-FX-3301GLF"
			(at 0 0 270)
			(unlocked yes)
			(layer "F.Fab")
			(hide yes)
			(effects
				(font
					(size 1 1)
					(thickness 0.15)
				)
			)
		)
		(property "Manufacturer" "Bourns"
			(at 0 0 270)
			(unlocked yes)
			(layer "F.Fab")
			(hide yes)
			(effects
				(font
					(size 1 1)
					(thickness 0.15)
				)
			)
		)
		(property "License" "Apache-2.0"
			(at 0 0 270)
			(unlocked yes)
			(layer "F.Fab")
			(hide yes)
			(effects
				(font
					(size 1 1)
					(thickness 0.15)
				)
			)
		)
		(property "Val" "3k3"
			(at 0 0 270)
			(unlocked yes)
			(layer "F.Fab")
			(hide yes)
			(effects
				(font
					(size 1 1)
					(thickness 0.15)
				)
			)
		)
		(property "Tolerance" "1%"
			(at 0 0 270)
			(unlocked yes)
			(layer "F.Fab")
			(hide yes)
			(effects
				(font
					(size 1 1)
					(thickness 0.15)
				)
			)
		)
		(property "Author" "Antmicro"
			(at 0 0 270)
			(unlocked yes)
			(layer "F.Fab")
			(hide yes)
			(effects
				(font
					(size 1 1)
					(thickness 0.15)
				)
			)
		)
		(sheetname "/TB flash memory/")
		(sheetfile "flash-memory.kicad_sch")
		(attr smd)
		(fp_rect
			(start -0.925 -0.47)
			(end 0.925 0.47)
			(stroke
				(width 0.05)
				(type default)
			)
			(fill no)
			(layer "F.CrtYd")
		)
		(fp_rect
			(start -0.5 -0.25)
			(end 0.5 0.25)
			(stroke
				(width 0.15)
				(type solid)
			)
			(fill no)
			(layer "F.Fab")
		)
		(fp_text user "${REFERENCE}"
			(at -0.95 3.168 270)
			(layer "F.Fab")
			(effects
				(font
					(size 0.7 0.7)
					(thickness 0.15)
				)
				(justify left bottom)
			)
		)
		(fp_text user "License: Apache-2.0"
			(at -0.95 5.169 270)
			(layer "F.Fab")
			(effects
				(font
					(size 0.7 0.7)
					(thickness 0.15)
				)
				(justify left bottom)
			)
		)
		(fp_text user "Author: Antmicro"
			(at -0.95 4.169 270)
			(layer "F.Fab")
			(effects
				(font
					(size 0.7 0.7)
					(thickness 0.15)
				)
				(justify left bottom)
			)
		)
		(pad "1" smd roundrect
			(at -0.48 0 270)
			(size 0.59 0.64)
			(layers "F.Cu" "F.Mask" "F.Paste")
			(roundrect_rratio 0.25)
			(net 359 "/PD and TB DC-DC/TB_FLASH.~{CE}")
			(pintype "passive")
		)
		(pad "2" smd roundrect
			(at 0.48 0 270)
			(size 0.59 0.64)
			(layers "F.Cu" "F.Mask" "F.Paste")
			(roundrect_rratio 0.25)
			(net 57 "+3V3_TB")
			(pintype "passive")
		)
	)
	(footprint "antmicro-footprints:C_0402_1005Metric"
		(layer "F.Cu")
		(at 117.8 128 180)
		(descr "Capacitor SMD 0402")
		(tags "capacitor SMD 0402")
		(property "Reference" "C51"
			(at -0.8 -0.2 180)
			(layer "F.SilkS")
			(effects
				(font
					(size 0.7 0.7)
					(thickness 0.15)
				)
				(justify left bottom)
			)
		)
		(property "Value" "C_220n_0402"
			(at -1.022927 2.155213 180)
			(layer "F.Fab")
			(effects
				(font
					(size 0.7 0.7)
					(thickness 0.15)
				)
				(justify left bottom)
			)
		)
		(property "Datasheet" "https://www.yageo.com/en/Chart/Download/pdf/CC0402KRX5R6BB224"
			(at 0 0 180)
			(layer "F.Fab")
			(hide yes)
			(effects
				(font
					(size 1.27 1.27)
					(thickness 0.15)
				)
			)
		)
		(property "Description" "SMD Multilayer Ceramic Capacitor, 0.22 µF, 10 V, 0402 [1005 Metric], ± 10%, X5R, CC Series"
			(at 0 0 180)
			(layer "F.Fab")
			(hide yes)
			(effects
				(font
					(size 1.27 1.27)
					(thickness 0.15)
				)
			)
		)
		(property "MPN" "CC0402KRX5R6BB224"
			(at 0 0 180)
			(unlocked yes)
			(layer "F.Fab")
			(hide yes)
			(effects
				(font
					(size 1 1)
					(thickness 0.15)
				)
			)
		)
		(property "Manufacturer" "YAGEO"
			(at 0 0 180)
			(unlocked yes)
			(layer "F.Fab")
			(hide yes)
			(effects
				(font
					(size 1 1)
					(thickness 0.15)
				)
			)
		)
		(property "License" "Apache-2.0"
			(at 0 0 180)
			(unlocked yes)
			(layer "F.Fab")
			(hide yes)
			(effects
				(font
					(size 1 1)
					(thickness 0.15)
				)
			)
		)
		(property "Val" "220n"
			(at 0 0 180)
			(unlocked yes)
			(layer "F.Fab")
			(hide yes)
			(effects
				(font
					(size 1 1)
					(thickness 0.15)
				)
			)
		)
		(property "Voltage" ""
			(at 0 0 180)
			(unlocked yes)
			(layer "F.Fab")
			(hide yes)
			(effects
				(font
					(size 1 1)
					(thickness 0.15)
				)
			)
		)
		(property "Dielectric" ""
			(at 0 0 180)
			(unlocked yes)
			(layer "F.Fab")
			(hide yes)
			(effects
				(font
					(size 1 1)
					(thickness 0.15)
				)
			)
		)
		(property "Author" "Antmicro"
			(at 0 0 180)
			(unlocked yes)
			(layer "F.Fab")
			(hide yes)
			(effects
				(font
					(size 1 1)
					(thickness 0.15)
				)
			)
		)
		(sheetname "/TB Controller/")
		(sheetfile "tb.kicad_sch")
		(attr smd)
		(fp_rect
			(start -0.925 -0.47)
			(end 0.925 0.47)
			(stroke
				(width 0.05)
				(type default)
			)
			(fill no)
			(layer "F.CrtYd")
		)
		(fp_line
			(start 0.504 0.248)
			(end -0.494 0.248)
			(stroke
				(width 0.15)
				(type solid)
			)
			(layer "F.Fab")
		)
		(fp_line
			(start 0.504 -0.25)
			(end 0.504 0.248)
			(stroke
				(width 0.15)
				(type solid)
			)
			(layer "F.Fab")
		)
		(fp_line
			(start -0.494 0.248)
			(end -0.494 -0.25)
			(stroke
				(width 0.15)
				(type solid)
			)
			(layer "F.Fab")
		)
		(fp_line
			(start -0.494 -0.25)
			(end 0.504 -0.25)
			(stroke
				(width 0.15)
				(type solid)
			)
			(layer "F.Fab")
		)
		(fp_text user "Author: Antmicro"
			(at -0.939 3.399 180)
			(layer "F.Fab")
			(effects
				(font
					(size 0.7 0.7)
					(thickness 0.15)
				)
				(justify left bottom)
			)
		)
		(fp_text user "License: Apache-2.0"
			(at -0.939 5.799 180)
			(layer "F.Fab")
			(effects
				(font
					(size 0.7 0.7)
					(thickness 0.15)
				)
				(justify left bottom)
			)
		)
		(fp_text user "${REFERENCE}"
			(at -0.939 4.599 180)
			(layer "F.Fab")
			(effects
				(font
					(size 0.7 0.7)
					(thickness 0.15)
				)
				(justify left bottom)
			)
		)
		(pad "1" smd roundrect
			(at -0.48 0 180)
			(size 0.59 0.64)
			(layers "F.Cu" "F.Mask" "F.Paste")
			(roundrect_rratio 0.25)
			(net 320 "/TB Controller/TB_PCIE_TX3_N")
			(pintype "passive")
		)
		(pad "2" smd roundrect
			(at 0.48 0 180)
			(size 0.59 0.64)
			(layers "F.Cu" "F.Mask" "F.Paste")
			(roundrect_rratio 0.25)
			(net 328 "/TB Controller/PCIex4.RX3-")
			(pintype "passive")
		)
	)
	(footprint "antmicro-footprints:C_0603_1608Metric_EIA"
		(layer "F.Cu")
		(at 158.2 105.600001 90)
		(descr "Capacitor SMD 0603, IPC-7351 Density Level A")
		(tags "Capacitor 0603")
		(property "Reference" "C137"
			(at -17.849995 13.250002 90)
			(layer "F.SilkS")
			(effects
				(font
					(size 0.7 0.7)
					(thickness 0.15)
				)
			)
		)
		(property "Value" "C_22u_16V_0603"
			(at -1.42757 1.770288 90)
			(layer "F.Fab")
			(effects
				(font
					(size 0.7 0.7)
					(thickness 0.15)
				)
				(justify left bottom)
			)
		)
		(property "Datasheet" "https://product.samsungsem.com/mlcc/CL10A226MO7JZN.do"
			(at 0 0 90)
			(layer "F.Fab")
			(hide yes)
			(effects
				(font
					(size 1.27 1.27)
					(thickness 0.15)
				)
			)
		)
		(property "Description" "SMD Multilayer Ceramic Capacitor"
			(at 0 0 90)
			(layer "F.Fab")
			(hide yes)
			(effects
				(font
					(size 1.27 1.27)
					(thickness 0.15)
				)
			)
		)
		(property "MPN" "CL10A226MO7JZNC"
			(at 0 0 90)
			(unlocked yes)
			(layer "F.Fab")
			(hide yes)
			(effects
				(font
					(size 1 1)
					(thickness 0.15)
				)
			)
		)
		(property "Manufacturer" "Samsung Electro-Mechanics"
			(at 0 0 90)
			(unlocked yes)
			(layer "F.Fab")
			(hide yes)
			(effects
				(font
					(size 1 1)
					(thickness 0.15)
				)
			)
		)
		(property "License" "Apache-2.0"
			(at 0 0 90)
			(unlocked yes)
			(layer "F.Fab")
			(hide yes)
			(effects
				(font
					(size 1 1)
					(thickness 0.15)
				)
			)
		)
		(property "Author" "Antmicro"
			(at 0 0 90)
			(unlocked yes)
			(layer "F.Fab")
			(hide yes)
			(effects
				(font
					(size 1 1)
					(thickness 0.15)
				)
			)
		)
		(property "Val" "22u"
			(at 0 0 90)
			(unlocked yes)
			(layer "F.Fab")
			(hide yes)
			(effects
				(font
					(size 1 1)
					(thickness 0.15)
				)
			)
		)
		(property "Voltage" "16V"
			(at 0 0 90)
			(unlocked yes)
			(layer "F.Fab")
			(hide yes)
			(effects
				(font
					(size 1 1)
					(thickness 0.15)
				)
			)
		)
		(property "Dielectric" ""
			(at 0 0 90)
			(unlocked yes)
			(layer "F.Fab")
			(hide yes)
			(effects
				(font
					(size 1 1)
					(thickness 0.15)
				)
			)
		)
		(sheetname "/X710 DCDC converters/")
		(sheetfile "DCDC_converters_X710.kicad_sch")
		(attr smd)
		(fp_line
			(start -0.15 -0.55)
			(end 0.15 -0.55)
			(stroke
				(width 0.15)
				(type solid)
			)
			(layer "F.SilkS")
		)
		(fp_line
			(start -0.15 0.55)
			(end 0.15 0.55)
			(stroke
				(width 0.15)
				(type solid)
			)
			(layer "F.SilkS")
		)
		(fp_rect
			(start -1.25 -0.65)
			(end 1.25 0.65)
			(stroke
				(width 0.05)
				(type solid)
			)
			(fill no)
			(layer "F.CrtYd")
		)
		(fp_rect
			(start -0.8 -0.45)
			(end 0.8 0.45)
			(stroke
				(width 0.15)
				(type solid)
			)
			(fill no)
			(layer "F.Fab")
		)
		(fp_text user "Author: Antmicro"
			(at -1.682 4.894 90)
			(layer "F.Fab")
			(effects
				(font
					(size 0.7 0.7)
					(thickness 0.15)
				)
				(justify left bottom)
			)
		)
		(fp_text user "${REFERENCE}"
			(at -1.682 3.895 90)
			(layer "F.Fab")
			(effects
				(font
					(size 0.7 0.7)
					(thickness 0.15)
				)
				(justify left bottom)
			)
		)
		(fp_text user "License: Apache-2.0"
			(at -1.682 5.895 90)
			(layer "F.Fab")
			(effects
				(font
					(size 0.7 0.7)
					(thickness 0.15)
				)
				(justify left bottom)
			)
		)
		(pad "1" smd roundrect
			(at -0.7 0 90)
			(size 0.8 1.1)
			(layers "F.Cu" "F.Mask" "F.Paste")
			(roundrect_rratio 0.2)
			(net 23 "GND")
			(pintype "passive")
		)
		(pad "2" smd roundrect
			(at 0.7 0 90)
			(size 0.8 1.1)
			(layers "F.Cu" "F.Mask" "F.Paste")
			(roundrect_rratio 0.2)
			(net 339 "/X710 DCDC converters/+1V0_OUT")
			(pintype "passive")
		)
	)
	(footprint "antmicro-footprints:C_0603_1608Metric"
		(layer "F.Cu")
		(at 151.654999 68.574999 -90)
		(descr "Capacitor SMD 0603")
		(tags "capacitor 0603")
		(property "Reference" "C226"
			(at -12.274999 -20.045 270)
			(layer "F.SilkS")
			(effects
				(font
					(size 0.7 0.7)
					(thickness 0.15)
				)
			)
		)
		(property "Value" "C_10u_10V_X7R_0603"
			(at -1.42757 1.770288 270)
			(layer "F.Fab")
			(effects
				(font
					(size 0.7 0.7)
					(thickness 0.15)
				)
				(justify left bottom)
			)
		)
		(property "Datasheet" "https://www.murata.com/products/productdetail?partno=GRM188Z71A106KA73%23"
			(at 0 0 270)
			(layer "F.Fab")
			(hide yes)
			(effects
				(font
					(size 1.27 1.27)
					(thickness 0.15)
				)
			)
		)
		(property "Description" "SMD Multilayer Ceramic Capacitor,  10µF, 10V, 0603, ±10%, X7R"
			(at 0 0 270)
			(layer "F.Fab")
			(hide yes)
			(effects
				(font
					(size 1.27 1.27)
					(thickness 0.15)
				)
			)
		)
		(property "MPN" "GRM188Z71A106KA73D"
			(at 0 0 270)
			(unlocked yes)
			(layer "F.Fab")
			(hide yes)
			(effects
				(font
					(size 1 1)
					(thickness 0.15)
				)
			)
		)
		(property "Val" "10u"
			(at 0 0 270)
			(unlocked yes)
			(layer "F.Fab")
			(hide yes)
			(effects
				(font
					(size 1 1)
					(thickness 0.15)
				)
			)
		)
		(property "Voltage" "10V"
			(at 0 0 270)
			(unlocked yes)
			(layer "F.Fab")
			(hide yes)
			(effects
				(font
					(size 1 1)
					(thickness 0.15)
				)
			)
		)
		(property "Dielectric" "X7R"
			(at 0 0 270)
			(unlocked yes)
			(layer "F.Fab")
			(hide yes)
			(effects
				(font
					(size 1 1)
					(thickness 0.15)
				)
			)
		)
		(property "Manufacturer" "Murata"
			(at 0 0 270)
			(unlocked yes)
			(layer "F.Fab")
			(hide yes)
			(effects
				(font
					(size 1 1)
					(thickness 0.15)
				)
			)
		)
		(property "License" "Apache-2.0"
			(at 0 0 270)
			(unlocked yes)
			(layer "F.Fab")
			(hide yes)
			(effects
				(font
					(size 1 1)
					(thickness 0.15)
				)
			)
		)
		(property "Author" "Antmicro"
			(at 0 0 270)
			(unlocked yes)
			(layer "F.Fab")
			(hide yes)
			(effects
				(font
					(size 1 1)
					(thickness 0.15)
				)
			)
		)
		(sheetname "/X710-AT2 power/")
		(sheetfile "x710-at2-power.kicad_sch")
		(attr smd)
		(fp_line
			(start -0.15 0.4)
			(end 0.15 0.4)
			(stroke
				(width 0.15)
				(type solid)
			)
			(layer "F.SilkS")
		)
		(fp_line
			(start -0.15 -0.4)
			(end 0.15 -0.4)
			(stroke
				(width 0.15)
				(type solid)
			)
			(layer "F.SilkS")
		)
		(fp_rect
			(start -1.25 -0.65)
			(end 1.25 0.65)
			(stroke
				(width 0.05)
				(type solid)
			)
			(fill no)
			(layer "F.CrtYd")
		)
		(fp_rect
			(start -0.8 -0.4)
			(end 0.8 0.4)
			(stroke
				(width 0.15)
				(type solid)
			)
			(fill no)
			(layer "F.Fab")
		)
		(fp_text user "${REFERENCE}"
			(at -1.682 3.895 270)
			(layer "F.Fab")
			(effects
				(font
					(size 0.7 0.7)
					(thickness 0.15)
				)
				(justify left bottom)
			)
		)
		(fp_text user "Author: Antmicro"
			(at -1.682 4.894 270)
			(layer "F.Fab")
			(effects
				(font
					(size 0.7 0.7)
					(thickness 0.15)
				)
				(justify left bottom)
			)
		)
		(fp_text user "License: Apache-2.0"
			(at -1.682 5.895 270)
			(layer "F.Fab")
			(effects
				(font
					(size 0.7 0.7)
					(thickness 0.15)
				)
				(justify left bottom)
			)
		)
		(pad "1" smd roundrect
			(at -0.7 0 270)
			(size 0.8 1)
			(layers "F.Cu" "F.Mask" "F.Paste")
			(roundrect_rratio 0.2)
			(net 23 "GND")
			(pintype "passive")
		)
		(pad "2" smd roundrect
			(at 0.7 0 270)
			(size 0.8 1)
			(layers "F.Cu" "F.Mask" "F.Paste")
			(roundrect_rratio 0.2)
			(net 7 "+3V3")
			(pintype "passive")
		)
	)
	(footprint "antmicro-footprints:TP_SMD_0.75mm"
		(layer "F.Cu")
		(at 142.9 122.25 180)
		(property "Reference" "TP4"
			(at 0 0.85 180)
			(layer "F.SilkS")
			(effects
				(font
					(size 0.7 0.7)
					(thickness 0.15)
				)
				(justify left bottom)
			)
		)
		(property "Value" "TP_0.75mm_SMD"
			(at 0 1.2 180)
			(layer "F.Fab")
			(effects
				(font
					(size 0.7 0.7)
					(thickness 0.15)
				)
				(justify left bottom)
			)
		)
		(property "Description" "SMT test point"
			(at 0 0 180)
			(layer "F.Fab")
			(hide yes)
			(effects
				(font
					(size 1.27 1.27)
					(thickness 0.15)
				)
			)
		)
		(property "License" "Apache-2.0"
			(at 0 0 180)
			(unlocked yes)
			(layer "F.Fab")
			(hide yes)
			(effects
				(font
					(size 1 1)
					(thickness 0.15)
				)
			)
		)
		(property "Manufacturer" ""
			(at 0 0 180)
			(unlocked yes)
			(layer "F.Fab")
			(hide yes)
			(effects
				(font
					(size 1 1)
					(thickness 0.15)
				)
			)
		)
		(property "MPN" ""
			(at 0 0 180)
			(unlocked yes)
			(layer "F.Fab")
			(hide yes)
			(effects
				(font
					(size 1 1)
					(thickness 0.15)
				)
			)
		)
		(property "Author" "Antmicro"
			(at 0 0 180)
			(unlocked yes)
			(layer "F.Fab")
			(hide yes)
			(effects
				(font
					(size 1 1)
					(thickness 0.15)
				)
			)
		)
		(sheetname "/TB Controller - Power/")
		(sheetfile "tb-power.kicad_sch")
		(attr exclude_from_pos_files exclude_from_bom)
		(fp_circle
			(center 0 0)
			(end 0.475 0)
			(stroke
				(width 0.05)
				(type default)
			)
			(fill no)
			(layer "F.CrtYd")
		)
		(fp_text user "${REFERENCE}"
			(at -0.4 2.7 180)
			(layer "F.Fab")
			(effects
				(font
					(size 0.7 0.7)
					(thickness 0.15)
				)
				(justify left bottom)
			)
		)
		(fp_text user "License: Apache-2.0"
			(at -0.4 5.101 180)
			(layer "F.Fab")
			(effects
				(font
					(size 0.7 0.7)
					(thickness 0.15)
				)
				(justify left bottom)
			)
		)
		(fp_text user "Author: Antmicro"
			(at -0.4 3.901 180)
			(layer "F.Fab")
			(effects
				(font
					(size 0.7 0.7)
					(thickness 0.15)
				)
				(justify left bottom)
			)
		)
		(pad "1" smd circle
			(at 0 0 180)
			(size 0.75 0.75)
			(layers "F.Cu" "F.Mask")
			(net 68 "/TB Controller - Power/VCC_0P9")
			(pinfunction "1")
			(pintype "passive")
		)
	)
	(footprint "antmicro-footprints:C_0402_1005Metric"
		(layer "F.Cu")
		(at 165.265 64 -90)
		(descr "Capacitor SMD 0402")
		(tags "capacitor SMD 0402")
		(property "Reference" "C283"
			(at -5 0.065 270)
			(layer "F.SilkS")
			(effects
				(font
					(size 0.7 0.7)
					(thickness 0.15)
				)
				(justify left bottom)
			)
		)
		(property "Value" "C_100n_0402"
			(at -1.022927 2.155213 270)
			(layer "F.Fab")
			(effects
				(font
					(size 0.7 0.7)
					(thickness 0.15)
				)
				(justify left bottom)
			)
		)
		(property "Datasheet" "https://www.murata.com/products/productdetail?partno=GRM155R61H104KE14%23"
			(at 0 0 270)
			(layer "F.Fab")
			(hide yes)
			(effects
				(font
					(size 1.27 1.27)
					(thickness 0.15)
				)
			)
		)
		(property "Description" "SMD Multilayer Ceramic Capacitor, 0.1 µF, 50 V, 0402 [1005 Metric], ± 10%, X5R, GRM Series"
			(at 0 0 270)
			(layer "F.Fab")
			(hide yes)
			(effects
				(font
					(size 1.27 1.27)
					(thickness 0.15)
				)
			)
		)
		(property "MPN" "GRM155R61H104KE14D"
			(at 0 0 270)
			(unlocked yes)
			(layer "F.Fab")
			(hide yes)
			(effects
				(font
					(size 1 1)
					(thickness 0.15)
				)
			)
		)
		(property "Val" "100n"
			(at 0 0 270)
			(unlocked yes)
			(layer "F.Fab")
			(hide yes)
			(effects
				(font
					(size 1 1)
					(thickness 0.15)
				)
			)
		)
		(property "Voltage" "50V"
			(at 0 0 270)
			(unlocked yes)
			(layer "F.Fab")
			(hide yes)
			(effects
				(font
					(size 1 1)
					(thickness 0.15)
				)
			)
		)
		(property "Dielectric" "X5R"
			(at 0 0 270)
			(unlocked yes)
			(layer "F.Fab")
			(hide yes)
			(effects
				(font
					(size 1 1)
					(thickness 0.15)
				)
			)
		)
		(property "Manufacturer" "Murata"
			(at 0 0 270)
			(unlocked yes)
			(layer "F.Fab")
			(hide yes)
			(effects
				(font
					(size 1 1)
					(thickness 0.15)
				)
			)
		)
		(property "License" "Apache-2.0"
			(at 0 0 270)
			(unlocked yes)
			(layer "F.Fab")
			(hide yes)
			(effects
				(font
					(size 1 1)
					(thickness 0.15)
				)
			)
		)
		(property "Author" "Antmicro"
			(at 0 0 270)
			(unlocked yes)
			(layer "F.Fab")
			(hide yes)
			(effects
				(font
					(size 1 1)
					(thickness 0.15)
				)
			)
		)
		(sheetname "/X710-AT2 10GbE/")
		(sheetfile "x710-at2-10gbe.kicad_sch")
		(attr smd)
		(fp_rect
			(start -0.925 -0.47)
			(end 0.925 0.47)
			(stroke
				(width 0.05)
				(type default)
			)
			(fill no)
			(layer "F.CrtYd")
		)
		(fp_line
			(start -0.494 0.248)
			(end -0.494 -0.25)
			(stroke
				(width 0.15)
				(type solid)
			)
			(layer "F.Fab")
		)
		(fp_line
			(start 0.504 0.248)
			(end -0.494 0.248)
			(stroke
				(width 0.15)
				(type solid)
			)
			(layer "F.Fab")
		)
		(fp_line
			(start -0.494 -0.25)
			(end 0.504 -0.25)
			(stroke
				(width 0.15)
				(type solid)
			)
			(layer "F.Fab")
		)
		(fp_line
			(start 0.504 -0.25)
			(end 0.504 0.248)
			(stroke
				(width 0.15)
				(type solid)
			)
			(layer "F.Fab")
		)
		(fp_text user "License: Apache-2.0"
			(at -0.939 5.799 270)
			(layer "F.Fab")
			(effects
				(font
					(size 0.7 0.7)
					(thickness 0.15)
				)
				(justify left bottom)
			)
		)
		(fp_text user "Author: Antmicro"
			(at -0.939 3.399 270)
			(layer "F.Fab")
			(effects
				(font
					(size 0.7 0.7)
					(thickness 0.15)
				)
				(justify left bottom)
			)
		)
		(fp_text user "${REFERENCE}"
			(at -0.939 4.599 270)
			(layer "F.Fab")
			(effects
				(font
					(size 0.7 0.7)
					(thickness 0.15)
				)
				(justify left bottom)
			)
		)
		(pad "1" smd roundrect
			(at -0.48 0 270)
			(size 0.59 0.64)
			(layers "F.Cu" "F.Mask" "F.Paste")
			(roundrect_rratio 0.25)
			(net 23 "GND")
			(pintype "passive")
		)
		(pad "2" smd roundrect
			(at 0.48 0 270)
			(size 0.59 0.64)
			(layers "F.Cu" "F.Mask" "F.Paste")
			(roundrect_rratio 0.25)
			(net 56 "/X710-AT2 10GbE/3V3_OSC")
			(pintype "passive")
		)
	)
	(footprint "antmicro-footprints:R_0402_1005Metric"
		(layer "F.Cu")
		(at 134 86.25 90)
		(descr "Resistor SMD 0402")
		(tags "resistor SMD 0402")
		(property "Reference" "R71"
			(at -1.8 -4.2 90)
			(layer "F.SilkS")
			(effects
				(font
					(size 0.7 0.7)
					(thickness 0.15)
				)
				(justify left bottom)
			)
		)
		(property "Value" "R_10k_0402"
			(at -1.011843 1.772047 90)
			(layer "F.Fab")
			(effects
				(font
					(size 0.7 0.7)
					(thickness 0.15)
				)
				(justify left bottom)
			)
		)
		(property "Datasheet" "https://www.bourns.com/docs/product-datasheets/cr.pdf"
			(at 0 0 90)
			(layer "F.Fab")
			(hide yes)
			(effects
				(font
					(size 1.27 1.27)
					(thickness 0.15)
				)
			)
		)
		(property "Description" "SMD Chip Resistor, 10 kohm, ± 1%, 62.5 mW, 0402 [1005 Metric], Thick Film, General Purpose"
			(at 0 0 90)
			(layer "F.Fab")
			(hide yes)
			(effects
				(font
					(size 1.27 1.27)
					(thickness 0.15)
				)
			)
		)
		(property "MPN" "CR0402-FX-1002GLF"
			(at 0 0 90)
			(unlocked yes)
			(layer "F.Fab")
			(hide yes)
			(effects
				(font
					(size 1 1)
					(thickness 0.15)
				)
			)
		)
		(property "Manufacturer" "Bourns"
			(at 0 0 90)
			(unlocked yes)
			(layer "F.Fab")
			(hide yes)
			(effects
				(font
					(size 1 1)
					(thickness 0.15)
				)
			)
		)
		(property "License" "Apache-2.0"
			(at 0 0 90)
			(unlocked yes)
			(layer "F.Fab")
			(hide yes)
			(effects
				(font
					(size 1 1)
					(thickness 0.15)
				)
			)
		)
		(property "Author" "Antmicro"
			(at 0 0 90)
			(unlocked yes)
			(layer "F.Fab")
			(hide yes)
			(effects
				(font
					(size 1 1)
					(thickness 0.15)
				)
			)
		)
		(property "Val" "10k"
			(at 0 0 90)
			(unlocked yes)
			(layer "F.Fab")
			(hide yes)
			(effects
				(font
					(size 1 1)
					(thickness 0.15)
				)
			)
		)
		(property "Tolerance" "1%"
			(at 0 0 90)
			(unlocked yes)
			(layer "F.Fab")
			(hide yes)
			(effects
				(font
					(size 1 1)
					(thickness 0.15)
				)
			)
		)
		(sheetname "/TB Controller/")
		(sheetfile "tb.kicad_sch")
		(attr smd)
		(fp_rect
			(start -0.925 -0.47)
			(end 0.925 0.47)
			(stroke
				(width 0.05)
				(type default)
			)
			(fill no)
			(layer "F.CrtYd")
		)
		(fp_rect
			(start -0.5 -0.25)
			(end 0.5 0.25)
			(stroke
				(width 0.15)
				(type solid)
			)
			(fill no)
			(layer "F.Fab")
		)
		(fp_text user "Author: Antmicro"
			(at -0.95 4.169 90)
			(layer "F.Fab")
			(effects
				(font
					(size 0.7 0.7)
					(thickness 0.15)
				)
				(justify left bottom)
			)
		)
		(fp_text user "${REFERENCE}"
			(at -0.95 3.168 90)
			(layer "F.Fab")
			(effects
				(font
					(size 0.7 0.7)
					(thickness 0.15)
				)
				(justify left bottom)
			)
		)
		(fp_text user "License: Apache-2.0"
			(at -0.95 5.169 90)
			(layer "F.Fab")
			(effects
				(font
					(size 0.7 0.7)
					(thickness 0.15)
				)
				(justify left bottom)
			)
		)
		(pad "1" smd roundrect
			(at -0.48 0 90)
			(size 0.59 0.64)
			(layers "F.Cu" "F.Mask" "F.Paste")
			(roundrect_rratio 0.25)
			(net 23 "GND")
			(pintype "passive")
		)
		(pad "2" smd roundrect
			(at 0.48 0 90)
			(size 0.59 0.64)
			(layers "F.Cu" "F.Mask" "F.Paste")
			(roundrect_rratio 0.25)
			(net 392 "/TB Controller/~{PE_RST}")
			(pintype "passive")
		)
	)
	(footprint "antmicro-footprints:R_0402_1005Metric"
		(layer "F.Cu")
		(at 117 66.495 180)
		(descr "Resistor SMD 0402")
		(tags "resistor SMD 0402")
		(property "Reference" "R133"
			(at -3 -1.4 180)
			(layer "F.SilkS")
			(effects
				(font
					(size 0.7 0.7)
					(thickness 0.15)
				)
				(justify left bottom)
			)
		)
		(property "Value" "R_1k_0402"
			(at -1.011843 1.772047 180)
			(layer "F.Fab")
			(effects
				(font
					(size 0.7 0.7)
					(thickness 0.15)
				)
				(justify left bottom)
			)
		)
		(property "Datasheet" "https://www.bourns.com/docs/product-datasheets/cr.pdf"
			(at 0 0 180)
			(layer "F.Fab")
			(hide yes)
			(effects
				(font
					(size 1.27 1.27)
					(thickness 0.15)
				)
			)
		)
		(property "Description" "SMD Chip Resistor, 1 kohm, ± 1%, 63 mW, 0402 [1005 Metric], Thick Film, General Purpose"
			(at 0 0 180)
			(layer "F.Fab")
			(hide yes)
			(effects
				(font
					(size 1.27 1.27)
					(thickness 0.15)
				)
			)
		)
		(property "MPN" "CR0402-FX-1001GLF"
			(at 0 0 180)
			(unlocked yes)
			(layer "F.Fab")
			(hide yes)
			(effects
				(font
					(size 1 1)
					(thickness 0.15)
				)
			)
		)
		(property "Manufacturer" "Bourns"
			(at 0 0 180)
			(unlocked yes)
			(layer "F.Fab")
			(hide yes)
			(effects
				(font
					(size 1 1)
					(thickness 0.15)
				)
			)
		)
		(property "License" "Apache-2.0"
			(at 0 0 180)
			(unlocked yes)
			(layer "F.Fab")
			(hide yes)
			(effects
				(font
					(size 1 1)
					(thickness 0.15)
				)
			)
		)
		(property "Author" "Antmicro"
			(at 0 0 180)
			(unlocked yes)
			(layer "F.Fab")
			(hide yes)
			(effects
				(font
					(size 1 1)
					(thickness 0.15)
				)
			)
		)
		(property "Val" "1k"
			(at 0 0 180)
			(unlocked yes)
			(layer "F.Fab")
			(hide yes)
			(effects
				(font
					(size 1 1)
					(thickness 0.15)
				)
			)
		)
		(property "Tolerance" "1%"
			(at 0 0 180)
			(unlocked yes)
			(layer "F.Fab")
			(hide yes)
			(effects
				(font
					(size 1 1)
					(thickness 0.15)
				)
			)
		)
		(sheetname "/X710-AT2 RSVD/")
		(sheetfile "x710-at2-rsvd.kicad_sch")
		(attr smd)
		(fp_rect
			(start -0.925 -0.47)
			(end 0.925 0.47)
			(stroke
				(width 0.05)
				(type default)
			)
			(fill no)
			(layer "F.CrtYd")
		)
		(fp_rect
			(start -0.5 -0.25)
			(end 0.5 0.25)
			(stroke
				(width 0.15)
				(type solid)
			)
			(fill no)
			(layer "F.Fab")
		)
		(fp_text user "${REFERENCE}"
			(at -0.95 3.168 180)
			(layer "F.Fab")
			(effects
				(font
					(size 0.7 0.7)
					(thickness 0.15)
				)
				(justify left bottom)
			)
		)
		(fp_text user "License: Apache-2.0"
			(at -0.95 5.169 180)
			(layer "F.Fab")
			(effects
				(font
					(size 0.7 0.7)
					(thickness 0.15)
				)
				(justify left bottom)
			)
		)
		(fp_text user "Author: Antmicro"
			(at -0.95 4.169 180)
			(layer "F.Fab")
			(effects
				(font
					(size 0.7 0.7)
					(thickness 0.15)
				)
				(justify left bottom)
			)
		)
		(pad "1" smd roundrect
			(at -0.48 0 180)
			(size 0.59 0.64)
			(layers "F.Cu" "F.Mask" "F.Paste")
			(roundrect_rratio 0.25)
			(net 90 "/X710-AT2 RSVD/DEBUG_W7")
			(pintype "passive")
		)
		(pad "2" smd roundrect
			(at 0.48 0 180)
			(size 0.59 0.64)
			(layers "F.Cu" "F.Mask" "F.Paste")
			(roundrect_rratio 0.25)
			(net 86 "/X710-AT2 RSVD/DEBUG_EN")
			(pintype "passive")
		)
	)
	(footprint "antmicro-footprints:R_0402_1005Metric"
		(layer "B.Cu")
		(at 154.58 146.66 90)
		(descr "Resistor SMD 0402")
		(tags "resistor SMD 0402")
		(property "Reference" "R210"
			(at -1.09 0.42 270)
			(layer "B.SilkS")
			(effects
				(font
					(size 0.7 0.7)
					(thickness 0.15)
				)
				(justify left bottom mirror)
			)
		)
		(property "Value" "R_220R_0402"
			(at -1.011843 -1.772047 270)
			(layer "B.Fab")
			(effects
				(font
					(size 0.7 0.7)
					(thickness 0.15)
				)
				(justify left bottom mirror)
			)
		)
		(property "Datasheet" "https://www.bourns.com/docs/product-datasheets/cr.pdf"
			(at 0 0 270)
			(layer "B.Fab")
			(hide yes)
			(effects
				(font
					(size 1.27 1.27)
					(thickness 0.15)
				)
				(justify mirror)
			)
		)
		(property "Description" "SMD Chip Resistor, 220 ohm, ± 1%, 62.5 mW, 0402 [1005 Metric], Thick Film, General Purpose"
			(at 0 0 270)
			(layer "B.Fab")
			(hide yes)
			(effects
				(font
					(size 1.27 1.27)
					(thickness 0.15)
				)
				(justify mirror)
			)
		)
		(property "MPN" "CR0402-FX-2200GLF"
			(at 0 0 90)
			(unlocked yes)
			(layer "B.Fab")
			(hide yes)
			(effects
				(font
					(size 1 1)
					(thickness 0.15)
				)
				(justify mirror)
			)
		)
		(property "Manufacturer" "Bourns"
			(at 0 0 90)
			(unlocked yes)
			(layer "B.Fab")
			(hide yes)
			(effects
				(font
					(size 1 1)
					(thickness 0.15)
				)
				(justify mirror)
			)
		)
		(property "License" "Apache-2.0"
			(at 0 0 90)
			(unlocked yes)
			(layer "B.Fab")
			(hide yes)
			(effects
				(font
					(size 1 1)
					(thickness 0.15)
				)
				(justify mirror)
			)
		)
		(property "Author" "Antmicro"
			(at 0 0 90)
			(unlocked yes)
			(layer "B.Fab")
			(hide yes)
			(effects
				(font
					(size 1 1)
					(thickness 0.15)
				)
				(justify mirror)
			)
		)
		(property "Val" "220R"
			(at 0 0 90)
			(unlocked yes)
			(layer "B.Fab")
			(hide yes)
			(effects
				(font
					(size 1 1)
					(thickness 0.15)
				)
				(justify mirror)
			)
		)
		(property "Tolerance" "1%"
			(at 0 0 90)
			(unlocked yes)
			(layer "B.Fab")
			(hide yes)
			(effects
				(font
					(size 1 1)
					(thickness 0.15)
				)
				(justify mirror)
			)
		)
		(sheetname "/2xRJ45/")
		(sheetfile "2xrj45.kicad_sch")
		(attr smd)
		(fp_rect
			(start -0.925 0.47)
			(end 0.925 -0.47)
			(stroke
				(width 0.05)
				(type default)
			)
			(fill no)
			(layer "B.CrtYd")
		)
		(fp_rect
			(start -0.5 0.25)
			(end 0.5 -0.25)
			(stroke
				(width 0.15)
				(type solid)
			)
			(fill no)
			(layer "B.Fab")
		)
		(fp_text user "License: Apache-2.0"
			(at -0.95 -5.169 270)
			(layer "B.Fab")
			(effects
				(font
					(size 0.7 0.7)
					(thickness 0.15)
				)
				(justify left bottom mirror)
			)
		)
		(fp_text user "${REFERENCE}"
			(at -0.95 -3.168 270)
			(layer "B.Fab")
			(effects
				(font
					(size 0.7 0.7)
					(thickness 0.15)
				)
				(justify left bottom mirror)
			)
		)
		(fp_text user "Author: Antmicro"
			(at -0.95 -4.169 270)
			(layer "B.Fab")
			(effects
				(font
					(size 0.7 0.7)
					(thickness 0.15)
				)
				(justify left bottom mirror)
			)
		)
		(pad "1" smd roundrect
			(at -0.48 0 90)
			(size 0.59 0.64)
			(layers "B.Cu" "B.Mask" "B.Paste")
			(roundrect_rratio 0.25)
			(net 406 "Net-(J3-LED_YG_Y-)")
			(pintype "passive")
		)
		(pad "2" smd roundrect
			(at 0.48 0 90)
			(size 0.59 0.64)
			(layers "B.Cu" "B.Mask" "B.Paste")
			(roundrect_rratio 0.25)
			(net 128 "/2xRJ45/~{P0_LINK_LESS_THAN_10G}")
			(pintype "passive")
		)
	)
	(footprint "antmicro-footprints:C_0402_1005Metric"
		(layer "B.Cu")
		(at 156.111866 85.165117 180)
		(descr "Capacitor SMD 0402")
		(tags "capacitor SMD 0402")
		(property "Reference" "C196"
			(at -19.873134 -9.464883 0)
			(layer "B.SilkS")
			(effects
				(font
					(size 0.7 0.7)
					(thickness 0.15)
				)
				(justify mirror)
			)
		)
		(property "Value" "C_1u_25V_0402"
			(at -1.022927 -2.155213 0)
			(layer "B.Fab")
			(effects
				(font
					(size 0.7 0.7)
					(thickness 0.15)
				)
				(justify left bottom mirror)
			)
		)
		(property "Datasheet" "https://www.murata.com/products/productdetail?partno=GRM155R61E105KE11%23"
			(at 0 0 0)
			(layer "B.Fab")
			(hide yes)
			(effects
				(font
					(size 1.27 1.27)
					(thickness 0.15)
				)
				(justify mirror)
			)
		)
		(property "Description" "SMD Multilayer Ceramic Capacitor, 1 µF, 25 V, 0402 [1005 Metric], ± 10%, X5R, GRM Series"
			(at 0 0 0)
			(layer "B.Fab")
			(hide yes)
			(effects
				(font
					(size 1.27 1.27)
					(thickness 0.15)
				)
				(justify mirror)
			)
		)
		(property "MPN" "GRM155R61E105KE11J"
			(at 0 0 180)
			(unlocked yes)
			(layer "B.Fab")
			(hide yes)
			(effects
				(font
					(size 1 1)
					(thickness 0.15)
				)
				(justify mirror)
			)
		)
		(property "Manufacturer" "Murata"
			(at 0 0 180)
			(unlocked yes)
			(layer "B.Fab")
			(hide yes)
			(effects
				(font
					(size 1 1)
					(thickness 0.15)
				)
				(justify mirror)
			)
		)
		(property "License" "Apache-2.0"
			(at 0 0 180)
			(unlocked yes)
			(layer "B.Fab")
			(hide yes)
			(effects
				(font
					(size 1 1)
					(thickness 0.15)
				)
				(justify mirror)
			)
		)
		(property "Author" "Antmicro"
			(at 0 0 180)
			(unlocked yes)
			(layer "B.Fab")
			(hide yes)
			(effects
				(font
					(size 1 1)
					(thickness 0.15)
				)
				(justify mirror)
			)
		)
		(property "Val" "1u"
			(at 0 0 180)
			(unlocked yes)
			(layer "B.Fab")
			(hide yes)
			(effects
				(font
					(size 1 1)
					(thickness 0.15)
				)
				(justify mirror)
			)
		)
		(property "Voltage" "25V"
			(at 0 0 180)
			(unlocked yes)
			(layer "B.Fab")
			(hide yes)
			(effects
				(font
					(size 1 1)
					(thickness 0.15)
				)
				(justify mirror)
			)
		)
		(property "Dielectric" "X5R"
			(at 0 0 180)
			(unlocked yes)
			(layer "B.Fab")
			(hide yes)
			(effects
				(font
					(size 1 1)
					(thickness 0.15)
				)
				(justify mirror)
			)
		)
		(sheetname "/X710-AT2 power/")
		(sheetfile "x710-at2-power.kicad_sch")
		(attr smd)
		(fp_rect
			(start -0.925 0.47)
			(end 0.925 -0.47)
			(stroke
				(width 0.05)
				(type default)
			)
			(fill no)
			(layer "B.CrtYd")
		)
		(fp_line
			(start 0.504 0.25)
			(end 0.504 -0.248)
			(stroke
				(width 0.15)
				(type solid)
			)
			(layer "B.Fab")
		)
		(fp_line
			(start 0.504 -0.248)
			(end -0.494 -0.248)
			(stroke
				(width 0.15)
				(type solid)
			)
			(layer "B.Fab")
		)
		(fp_line
			(start -0.494 0.25)
			(end 0.504 0.25)
			(stroke
				(width 0.15)
				(type solid)
			)
			(layer "B.Fab")
		)
		(fp_line
			(start -0.494 -0.248)
			(end -0.494 0.25)
			(stroke
				(width 0.15)
				(type solid)
			)
			(layer "B.Fab")
		)
		(fp_text user "${REFERENCE}"
			(at -0.939 -4.599 0)
			(layer "B.Fab")
			(effects
				(font
					(size 0.7 0.7)
					(thickness 0.15)
				)
				(justify left bottom mirror)
			)
		)
		(fp_text user "Author: Antmicro"
			(at -0.939 -3.399 0)
			(layer "B.Fab")
			(effects
				(font
					(size 0.7 0.7)
					(thickness 0.15)
				)
				(justify left bottom mirror)
			)
		)
		(fp_text user "License: Apache-2.0"
			(at -0.939 -5.799 0)
			(layer "B.Fab")
			(effects
				(font
					(size 0.7 0.7)
					(thickness 0.15)
				)
				(justify left bottom mirror)
			)
		)
		(pad "1" smd roundrect
			(at -0.48 0 180)
			(size 0.59 0.64)
			(layers "B.Cu" "B.Mask" "B.Paste")
			(roundrect_rratio 0.25)
			(net 23 "GND")
			(pintype "passive")
		)
		(pad "2" smd roundrect
			(at 0.48 0 180)
			(size 0.59 0.64)
			(layers "B.Cu" "B.Mask" "B.Paste")
			(roundrect_rratio 0.25)
			(net 6 "DVDD")
			(pintype "passive")
		)
	)
	(footprint "antmicro-footprints:C_Pol_EIA-A"
		(layer "B.Cu")
		(at 155 99.75 180)
		(property "Reference" "C77"
			(at 2 0 0)
			(layer "B.SilkS")
			(effects
				(font
					(size 0.7 0.7)
					(thickness 0.15)
				)
				(justify left bottom mirror)
			)
		)
		(property "Value" "C_Pol_100u_6V_KEMET-T490-A"
			(at 0 -2 0)
			(layer "B.Fab")
			(effects
				(font
					(size 0.7 0.7)
					(thickness 0.15)
				)
				(justify left bottom mirror)
			)
		)
		(property "Datasheet" "https://www.kemet.com/en/us/capacitors/product/T490A107M006ATE800.html"
			(at 0 0 0)
			(layer "B.Fab")
			(hide yes)
			(effects
				(font
					(size 1.27 1.27)
					(thickness 0.15)
				)
				(justify mirror)
			)
		)
		(property "Description" "Surface Mount Tantalum Capacitor,  Solid SMD 6V 100uF 1206 20% ESR=800mOhms"
			(at 0 0 0)
			(layer "B.Fab")
			(hide yes)
			(effects
				(font
					(size 1.27 1.27)
					(thickness 0.15)
				)
				(justify mirror)
			)
		)
		(property "Val" "100u"
			(at 0 0 180)
			(unlocked yes)
			(layer "B.Fab")
			(hide yes)
			(effects
				(font
					(size 1 1)
					(thickness 0.15)
				)
				(justify mirror)
			)
		)
		(property "MPN" "T490A107M006ATE800"
			(at 0 0 180)
			(unlocked yes)
			(layer "B.Fab")
			(hide yes)
			(effects
				(font
					(size 1 1)
					(thickness 0.15)
				)
				(justify mirror)
			)
		)
		(property "Manufacturer" "KEMET"
			(at 0 0 180)
			(unlocked yes)
			(layer "B.Fab")
			(hide yes)
			(effects
				(font
					(size 1 1)
					(thickness 0.15)
				)
				(justify mirror)
			)
		)
		(property "License" "Apache-2.0"
			(at 0 0 180)
			(unlocked yes)
			(layer "B.Fab")
			(hide yes)
			(effects
				(font
					(size 1 1)
					(thickness 0.15)
				)
				(justify mirror)
			)
		)
		(property "Author" "Antmicro"
			(at 0 0 180)
			(unlocked yes)
			(layer "B.Fab")
			(hide yes)
			(effects
				(font
					(size 1 1)
					(thickness 0.15)
				)
				(justify mirror)
			)
		)
		(property "Voltage" "6V"
			(at 0 0 180)
			(unlocked yes)
			(layer "B.Fab")
			(hide yes)
			(effects
				(font
					(size 1 1)
					(thickness 0.15)
				)
				(justify mirror)
			)
		)
		(property "Dielectric" "template_dielectric"
			(at 0 0 180)
			(unlocked yes)
			(layer "B.Fab")
			(hide yes)
			(effects
				(font
					(size 1 1)
					(thickness 0.15)
				)
				(justify mirror)
			)
		)
		(sheetname "/X710-AT2 power/")
		(sheetfile "x710-at2-power.kicad_sch")
		(attr smd)
		(fp_line
			(start 1.5 0.75)
			(end 1.5 0.85)
			(stroke
				(width 0.12)
				(type solid)
			)
			(layer "B.SilkS")
		)
		(fp_line
			(start 1.5 -0.75)
			(end 1.5 -0.85)
			(stroke
				(width 0.12)
				(type solid)
			)
			(layer "B.SilkS")
		)
		(fp_line
			(start 1.5 -0.85)
			(end -1.5 -0.85)
			(stroke
				(width 0.12)
				(type solid)
			)
			(layer "B.SilkS")
		)
		(fp_line
			(start -1.5 0.85)
			(end 1.5 0.85)
			(stroke
				(width 0.12)
				(type solid)
			)
			(layer "B.SilkS")
		)
		(fp_line
			(start -1.5 0.75)
			(end -1.5 0.85)
			(stroke
				(width 0.12)
				(type solid)
			)
			(layer "B.SilkS")
		)
		(fp_line
			(start -1.5 -0.75)
			(end -1.5 -0.85)
			(stroke
				(width 0.12)
				(type solid)
			)
			(layer "B.SilkS")
		)
		(fp_line
			(start -1.95 1.25)
			(end -1.95 0.95)
			(stroke
				(width 0.12)
				(type solid)
			)
			(layer "B.SilkS")
		)
		(fp_line
			(start -2.1 1.1)
			(end -1.8 1.1)
			(stroke
				(width 0.12)
				(type solid)
			)
			(layer "B.SilkS")
		)
		(fp_line
			(start 2.05 0.85)
			(end 2.05 -0.85)
			(stroke
				(width 0.05)
				(type solid)
			)
			(layer "B.CrtYd")
		)
		(fp_line
			(start 2.05 0.85)
			(end 1.7 0.85)
			(stroke
				(width 0.05)
				(type solid)
			)
			(layer "B.CrtYd")
		)
		(fp_line
			(start 2.05 -0.85)
			(end 1.7 -0.85)
			(stroke
				(width 0.05)
				(type solid)
			)
			(layer "B.CrtYd")
		)
		(fp_line
			(start 1.7 1.05)
			(end -1.7 1.05)
			(stroke
				(width 0.05)
				(type solid)
			)
			(layer "B.CrtYd")
		)
		(fp_line
			(start 1.7 0.85)
			(end 1.7 1.05)
			(stroke
				(width 0.05)
				(type solid)
			)
			(layer "B.CrtYd")
		)
		(fp_line
			(start 1.7 -1.05)
			(end 1.7 -0.85)
			(stroke
				(width 0.05)
				(type solid)
			)
			(layer "B.CrtYd")
		)
		(fp_line
			(start 1.7 -1.05)
			(end -1.7 -1.05)
			(stroke
				(width 0.05)
				(type solid)
			)
			(layer "B.CrtYd")
		)
		(fp_line
			(start -1.7 0.85)
			(end -1.7 1.05)
			(stroke
				(width 0.05)
				(type solid)
			)
			(layer "B.CrtYd")
		)
		(fp_line
			(start -1.7 0.85)
			(end -2.05 0.85)
			(stroke
				(width 0.05)
				(type solid)
			)
			(layer "B.CrtYd")
		)
		(fp_line
			(start -1.7 -0.85)
			(end -2.05 -0.85)
			(stroke
				(width 0.05)
				(type solid)
			)
			(layer "B.CrtYd")
		)
		(fp_line
			(start -1.7 -1.05)
			(end -1.7 -0.85)
			(stroke
				(width 0.05)
				(type solid)
			)
			(layer "B.CrtYd")
		)
		(fp_line
			(start -2.05 0.85)
			(end -2.05 -0.85)
			(stroke
				(width 0.05)
				(type solid)
			)
			(layer "B.CrtYd")
		)
		(fp_rect
			(start -1.601 0.802)
			(end 1.6 -0.8)
			(stroke
				(width 0.1)
				(type solid)
			)
			(fill no)
			(layer "B.Fab")
		)
		(fp_text user "${REFERENCE}"
			(at -2.1 -4.198 0)
			(layer "B.Fab")
			(effects
				(font
					(size 0.7 0.7)
					(thickness 0.15)
				)
				(justify left bottom mirror)
			)
		)
		(fp_text user "Author: Antmicro"
			(at -2.1 -6.198 0)
			(layer "B.Fab")
			(effects
				(font
					(size 0.7 0.7)
					(thickness 0.15)
				)
				(justify left bottom mirror)
			)
		)
		(fp_text user "License: Apache-2.0"
			(at -2.1 -5.198 0)
			(layer "B.Fab")
			(effects
				(font
					(size 0.7 0.7)
					(thickness 0.15)
				)
				(justify left bottom mirror)
			)
		)
		(pad "1" smd roundrect
			(at -1.2 0 180)
			(size 1.2 1.2)
			(layers "B.Cu" "B.Mask" "B.Paste")
			(roundrect_rratio 0.1)
			(net 136 "+1V0")
			(pintype "passive")
		)
		(pad "2" smd roundrect
			(at 1.2 0 180)
			(size 1.2 1.2)
			(layers "B.Cu" "B.Mask" "B.Paste")
			(roundrect_rratio 0.1)
			(net 23 "GND")
			(pintype "passive")
		)
	)
	(footprint "antmicro-footprints:C_0402_1005Metric"
		(layer "B.Cu")
		(at 129.474998 120.05 -90)
		(descr "Capacitor SMD 0402")
		(tags "capacitor SMD 0402")
		(property "Reference" "C72"
			(at -7.700002 -21.900002 90)
			(layer "B.SilkS")
			(effects
				(font
					(size 0.7 0.7)
					(thickness 0.15)
				)
				(justify mirror)
			)
		)
		(property "Value" "C_1u_0402"
			(at -1.022927 -2.155213 90)
			(layer "B.Fab")
			(effects
				(font
					(size 0.7 0.7)
					(thickness 0.15)
				)
				(justify left bottom mirror)
			)
		)
		(property "Datasheet" "https://product.tdk.com/en/search/capacitor/ceramic/mlcc/info?part_no=C1005X6S1A105K050BC"
			(at 0 0 90)
			(layer "B.Fab")
			(hide yes)
			(effects
				(font
					(size 1.27 1.27)
					(thickness 0.15)
				)
				(justify mirror)
			)
		)
		(property "Description" "SMD Multilayer Ceramic Capacitor, 1 µF, 10 V, 0402 [1005 Metric], ± 10%, X6S, C"
			(at 0 0 90)
			(layer "B.Fab")
			(hide yes)
			(effects
				(font
					(size 1.27 1.27)
					(thickness 0.15)
				)
				(justify mirror)
			)
		)
		(property "MPN" "C1005X6S1A105K050BC"
			(at 0 0 270)
			(unlocked yes)
			(layer "B.Fab")
			(hide yes)
			(effects
				(font
					(size 1 1)
					(thickness 0.15)
				)
				(justify mirror)
			)
		)
		(property "Manufacturer" "TDK"
			(at 0 0 270)
			(unlocked yes)
			(layer "B.Fab")
			(hide yes)
			(effects
				(font
					(size 1 1)
					(thickness 0.15)
				)
				(justify mirror)
			)
		)
		(property "License" "Apache-2.0"
			(at 0 0 270)
			(unlocked yes)
			(layer "B.Fab")
			(hide yes)
			(effects
				(font
					(size 1 1)
					(thickness 0.15)
				)
				(justify mirror)
			)
		)
		(property "Val" "1u"
			(at 0 0 270)
			(unlocked yes)
			(layer "B.Fab")
			(hide yes)
			(effects
				(font
					(size 1 1)
					(thickness 0.15)
				)
				(justify mirror)
			)
		)
		(property "Voltage" ""
			(at 0 0 270)
			(unlocked yes)
			(layer "B.Fab")
			(hide yes)
			(effects
				(font
					(size 1 1)
					(thickness 0.15)
				)
				(justify mirror)
			)
		)
		(property "Dielectric" ""
			(at 0 0 270)
			(unlocked yes)
			(layer "B.Fab")
			(hide yes)
			(effects
				(font
					(size 1 1)
					(thickness 0.15)
				)
				(justify mirror)
			)
		)
		(property "Author" "Antmicro"
			(at 0 0 270)
			(unlocked yes)
			(layer "B.Fab")
			(hide yes)
			(effects
				(font
					(size 1 1)
					(thickness 0.15)
				)
				(justify mirror)
			)
		)
		(sheetname "/TB Controller - Power/")
		(sheetfile "tb-power.kicad_sch")
		(attr smd)
		(fp_rect
			(start -0.925 0.47)
			(end 0.925 -0.47)
			(stroke
				(width 0.05)
				(type default)
			)
			(fill no)
			(layer "B.CrtYd")
		)
		(fp_line
			(start -0.494 0.25)
			(end 0.504 0.25)
			(stroke
				(width 0.15)
				(type solid)
			)
			(layer "B.Fab")
		)
		(fp_line
			(start 0.504 0.25)
			(end 0.504 -0.248)
			(stroke
				(width 0.15)
				(type solid)
			)
			(layer "B.Fab")
		)
		(fp_line
			(start -0.494 -0.248)
			(end -0.494 0.25)
			(stroke
				(width 0.15)
				(type solid)
			)
			(layer "B.Fab")
		)
		(fp_line
			(start 0.504 -0.248)
			(end -0.494 -0.248)
			(stroke
				(width 0.15)
				(type solid)
			)
			(layer "B.Fab")
		)
		(fp_text user "Author: Antmicro"
			(at -0.939 -3.399 90)
			(layer "B.Fab")
			(effects
				(font
					(size 0.7 0.7)
					(thickness 0.15)
				)
				(justify left bottom mirror)
			)
		)
		(fp_text user "${REFERENCE}"
			(at -0.939 -4.599 90)
			(layer "B.Fab")
			(effects
				(font
					(size 0.7 0.7)
					(thickness 0.15)
				)
				(justify left bottom mirror)
			)
		)
		(fp_text user "License: Apache-2.0"
			(at -0.939 -5.799 90)
			(layer "B.Fab")
			(effects
				(font
					(size 0.7 0.7)
					(thickness 0.15)
				)
				(justify left bottom mirror)
			)
		)
		(pad "1" smd roundrect
			(at -0.48 0 270)
			(size 0.59 0.64)
			(layers "B.Cu" "B.Mask" "B.Paste")
			(roundrect_rratio 0.25)
			(net 23 "GND")
			(pintype "passive")
		)
		(pad "2" smd roundrect
			(at 0.48 0 270)
			(size 0.59 0.64)
			(layers "B.Cu" "B.Mask" "B.Paste")
			(roundrect_rratio 0.25)
			(net 404 "Net-(C58-Pad2)")
			(pintype "passive")
		)
	)
	(footprint "antmicro-footprints:C_0402_1005Metric"
		(layer "B.Cu")
		(at 131.424998 122.000002 -90)
		(descr "Capacitor SMD 0402")
		(tags "capacitor SMD 0402")
		(property "Reference" "C73"
			(at -7.700002 -21.900002 90)
			(layer "B.SilkS")
			(effects
				(font
					(size 0.7 0.7)
					(thickness 0.15)
				)
				(justify mirror)
			)
		)
		(property "Value" "C_1u_0402"
			(at -1.022927 -2.155213 90)
			(layer "B.Fab")
			(effects
				(font
					(size 0.7 0.7)
					(thickness 0.15)
				)
				(justify left bottom mirror)
			)
		)
		(property "Datasheet" "https://product.tdk.com/en/search/capacitor/ceramic/mlcc/info?part_no=C1005X6S1A105K050BC"
			(at 0 0 90)
			(layer "B.Fab")
			(hide yes)
			(effects
				(font
					(size 1.27 1.27)
					(thickness 0.15)
				)
				(justify mirror)
			)
		)
		(property "Description" "SMD Multilayer Ceramic Capacitor, 1 µF, 10 V, 0402 [1005 Metric], ± 10%, X6S, C"
			(at 0 0 90)
			(layer "B.Fab")
			(hide yes)
			(effects
				(font
					(size 1.27 1.27)
					(thickness 0.15)
				)
				(justify mirror)
			)
		)
		(property "MPN" "C1005X6S1A105K050BC"
			(at 0 0 270)
			(unlocked yes)
			(layer "B.Fab")
			(hide yes)
			(effects
				(font
					(size 1 1)
					(thickness 0.15)
				)
				(justify mirror)
			)
		)
		(property "Manufacturer" "TDK"
			(at 0 0 270)
			(unlocked yes)
			(layer "B.Fab")
			(hide yes)
			(effects
				(font
					(size 1 1)
					(thickness 0.15)
				)
				(justify mirror)
			)
		)
		(property "License" "Apache-2.0"
			(at 0 0 270)
			(unlocked yes)
			(layer "B.Fab")
			(hide yes)
			(effects
				(font
					(size 1 1)
					(thickness 0.15)
				)
				(justify mirror)
			)
		)
		(property "Val" "1u"
			(at 0 0 270)
			(unlocked yes)
			(layer "B.Fab")
			(hide yes)
			(effects
				(font
					(size 1 1)
					(thickness 0.15)
				)
				(justify mirror)
			)
		)
		(property "Voltage" ""
			(at 0 0 270)
			(unlocked yes)
			(layer "B.Fab")
			(hide yes)
			(effects
				(font
					(size 1 1)
					(thickness 0.15)
				)
				(justify mirror)
			)
		)
		(property "Dielectric" ""
			(at 0 0 270)
			(unlocked yes)
			(layer "B.Fab")
			(hide yes)
			(effects
				(font
					(size 1 1)
					(thickness 0.15)
				)
				(justify mirror)
			)
		)
		(property "Author" "Antmicro"
			(at 0 0 270)
			(unlocked yes)
			(layer "B.Fab")
			(hide yes)
			(effects
				(font
					(size 1 1)
					(thickness 0.15)
				)
				(justify mirror)
			)
		)
		(sheetname "/TB Controller - Power/")
		(sheetfile "tb-power.kicad_sch")
		(attr smd)
		(fp_rect
			(start -0.925 0.47)
			(end 0.925 -0.47)
			(stroke
				(width 0.05)
				(type default)
			)
			(fill no)
			(layer "B.CrtYd")
		)
		(fp_line
			(start -0.494 0.25)
			(end 0.504 0.25)
			(stroke
				(width 0.15)
				(type solid)
			)
			(layer "B.Fab")
		)
		(fp_line
			(start 0.504 0.25)
			(end 0.504 -0.248)
			(stroke
				(width 0.15)
				(type solid)
			)
			(layer "B.Fab")
		)
		(fp_line
			(start -0.494 -0.248)
			(end -0.494 0.25)
			(stroke
				(width 0.15)
				(type solid)
			)
			(layer "B.Fab")
		)
		(fp_line
			(start 0.504 -0.248)
			(end -0.494 -0.248)
			(stroke
				(width 0.15)
				(type solid)
			)
			(layer "B.Fab")
		)
		(fp_text user "License: Apache-2.0"
			(at -0.939 -5.799 90)
			(layer "B.Fab")
			(effects
				(font
					(size 0.7 0.7)
					(thickness 0.15)
				)
				(justify left bottom mirror)
			)
		)
		(fp_text user "${REFERENCE}"
			(at -0.939 -4.599 90)
			(layer "B.Fab")
			(effects
				(font
					(size 0.7 0.7)
					(thickness 0.15)
				)
				(justify left bottom mirror)
			)
		)
		(fp_text user "Author: Antmicro"
			(at -0.939 -3.399 90)
			(layer "B.Fab")
			(effects
				(font
					(size 0.7 0.7)
					(thickness 0.15)
				)
				(justify left bottom mirror)
			)
		)
		(pad "1" smd roundrect
			(at -0.48 0 270)
			(size 0.59 0.64)
			(layers "B.Cu" "B.Mask" "B.Paste")
			(roundrect_rratio 0.25)
			(net 23 "GND")
			(pintype "passive")
		)
		(pad "2" smd roundrect
			(at 0.48 0 270)
			(size 0.59 0.64)
			(layers "B.Cu" "B.Mask" "B.Paste")
			(roundrect_rratio 0.25)
			(net 179 "Net-(U4A-VCC3P3_LC)")
			(pintype "passive")
		)
	)
	(footprint "antmicro-footprints:C_0402_1005Metric"
		(layer "B.Cu")
		(at 159.381866 80.685116 -90)
		(descr "Capacitor SMD 0402")
		(tags "capacitor SMD 0402")
		(property "Reference" "C194"
			(at 8.814884 -20.618136 90)
			(layer "B.SilkS")
			(effects
				(font
					(size 0.7 0.7)
					(thickness 0.15)
				)
				(justify mirror)
			)
		)
		(property "Value" "C_1u_25V_0402"
			(at -1.022927 -2.155213 90)
			(layer "B.Fab")
			(effects
				(font
					(size 0.7 0.7)
					(thickness 0.15)
				)
				(justify left bottom mirror)
			)
		)
		(property "Datasheet" "https://www.murata.com/products/productdetail?partno=GRM155R61E105KE11%23"
			(at 0 0 90)
			(layer "B.Fab")
			(hide yes)
			(effects
				(font
					(size 1.27 1.27)
					(thickness 0.15)
				)
				(justify mirror)
			)
		)
		(property "Description" "SMD Multilayer Ceramic Capacitor, 1 µF, 25 V, 0402 [1005 Metric], ± 10%, X5R, GRM Series"
			(at 0 0 90)
			(layer "B.Fab")
			(hide yes)
			(effects
				(font
					(size 1.27 1.27)
					(thickness 0.15)
				)
				(justify mirror)
			)
		)
		(property "MPN" "GRM155R61E105KE11J"
			(at 0 0 270)
			(unlocked yes)
			(layer "B.Fab")
			(hide yes)
			(effects
				(font
					(size 1 1)
					(thickness 0.15)
				)
				(justify mirror)
			)
		)
		(property "Manufacturer" "Murata"
			(at 0 0 270)
			(unlocked yes)
			(layer "B.Fab")
			(hide yes)
			(effects
				(font
					(size 1 1)
					(thickness 0.15)
				)
				(justify mirror)
			)
		)
		(property "License" "Apache-2.0"
			(at 0 0 270)
			(unlocked yes)
			(layer "B.Fab")
			(hide yes)
			(effects
				(font
					(size 1 1)
					(thickness 0.15)
				)
				(justify mirror)
			)
		)
		(property "Author" "Antmicro"
			(at 0 0 270)
			(unlocked yes)
			(layer "B.Fab")
			(hide yes)
			(effects
				(font
					(size 1 1)
					(thickness 0.15)
				)
				(justify mirror)
			)
		)
		(property "Val" "1u"
			(at 0 0 270)
			(unlocked yes)
			(layer "B.Fab")
			(hide yes)
			(effects
				(font
					(size 1 1)
					(thickness 0.15)
				)
				(justify mirror)
			)
		)
		(property "Voltage" "25V"
			(at 0 0 270)
			(unlocked yes)
			(layer "B.Fab")
			(hide yes)
			(effects
				(font
					(size 1 1)
					(thickness 0.15)
				)
				(justify mirror)
			)
		)
		(property "Dielectric" "X5R"
			(at 0 0 270)
			(unlocked yes)
			(layer "B.Fab")
			(hide yes)
			(effects
				(font
					(size 1 1)
					(thickness 0.15)
				)
				(justify mirror)
			)
		)
		(sheetname "/X710-AT2 power/")
		(sheetfile "x710-at2-power.kicad_sch")
		(attr smd)
		(fp_rect
			(start -0.925 0.47)
			(end 0.925 -0.47)
			(stroke
				(width 0.05)
				(type default)
			)
			(fill no)
			(layer "B.CrtYd")
		)
		(fp_line
			(start -0.494 0.25)
			(end 0.504 0.25)
			(stroke
				(width 0.15)
				(type solid)
			)
			(layer "B.Fab")
		)
		(fp_line
			(start 0.504 0.25)
			(end 0.504 -0.248)
			(stroke
				(width 0.15)
				(type solid)
			)
			(layer "B.Fab")
		)
		(fp_line
			(start -0.494 -0.248)
			(end -0.494 0.25)
			(stroke
				(width 0.15)
				(type solid)
			)
			(layer "B.Fab")
		)
		(fp_line
			(start 0.504 -0.248)
			(end -0.494 -0.248)
			(stroke
				(width 0.15)
				(type solid)
			)
			(layer "B.Fab")
		)
		(fp_text user "${REFERENCE}"
			(at -0.939 -4.599 90)
			(layer "B.Fab")
			(effects
				(font
					(size 0.7 0.7)
					(thickness 0.15)
				)
				(justify left bottom mirror)
			)
		)
		(fp_text user "License: Apache-2.0"
			(at -0.939 -5.799 90)
			(layer "B.Fab")
			(effects
				(font
					(size 0.7 0.7)
					(thickness 0.15)
				)
				(justify left bottom mirror)
			)
		)
		(fp_text user "Author: Antmicro"
			(at -0.939 -3.399 90)
			(layer "B.Fab")
			(effects
				(font
					(size 0.7 0.7)
					(thickness 0.15)
				)
				(justify left bottom mirror)
			)
		)
		(pad "1" smd roundrect
			(at -0.48 0 270)
			(size 0.59 0.64)
			(layers "B.Cu" "B.Mask" "B.Paste")
			(roundrect_rratio 0.25)
			(net 23 "GND")
			(pintype "passive")
		)
		(pad "2" smd roundrect
			(at 0.48 0 270)
			(size 0.59 0.64)
			(layers "B.Cu" "B.Mask" "B.Paste")
			(roundrect_rratio 0.25)
			(net 14 "P1_AVDDL")
			(pintype "passive")
		)
	)
	(footprint "antmicro-footprints:R_0402_1005Metric"
		(layer "B.Cu")
		(at 135 93.4 90)
		(descr "Resistor SMD 0402")
		(tags "resistor SMD 0402")
		(property "Reference" "R87"
			(at -1 0.4 270)
			(layer "B.SilkS")
			(effects
				(font
					(size 0.7 0.7)
					(thickness 0.15)
				)
				(justify left bottom mirror)
			)
		)
		(property "Value" "R_100k_0402"
			(at -1.011843 -1.772047 270)
			(layer "B.Fab")
			(effects
				(font
					(size 0.7 0.7)
					(thickness 0.15)
				)
				(justify left bottom mirror)
			)
		)
		(property "Datasheet" "https://www.bourns.com/docs/product-datasheets/cr.pdf"
			(at 0 0 270)
			(layer "B.Fab")
			(hide yes)
			(effects
				(font
					(size 1.27 1.27)
					(thickness 0.15)
				)
				(justify mirror)
			)
		)
		(property "Description" "SMD Chip Resistor, 100 kohm, ± 1%, 62.5 mW, 0402 [1005 Metric], Thick Film, General Purpose"
			(at 0 0 270)
			(layer "B.Fab")
			(hide yes)
			(effects
				(font
					(size 1.27 1.27)
					(thickness 0.15)
				)
				(justify mirror)
			)
		)
		(property "MPN" "CR0402-FX-1003GLF"
			(at 0 0 90)
			(unlocked yes)
			(layer "B.Fab")
			(hide yes)
			(effects
				(font
					(size 1 1)
					(thickness 0.15)
				)
				(justify mirror)
			)
		)
		(property "Manufacturer" "Bourns"
			(at 0 0 90)
			(unlocked yes)
			(layer "B.Fab")
			(hide yes)
			(effects
				(font
					(size 1 1)
					(thickness 0.15)
				)
				(justify mirror)
			)
		)
		(property "License" "Apache-2.0"
			(at 0 0 90)
			(unlocked yes)
			(layer "B.Fab")
			(hide yes)
			(effects
				(font
					(size 1 1)
					(thickness 0.15)
				)
				(justify mirror)
			)
		)
		(property "Author" "Antmicro"
			(at 0 0 90)
			(unlocked yes)
			(layer "B.Fab")
			(hide yes)
			(effects
				(font
					(size 1 1)
					(thickness 0.15)
				)
				(justify mirror)
			)
		)
		(property "Val" "100k"
			(at 0 0 90)
			(unlocked yes)
			(layer "B.Fab")
			(hide yes)
			(effects
				(font
					(size 1 1)
					(thickness 0.15)
				)
				(justify mirror)
			)
		)
		(property "Tolerance" "1%"
			(at 0 0 90)
			(unlocked yes)
			(layer "B.Fab")
			(hide yes)
			(effects
				(font
					(size 1 1)
					(thickness 0.15)
				)
				(justify mirror)
			)
		)
		(sheetname "/X710 DCDC converters/")
		(sheetfile "DCDC_converters_X710.kicad_sch")
		(attr smd)
		(fp_rect
			(start -0.925 0.47)
			(end 0.925 -0.47)
			(stroke
				(width 0.05)
				(type default)
			)
			(fill no)
			(layer "B.CrtYd")
		)
		(fp_rect
			(start -0.5 0.25)
			(end 0.5 -0.25)
			(stroke
				(width 0.15)
				(type solid)
			)
			(fill no)
			(layer "B.Fab")
		)
		(fp_text user "Author: Antmicro"
			(at -0.95 -4.169 270)
			(layer "B.Fab")
			(effects
				(font
					(size 0.7 0.7)
					(thickness 0.15)
				)
				(justify left bottom mirror)
			)
		)
		(fp_text user "${REFERENCE}"
			(at -0.95 -3.168 270)
			(layer "B.Fab")
			(effects
				(font
					(size 0.7 0.7)
					(thickness 0.15)
				)
				(justify left bottom mirror)
			)
		)
		(fp_text user "License: Apache-2.0"
			(at -0.95 -5.169 270)
			(layer "B.Fab")
			(effects
				(font
					(size 0.7 0.7)
					(thickness 0.15)
				)
				(justify left bottom mirror)
			)
		)
		(pad "1" smd roundrect
			(at -0.48 0 90)
			(size 0.59 0.64)
			(layers "B.Cu" "B.Mask" "B.Paste")
			(roundrect_rratio 0.25)
			(net 378 "/X710 DCDC converters/3V3_PG")
			(pintype "passive")
		)
		(pad "2" smd roundrect
			(at 0.48 0 90)
			(size 0.59 0.64)
			(layers "B.Cu" "B.Mask" "B.Paste")
			(roundrect_rratio 0.25)
			(net 80 "/X710 DCDC converters/3V3_VCC")
			(pintype "passive")
		)
	)
	(footprint "antmicro-footprints:C_0402_1005Metric"
		(layer "B.Cu")
		(at 153.031866 76.260117 180)
		(descr "Capacitor SMD 0402")
		(tags "capacitor SMD 0402")
		(property "Reference" "C217"
			(at -21.168135 -9.464883 0)
			(layer "B.SilkS")
			(effects
				(font
					(size 0.7 0.7)
					(thickness 0.15)
				)
				(justify mirror)
			)
		)
		(property "Value" "C_1u_25V_0402"
			(at -1.022927 -2.155213 0)
			(layer "B.Fab")
			(effects
				(font
					(size 0.7 0.7)
					(thickness 0.15)
				)
				(justify left bottom mirror)
			)
		)
		(property "Datasheet" "https://www.murata.com/products/productdetail?partno=GRM155R61E105KE11%23"
			(at 0 0 0)
			(layer "B.Fab")
			(hide yes)
			(effects
				(font
					(size 1.27 1.27)
					(thickness 0.15)
				)
				(justify mirror)
			)
		)
		(property "Description" "SMD Multilayer Ceramic Capacitor, 1 µF, 25 V, 0402 [1005 Metric], ± 10%, X5R, GRM Series"
			(at 0 0 0)
			(layer "B.Fab")
			(hide yes)
			(effects
				(font
					(size 1.27 1.27)
					(thickness 0.15)
				)
				(justify mirror)
			)
		)
		(property "MPN" "GRM155R61E105KE11J"
			(at 0 0 180)
			(unlocked yes)
			(layer "B.Fab")
			(hide yes)
			(effects
				(font
					(size 1 1)
					(thickness 0.15)
				)
				(justify mirror)
			)
		)
		(property "Manufacturer" "Murata"
			(at 0 0 180)
			(unlocked yes)
			(layer "B.Fab")
			(hide yes)
			(effects
				(font
					(size 1 1)
					(thickness 0.15)
				)
				(justify mirror)
			)
		)
		(property "License" "Apache-2.0"
			(at 0 0 180)
			(unlocked yes)
			(layer "B.Fab")
			(hide yes)
			(effects
				(font
					(size 1 1)
					(thickness 0.15)
				)
				(justify mirror)
			)
		)
		(property "Author" "Antmicro"
			(at 0 0 180)
			(unlocked yes)
			(layer "B.Fab")
			(hide yes)
			(effects
				(font
					(size 1 1)
					(thickness 0.15)
				)
				(justify mirror)
			)
		)
		(property "Val" "1u"
			(at 0 0 180)
			(unlocked yes)
			(layer "B.Fab")
			(hide yes)
			(effects
				(font
					(size 1 1)
					(thickness 0.15)
				)
				(justify mirror)
			)
		)
		(property "Voltage" "25V"
			(at 0 0 180)
			(unlocked yes)
			(layer "B.Fab")
			(hide yes)
			(effects
				(font
					(size 1 1)
					(thickness 0.15)
				)
				(justify mirror)
			)
		)
		(property "Dielectric" "X5R"
			(at 0 0 180)
			(unlocked yes)
			(layer "B.Fab")
			(hide yes)
			(effects
				(font
					(size 1 1)
					(thickness 0.15)
				)
				(justify mirror)
			)
		)
		(sheetname "/X710-AT2 power/")
		(sheetfile "x710-at2-power.kicad_sch")
		(attr smd)
		(fp_rect
			(start -0.925 0.47)
			(end 0.925 -0.47)
			(stroke
				(width 0.05)
				(type default)
			)
			(fill no)
			(layer "B.CrtYd")
		)
		(fp_line
			(start 0.504 0.25)
			(end 0.504 -0.248)
			(stroke
				(width 0.15)
				(type solid)
			)
			(layer "B.Fab")
		)
		(fp_line
			(start 0.504 -0.248)
			(end -0.494 -0.248)
			(stroke
				(width 0.15)
				(type solid)
			)
			(layer "B.Fab")
		)
		(fp_line
			(start -0.494 0.25)
			(end 0.504 0.25)
			(stroke
				(width 0.15)
				(type solid)
			)
			(layer "B.Fab")
		)
		(fp_line
			(start -0.494 -0.248)
			(end -0.494 0.25)
			(stroke
				(width 0.15)
				(type solid)
			)
			(layer "B.Fab")
		)
		(fp_text user "License: Apache-2.0"
			(at -0.939 -5.799 0)
			(layer "B.Fab")
			(effects
				(font
					(size 0.7 0.7)
					(thickness 0.15)
				)
				(justify left bottom mirror)
			)
		)
		(fp_text user "${REFERENCE}"
			(at -0.939 -4.599 0)
			(layer "B.Fab")
			(effects
				(font
					(size 0.7 0.7)
					(thickness 0.15)
				)
				(justify left bottom mirror)
			)
		)
		(fp_text user "Author: Antmicro"
			(at -0.939 -3.399 0)
			(layer "B.Fab")
			(effects
				(font
					(size 0.7 0.7)
					(thickness 0.15)
				)
				(justify left bottom mirror)
			)
		)
		(pad "1" smd roundrect
			(at -0.48 0 180)
			(size 0.59 0.64)
			(layers "B.Cu" "B.Mask" "B.Paste")
			(roundrect_rratio 0.25)
			(net 23 "GND")
			(pintype "passive")
		)
		(pad "2" smd roundrect
			(at 0.48 0 180)
			(size 0.59 0.64)
			(layers "B.Cu" "B.Mask" "B.Paste")
			(roundrect_rratio 0.25)
			(net 1 "VCCA")
			(pintype "passive")
		)
	)
	(footprint "antmicro-footprints:C_0402_1005Metric"
		(layer "B.Cu")
		(at 127.25 134.75 90)
		(descr "Capacitor SMD 0402")
		(tags "capacitor SMD 0402")
		(property "Reference" "C34"
			(at -1.25 0.5 270)
			(layer "B.SilkS")
			(effects
				(font
					(size 0.7 0.7)
					(thickness 0.15)
				)
				(justify left bottom mirror)
			)
		)
		(property "Value" "C_220n_0402"
			(at -1.022927 -2.155213 270)
			(layer "B.Fab")
			(effects
				(font
					(size 0.7 0.7)
					(thickness 0.15)
				)
				(justify left bottom mirror)
			)
		)
		(property "Datasheet" "https://www.yageo.com/en/Chart/Download/pdf/CC0402KRX5R6BB224"
			(at 0 0 270)
			(layer "B.Fab")
			(hide yes)
			(effects
				(font
					(size 1.27 1.27)
					(thickness 0.15)
				)
				(justify mirror)
			)
		)
		(property "Description" "SMD Multilayer Ceramic Capacitor, 0.22 µF, 10 V, 0402 [1005 Metric], ± 10%, X5R, CC Series"
			(at 0 0 270)
			(layer "B.Fab")
			(hide yes)
			(effects
				(font
					(size 1.27 1.27)
					(thickness 0.15)
				)
				(justify mirror)
			)
		)
		(property "MPN" "CC0402KRX5R6BB224"
			(at 0 0 90)
			(unlocked yes)
			(layer "B.Fab")
			(hide yes)
			(effects
				(font
					(size 1 1)
					(thickness 0.15)
				)
				(justify mirror)
			)
		)
		(property "Manufacturer" "YAGEO"
			(at 0 0 90)
			(unlocked yes)
			(layer "B.Fab")
			(hide yes)
			(effects
				(font
					(size 1 1)
					(thickness 0.15)
				)
				(justify mirror)
			)
		)
		(property "License" "Apache-2.0"
			(at 0 0 90)
			(unlocked yes)
			(layer "B.Fab")
			(hide yes)
			(effects
				(font
					(size 1 1)
					(thickness 0.15)
				)
				(justify mirror)
			)
		)
		(property "Val" "220n"
			(at 0 0 90)
			(unlocked yes)
			(layer "B.Fab")
			(hide yes)
			(effects
				(font
					(size 1 1)
					(thickness 0.15)
				)
				(justify mirror)
			)
		)
		(property "Voltage" ""
			(at 0 0 90)
			(unlocked yes)
			(layer "B.Fab")
			(hide yes)
			(effects
				(font
					(size 1 1)
					(thickness 0.15)
				)
				(justify mirror)
			)
		)
		(property "Dielectric" ""
			(at 0 0 90)
			(unlocked yes)
			(layer "B.Fab")
			(hide yes)
			(effects
				(font
					(size 1 1)
					(thickness 0.15)
				)
				(justify mirror)
			)
		)
		(property "Author" "Antmicro"
			(at 0 0 90)
			(unlocked yes)
			(layer "B.Fab")
			(hide yes)
			(effects
				(font
					(size 1 1)
					(thickness 0.15)
				)
				(justify mirror)
			)
		)
		(sheetname "/TB Controller/")
		(sheetfile "tb.kicad_sch")
		(attr smd)
		(fp_rect
			(start -0.925 0.47)
			(end 0.925 -0.47)
			(stroke
				(width 0.05)
				(type default)
			)
			(fill no)
			(layer "B.CrtYd")
		)
		(fp_line
			(start 0.504 -0.248)
			(end -0.494 -0.248)
			(stroke
				(width 0.15)
				(type solid)
			)
			(layer "B.Fab")
		)
		(fp_line
			(start -0.494 -0.248)
			(end -0.494 0.25)
			(stroke
				(width 0.15)
				(type solid)
			)
			(layer "B.Fab")
		)
		(fp_line
			(start 0.504 0.25)
			(end 0.504 -0.248)
			(stroke
				(width 0.15)
				(type solid)
			)
			(layer "B.Fab")
		)
		(fp_line
			(start -0.494 0.25)
			(end 0.504 0.25)
			(stroke
				(width 0.15)
				(type solid)
			)
			(layer "B.Fab")
		)
		(fp_text user "${REFERENCE}"
			(at -0.939 -4.599 270)
			(layer "B.Fab")
			(effects
				(font
					(size 0.7 0.7)
					(thickness 0.15)
				)
				(justify left bottom mirror)
			)
		)
		(fp_text user "License: Apache-2.0"
			(at -0.939 -5.799 270)
			(layer "B.Fab")
			(effects
				(font
					(size 0.7 0.7)
					(thickness 0.15)
				)
				(justify left bottom mirror)
			)
		)
		(fp_text user "Author: Antmicro"
			(at -0.939 -3.399 270)
			(layer "B.Fab")
			(effects
				(font
					(size 0.7 0.7)
					(thickness 0.15)
				)
				(justify left bottom mirror)
			)
		)
		(pad "1" smd roundrect
			(at -0.48 0 90)
			(size 0.59 0.64)
			(layers "B.Cu" "B.Mask" "B.Paste")
			(roundrect_rratio 0.25)
			(net 309 "/PD and TB DC-DC/USB3.TX1_P")
			(pintype "passive")
		)
		(pad "2" smd roundrect
			(at 0.48 0 90)
			(size 0.59 0.64)
			(layers "B.Cu" "B.Mask" "B.Paste")
			(roundrect_rratio 0.25)
			(net 168 "/TB Controller/PA_TX1_P")
			(pintype "passive")
		)
	)
	(footprint "antmicro-footprints:R_0402_1005Metric"
		(layer "B.Cu")
		(at 142.5 115.099997 180)
		(descr "Resistor SMD 0402")
		(tags "resistor SMD 0402")
		(property "Reference" "R65"
			(at -19.75 7.450001 0)
			(layer "B.SilkS")
			(effects
				(font
					(size 0.7 0.7)
					(thickness 0.15)
				)
				(justify mirror)
			)
		)
		(property "Value" "R_10k_0402"
			(at -1.011843 -1.772047 0)
			(layer "B.Fab")
			(effects
				(font
					(size 0.7 0.7)
					(thickness 0.15)
				)
				(justify left bottom mirror)
			)
		)
		(property "Datasheet" "https://www.bourns.com/docs/product-datasheets/cr.pdf"
			(at 0 0 0)
			(layer "B.Fab")
			(hide yes)
			(effects
				(font
					(size 1.27 1.27)
					(thickness 0.15)
				)
				(justify mirror)
			)
		)
		(property "Description" "SMD Chip Resistor, 10 kohm, ± 1%, 62.5 mW, 0402 [1005 Metric], Thick Film, General Purpose"
			(at 0 0 0)
			(layer "B.Fab")
			(hide yes)
			(effects
				(font
					(size 1.27 1.27)
					(thickness 0.15)
				)
				(justify mirror)
			)
		)
		(property "MPN" "CR0402-FX-1002GLF"
			(at 0 0 180)
			(unlocked yes)
			(layer "B.Fab")
			(hide yes)
			(effects
				(font
					(size 1 1)
					(thickness 0.15)
				)
				(justify mirror)
			)
		)
		(property "Manufacturer" "Bourns"
			(at 0 0 180)
			(unlocked yes)
			(layer "B.Fab")
			(hide yes)
			(effects
				(font
					(size 1 1)
					(thickness 0.15)
				)
				(justify mirror)
			)
		)
		(property "License" "Apache-2.0"
			(at 0 0 180)
			(unlocked yes)
			(layer "B.Fab")
			(hide yes)
			(effects
				(font
					(size 1 1)
					(thickness 0.15)
				)
				(justify mirror)
			)
		)
		(property "Val" "10k"
			(at 0 0 180)
			(unlocked yes)
			(layer "B.Fab")
			(hide yes)
			(effects
				(font
					(size 1 1)
					(thickness 0.15)
				)
				(justify mirror)
			)
		)
		(property "Tolerance" "1%"
			(at 0 0 180)
			(unlocked yes)
			(layer "B.Fab")
			(hide yes)
			(effects
				(font
					(size 1 1)
					(thickness 0.15)
				)
				(justify mirror)
			)
		)
		(property "Author" "Antmicro"
			(at 0 0 180)
			(unlocked yes)
			(layer "B.Fab")
			(hide yes)
			(effects
				(font
					(size 1 1)
					(thickness 0.15)
				)
				(justify mirror)
			)
		)
		(sheetname "/TB Controller/")
		(sheetfile "tb.kicad_sch")
		(attr smd)
		(fp_rect
			(start -0.925 0.47)
			(end 0.925 -0.47)
			(stroke
				(width 0.05)
				(type default)
			)
			(fill no)
			(layer "B.CrtYd")
		)
		(fp_rect
			(start -0.5 0.25)
			(end 0.5 -0.25)
			(stroke
				(width 0.15)
				(type solid)
			)
			(fill no)
			(layer "B.Fab")
		)
		(fp_text user "Author: Antmicro"
			(at -0.95 -4.169 0)
			(layer "B.Fab")
			(effects
				(font
					(size 0.7 0.7)
					(thickness 0.15)
				)
				(justify left bottom mirror)
			)
		)
		(fp_text user "License: Apache-2.0"
			(at -0.95 -5.169 0)
			(layer "B.Fab")
			(effects
				(font
					(size 0.7 0.7)
					(thickness 0.15)
				)
				(justify left bottom mirror)
			)
		)
		(fp_text user "${REFERENCE}"
			(at -0.95 -3.168 0)
			(layer "B.Fab")
			(effects
				(font
					(size 0.7 0.7)
					(thickness 0.15)
				)
				(justify left bottom mirror)
			)
		)
		(pad "1" smd roundrect
			(at -0.48 0 180)
			(size 0.59 0.64)
			(layers "B.Cu" "B.Mask" "B.Paste")
			(roundrect_rratio 0.25)
			(net 57 "+3V3_TB")
			(pintype "passive")
		)
		(pad "2" smd roundrect
			(at 0.48 0 180)
			(size 0.59 0.64)
			(layers "B.Cu" "B.Mask" "B.Paste")
			(roundrect_rratio 0.25)
			(net 227 "Net-(U4D-TDO)")
			(pintype "passive")
		)
	)
	(footprint "antmicro-footprints:TP_SMD_0.75mm"
		(layer "B.Cu")
		(at 159.731865 62.935117 90)
		(property "Reference" "TP27"
			(at -0.264883 3.268135 180)
			(layer "B.SilkS")
			(effects
				(font
					(size 0.7 0.7)
					(thickness 0.15)
				)
				(justify left bottom mirror)
			)
		)
		(property "Value" "TP_0.75mm_SMD"
			(at 0 -1.2 270)
			(layer "B.Fab")
			(effects
				(font
					(size 0.7 0.7)
					(thickness 0.15)
				)
				(justify left bottom mirror)
			)
		)
		(property "Description" "SMT test point"
			(at 0 0 270)
			(layer "B.Fab")
			(hide yes)
			(effects
				(font
					(size 1.27 1.27)
					(thickness 0.15)
				)
				(justify mirror)
			)
		)
		(property "MPN" ""
			(at 0 0 90)
			(unlocked yes)
			(layer "B.Fab")
			(hide yes)
			(effects
				(font
					(size 1 1)
					(thickness 0.15)
				)
				(justify mirror)
			)
		)
		(property "Manufacturer" ""
			(at 0 0 90)
			(unlocked yes)
			(layer "B.Fab")
			(hide yes)
			(effects
				(font
					(size 1 1)
					(thickness 0.15)
				)
				(justify mirror)
			)
		)
		(property "Author" "Antmicro"
			(at 0 0 90)
			(unlocked yes)
			(layer "B.Fab")
			(hide yes)
			(effects
				(font
					(size 1 1)
					(thickness 0.15)
				)
				(justify mirror)
			)
		)
		(property "License" "Apache-2.0"
			(at 0 0 90)
			(unlocked yes)
			(layer "B.Fab")
			(hide yes)
			(effects
				(font
					(size 1 1)
					(thickness 0.15)
				)
				(justify mirror)
			)
		)
		(sheetname "/X710-AT2 Misc/")
		(sheetfile "x710-at2-mics.kicad_sch")
		(attr exclude_from_pos_files exclude_from_bom)
		(fp_circle
			(center 0 0)
			(end 0.475 0)
			(stroke
				(width 0.05)
				(type default)
			)
			(fill no)
			(layer "B.CrtYd")
		)
		(fp_text user "${REFERENCE}"
			(at -0.4 -2.7 270)
			(layer "B.Fab")
			(effects
				(font
					(size 0.7 0.7)
					(thickness 0.15)
				)
				(justify left bottom mirror)
			)
		)
		(fp_text user "Author: Antmicro"
			(at -0.4 -3.901 270)
			(layer "B.Fab")
			(effects
				(font
					(size 0.7 0.7)
					(thickness 0.15)
				)
				(justify left bottom mirror)
			)
		)
		(fp_text user "License: Apache-2.0"
			(at -0.4 -5.101 270)
			(layer "B.Fab")
			(effects
				(font
					(size 0.7 0.7)
					(thickness 0.15)
				)
				(justify left bottom mirror)
			)
		)
		(pad "1" smd circle
			(at 0 0 90)
			(size 0.75 0.75)
			(layers "B.Cu" "B.Mask")
			(net 139 "/X710-AT2 Misc/NCSI.RXD_0")
			(pinfunction "1")
			(pintype "passive")
		)
	)
	(footprint "antmicro-footprints:R_0402_1005Metric"
		(layer "B.Cu")
		(at 135.761535 138.807574 90)
		(descr "Resistor SMD 0402")
		(tags "resistor SMD 0402")
		(property "Reference" "R26"
			(at 9.557574 19.525001 270)
			(layer "B.SilkS")
			(effects
				(font
					(size 0.7 0.7)
					(thickness 0.15)
				)
				(justify mirror)
			)
		)
		(property "Value" "R_10k_0402"
			(at -1.011843 -1.772047 270)
			(layer "B.Fab")
			(effects
				(font
					(size 0.7 0.7)
					(thickness 0.15)
				)
				(justify left bottom mirror)
			)
		)
		(property "Datasheet" "https://www.bourns.com/docs/product-datasheets/cr.pdf"
			(at 0 0 270)
			(layer "B.Fab")
			(hide yes)
			(effects
				(font
					(size 1.27 1.27)
					(thickness 0.15)
				)
				(justify mirror)
			)
		)
		(property "Description" "SMD Chip Resistor, 10 kohm, ± 1%, 62.5 mW, 0402 [1005 Metric], Thick Film, General Purpose"
			(at 0 0 270)
			(layer "B.Fab")
			(hide yes)
			(effects
				(font
					(size 1.27 1.27)
					(thickness 0.15)
				)
				(justify mirror)
			)
		)
		(property "MPN" "CR0402-FX-1002GLF"
			(at 0 0 90)
			(unlocked yes)
			(layer "B.Fab")
			(hide yes)
			(effects
				(font
					(size 1 1)
					(thickness 0.15)
				)
				(justify mirror)
			)
		)
		(property "Manufacturer" "Bourns"
			(at 0 0 90)
			(unlocked yes)
			(layer "B.Fab")
			(hide yes)
			(effects
				(font
					(size 1 1)
					(thickness 0.15)
				)
				(justify mirror)
			)
		)
		(property "License" "Apache-2.0"
			(at 0 0 90)
			(unlocked yes)
			(layer "B.Fab")
			(hide yes)
			(effects
				(font
					(size 1 1)
					(thickness 0.15)
				)
				(justify mirror)
			)
		)
		(property "Val" "10k"
			(at 0 0 90)
			(unlocked yes)
			(layer "B.Fab")
			(hide yes)
			(effects
				(font
					(size 1 1)
					(thickness 0.15)
				)
				(justify mirror)
			)
		)
		(property "Tolerance" "1%"
			(at 0 0 90)
			(unlocked yes)
			(layer "B.Fab")
			(hide yes)
			(effects
				(font
					(size 1 1)
					(thickness 0.15)
				)
				(justify mirror)
			)
		)
		(property "Author" "Antmicro"
			(at 0 0 90)
			(unlocked yes)
			(layer "B.Fab")
			(hide yes)
			(effects
				(font
					(size 1 1)
					(thickness 0.15)
				)
				(justify mirror)
			)
		)
		(sheetname "/PD and TB DC-DC/")
		(sheetfile "PD_and_TB_DC_DC.kicad_sch")
		(attr smd)
		(fp_rect
			(start -0.925 0.47)
			(end 0.925 -0.47)
			(stroke
				(width 0.05)
				(type default)
			)
			(fill no)
			(layer "B.CrtYd")
		)
		(fp_rect
			(start -0.5 0.25)
			(end 0.5 -0.25)
			(stroke
				(width 0.15)
				(type solid)
			)
			(fill no)
			(layer "B.Fab")
		)
		(fp_text user "Author: Antmicro"
			(at -0.95 -4.169 270)
			(layer "B.Fab")
			(effects
				(font
					(size 0.7 0.7)
					(thickness 0.15)
				)
				(justify left bottom mirror)
			)
		)
		(fp_text user "${REFERENCE}"
			(at -0.95 -3.168 270)
			(layer "B.Fab")
			(effects
				(font
					(size 0.7 0.7)
					(thickness 0.15)
				)
				(justify left bottom mirror)
			)
		)
		(fp_text user "License: Apache-2.0"
			(at -0.95 -5.169 270)
			(layer "B.Fab")
			(effects
				(font
					(size 0.7 0.7)
					(thickness 0.15)
				)
				(justify left bottom mirror)
			)
		)
		(pad "1" smd roundrect
			(at -0.48 0 90)
			(size 0.59 0.64)
			(layers "B.Cu" "B.Mask" "B.Paste")
			(roundrect_rratio 0.25)
			(net 209 "Net-(U3-MRESET(GPIO11))")
			(pintype "passive")
		)
		(pad "2" smd roundrect
			(at 0.48 0 90)
			(size 0.59 0.64)
			(layers "B.Cu" "B.Mask" "B.Paste")
			(roundrect_rratio 0.25)
			(net 23 "GND")
			(pintype "passive")
		)
	)
	(footprint "antmicro-footprints:C_0402_1005Metric"
		(layer "B.Cu")
		(at 126.224999 122.000001 -90)
		(descr "Capacitor SMD 0402")
		(tags "capacitor SMD 0402")
		(property "Reference" "C66"
			(at -7.700002 -21.900002 90)
			(layer "B.SilkS")
			(effects
				(font
					(size 0.7 0.7)
					(thickness 0.15)
				)
				(justify mirror)
			)
		)
		(property "Value" "C_1u_0402"
			(at -1.022927 -2.155213 90)
			(layer "B.Fab")
			(effects
				(font
					(size 0.7 0.7)
					(thickness 0.15)
				)
				(justify left bottom mirror)
			)
		)
		(property "Datasheet" "https://product.tdk.com/en/search/capacitor/ceramic/mlcc/info?part_no=C1005X6S1A105K050BC"
			(at 0 0 90)
			(layer "B.Fab")
			(hide yes)
			(effects
				(font
					(size 1.27 1.27)
					(thickness 0.15)
				)
				(justify mirror)
			)
		)
		(property "Description" "SMD Multilayer Ceramic Capacitor, 1 µF, 10 V, 0402 [1005 Metric], ± 10%, X6S, C"
			(at 0 0 90)
			(layer "B.Fab")
			(hide yes)
			(effects
				(font
					(size 1.27 1.27)
					(thickness 0.15)
				)
				(justify mirror)
			)
		)
		(property "MPN" "C1005X6S1A105K050BC"
			(at 0 0 270)
			(unlocked yes)
			(layer "B.Fab")
			(hide yes)
			(effects
				(font
					(size 1 1)
					(thickness 0.15)
				)
				(justify mirror)
			)
		)
		(property "Manufacturer" "TDK"
			(at 0 0 270)
			(unlocked yes)
			(layer "B.Fab")
			(hide yes)
			(effects
				(font
					(size 1 1)
					(thickness 0.15)
				)
				(justify mirror)
			)
		)
		(property "License" "Apache-2.0"
			(at 0 0 270)
			(unlocked yes)
			(layer "B.Fab")
			(hide yes)
			(effects
				(font
					(size 1 1)
					(thickness 0.15)
				)
				(justify mirror)
			)
		)
		(property "Val" "1u"
			(at 0 0 270)
			(unlocked yes)
			(layer "B.Fab")
			(hide yes)
			(effects
				(font
					(size 1 1)
					(thickness 0.15)
				)
				(justify mirror)
			)
		)
		(property "Voltage" ""
			(at 0 0 270)
			(unlocked yes)
			(layer "B.Fab")
			(hide yes)
			(effects
				(font
					(size 1 1)
					(thickness 0.15)
				)
				(justify mirror)
			)
		)
		(property "Dielectric" ""
			(at 0 0 270)
			(unlocked yes)
			(layer "B.Fab")
			(hide yes)
			(effects
				(font
					(size 1 1)
					(thickness 0.15)
				)
				(justify mirror)
			)
		)
		(property "Author" "Antmicro"
			(at 0 0 270)
			(unlocked yes)
			(layer "B.Fab")
			(hide yes)
			(effects
				(font
					(size 1 1)
					(thickness 0.15)
				)
				(justify mirror)
			)
		)
		(sheetname "/TB Controller - Power/")
		(sheetfile "tb-power.kicad_sch")
		(attr smd)
		(fp_rect
			(start -0.925 0.47)
			(end 0.925 -0.47)
			(stroke
				(width 0.05)
				(type default)
			)
			(fill no)
			(layer "B.CrtYd")
		)
		(fp_line
			(start -0.494 0.25)
			(end 0.504 0.25)
			(stroke
				(width 0.15)
				(type solid)
			)
			(layer "B.Fab")
		)
		(fp_line
			(start 0.504 0.25)
			(end 0.504 -0.248)
			(stroke
				(width 0.15)
				(type solid)
			)
			(layer "B.Fab")
		)
		(fp_line
			(start -0.494 -0.248)
			(end -0.494 0.25)
			(stroke
				(width 0.15)
				(type solid)
			)
			(layer "B.Fab")
		)
		(fp_line
			(start 0.504 -0.248)
			(end -0.494 -0.248)
			(stroke
				(width 0.15)
				(type solid)
			)
			(layer "B.Fab")
		)
		(fp_text user "${REFERENCE}"
			(at -0.939 -4.599 90)
			(layer "B.Fab")
			(effects
				(font
					(size 0.7 0.7)
					(thickness 0.15)
				)
				(justify left bottom mirror)
			)
		)
		(fp_text user "Author: Antmicro"
			(at -0.939 -3.399 90)
			(layer "B.Fab")
			(effects
				(font
					(size 0.7 0.7)
					(thickness 0.15)
				)
				(justify left bottom mirror)
			)
		)
		(fp_text user "License: Apache-2.0"
			(at -0.939 -5.799 90)
			(layer "B.Fab")
			(effects
				(font
					(size 0.7 0.7)
					(thickness 0.15)
				)
				(justify left bottom mirror)
			)
		)
		(pad "1" smd roundrect
			(at -0.48 0 270)
			(size 0.59 0.64)
			(layers "B.Cu" "B.Mask" "B.Paste")
			(roundrect_rratio 0.25)
			(net 23 "GND")
			(pintype "passive")
		)
		(pad "2" smd roundrect
			(at 0.48 0 270)
			(size 0.59 0.64)
			(layers "B.Cu" "B.Mask" "B.Paste")
			(roundrect_rratio 0.25)
			(net 405 "Net-(C66-Pad2)")
			(pintype "passive")
		)
	)
	(footprint "antmicro-footprints:C_0402_1005Metric"
		(layer "B.Cu")
		(at 133.849999 137.099998 90)
		(descr "Capacitor SMD 0402")
		(tags "capacitor SMD 0402")
		(property "Reference" "C23"
			(at 8.339997 19.525001 270)
			(layer "B.SilkS")
			(effects
				(font
					(size 0.7 0.7)
					(thickness 0.15)
				)
				(justify mirror)
			)
		)
		(property "Value" "C_220n_0402"
			(at -1.022927 -2.155213 270)
			(layer "B.Fab")
			(effects
				(font
					(size 0.7 0.7)
					(thickness 0.15)
				)
				(justify left bottom mirror)
			)
		)
		(property "Datasheet" "https://www.yageo.com/en/Chart/Download/pdf/CC0402KRX5R6BB224"
			(at 0 0 270)
			(layer "B.Fab")
			(hide yes)
			(effects
				(font
					(size 1.27 1.27)
					(thickness 0.15)
				)
				(justify mirror)
			)
		)
		(property "Description" "SMD Multilayer Ceramic Capacitor, 0.22 µF, 10 V, 0402 [1005 Metric], ± 10%, X5R, CC Series"
			(at 0 0 270)
			(layer "B.Fab")
			(hide yes)
			(effects
				(font
					(size 1.27 1.27)
					(thickness 0.15)
				)
				(justify mirror)
			)
		)
		(property "MPN" "CC0402KRX5R6BB224"
			(at 0 0 90)
			(unlocked yes)
			(layer "B.Fab")
			(hide yes)
			(effects
				(font
					(size 1 1)
					(thickness 0.15)
				)
				(justify mirror)
			)
		)
		(property "Manufacturer" "YAGEO"
			(at 0 0 90)
			(unlocked yes)
			(layer "B.Fab")
			(hide yes)
			(effects
				(font
					(size 1 1)
					(thickness 0.15)
				)
				(justify mirror)
			)
		)
		(property "License" "Apache-2.0"
			(at 0 0 90)
			(unlocked yes)
			(layer "B.Fab")
			(hide yes)
			(effects
				(font
					(size 1 1)
					(thickness 0.15)
				)
				(justify mirror)
			)
		)
		(property "Val" "220n"
			(at 0 0 90)
			(unlocked yes)
			(layer "B.Fab")
			(hide yes)
			(effects
				(font
					(size 1 1)
					(thickness 0.15)
				)
				(justify mirror)
			)
		)
		(property "Voltage" ""
			(at 0 0 90)
			(unlocked yes)
			(layer "B.Fab")
			(hide yes)
			(effects
				(font
					(size 1 1)
					(thickness 0.15)
				)
				(justify mirror)
			)
		)
		(property "Dielectric" ""
			(at 0 0 90)
			(unlocked yes)
			(layer "B.Fab")
			(hide yes)
			(effects
				(font
					(size 1 1)
					(thickness 0.15)
				)
				(justify mirror)
			)
		)
		(property "Author" "Antmicro"
			(at 0 0 90)
			(unlocked yes)
			(layer "B.Fab")
			(hide yes)
			(effects
				(font
					(size 1 1)
					(thickness 0.15)
				)
				(justify mirror)
			)
		)
		(sheetname "/PD and TB DC-DC/")
		(sheetfile "PD_and_TB_DC_DC.kicad_sch")
		(attr smd)
		(fp_rect
			(start -0.925 0.47)
			(end 0.925 -0.47)
			(stroke
				(width 0.05)
				(type default)
			)
			(fill no)
			(layer "B.CrtYd")
		)
		(fp_line
			(start 0.504 -0.248)
			(end -0.494 -0.248)
			(stroke
				(width 0.15)
				(type solid)
			)
			(layer "B.Fab")
		)
		(fp_line
			(start -0.494 -0.248)
			(end -0.494 0.25)
			(stroke
				(width 0.15)
				(type solid)
			)
			(layer "B.Fab")
		)
		(fp_line
			(start 0.504 0.25)
			(end 0.504 -0.248)
			(stroke
				(width 0.15)
				(type solid)
			)
			(layer "B.Fab")
		)
		(fp_line
			(start -0.494 0.25)
			(end 0.504 0.25)
			(stroke
				(width 0.15)
				(type solid)
			)
			(layer "B.Fab")
		)
		(fp_text user "License: Apache-2.0"
			(at -0.939 -5.799 270)
			(layer "B.Fab")
			(effects
				(font
					(size 0.7 0.7)
					(thickness 0.15)
				)
				(justify left bottom mirror)
			)
		)
		(fp_text user "${REFERENCE}"
			(at -0.939 -4.599 270)
			(layer "B.Fab")
			(effects
				(font
					(size 0.7 0.7)
					(thickness 0.15)
				)
				(justify left bottom mirror)
			)
		)
		(fp_text user "Author: Antmicro"
			(at -0.939 -3.399 270)
			(layer "B.Fab")
			(effects
				(font
					(size 0.7 0.7)
					(thickness 0.15)
				)
				(justify left bottom mirror)
			)
		)
		(pad "1" smd roundrect
			(at -0.48 0 90)
			(size 0.59 0.64)
			(layers "B.Cu" "B.Mask" "B.Paste")
			(roundrect_rratio 0.25)
			(net 23 "GND")
			(pintype "passive")
		)
		(pad "2" smd roundrect
			(at 0.48 0 90)
			(size 0.59 0.64)
			(layers "B.Cu" "B.Mask" "B.Paste")
			(roundrect_rratio 0.25)
			(net 165 "Net-(U3-SS)")
			(pintype "passive")
		)
	)
	(footprint "antmicro-footprints:R_0402_1005Metric"
		(layer "B.Cu")
		(at 150.681866 92.485116 90)
		(descr "Resistor SMD 0402")
		(tags "resistor SMD 0402")
		(property "Reference" "R149"
			(at -10.814884 18.718134 270)
			(layer "B.SilkS")
			(effects
				(font
					(size 0.7 0.7)
					(thickness 0.15)
				)
				(justify mirror)
			)
		)
		(property "Value" "R_100R_0402"
			(at -1.011843 -1.772047 270)
			(layer "B.Fab")
			(effects
				(font
					(size 0.7 0.7)
					(thickness 0.15)
				)
				(justify left bottom mirror)
			)
		)
		(property "Datasheet" "https://www.bourns.com/docs/product-datasheets/cr.pdf"
			(at 0 0 270)
			(layer "B.Fab")
			(hide yes)
			(effects
				(font
					(size 1.27 1.27)
					(thickness 0.15)
				)
				(justify mirror)
			)
		)
		(property "Description" "SMD Chip Resistor, 100 ohm, ± 1%, 62.5 mW, 0402 [1005 Metric], Thick Film, General Purpose"
			(at 0 0 270)
			(layer "B.Fab")
			(hide yes)
			(effects
				(font
					(size 1.27 1.27)
					(thickness 0.15)
				)
				(justify mirror)
			)
		)
		(property "MPN" "CR0402-FX-1000GLF"
			(at 0 0 90)
			(unlocked yes)
			(layer "B.Fab")
			(hide yes)
			(effects
				(font
					(size 1 1)
					(thickness 0.15)
				)
				(justify mirror)
			)
		)
		(property "Manufacturer" "Bourns"
			(at 0 0 90)
			(unlocked yes)
			(layer "B.Fab")
			(hide yes)
			(effects
				(font
					(size 1 1)
					(thickness 0.15)
				)
				(justify mirror)
			)
		)
		(property "License" "Apache-2.0"
			(at 0 0 90)
			(unlocked yes)
			(layer "B.Fab")
			(hide yes)
			(effects
				(font
					(size 1 1)
					(thickness 0.15)
				)
				(justify mirror)
			)
		)
		(property "Author" "Antmicro"
			(at 0 0 90)
			(unlocked yes)
			(layer "B.Fab")
			(hide yes)
			(effects
				(font
					(size 1 1)
					(thickness 0.15)
				)
				(justify mirror)
			)
		)
		(property "Val" "100R"
			(at 0 0 90)
			(unlocked yes)
			(layer "B.Fab")
			(hide yes)
			(effects
				(font
					(size 1 1)
					(thickness 0.15)
				)
				(justify mirror)
			)
		)
		(property "Tolerance" "1%"
			(at 0 0 90)
			(unlocked yes)
			(layer "B.Fab")
			(hide yes)
			(effects
				(font
					(size 1 1)
					(thickness 0.15)
				)
				(justify mirror)
			)
		)
		(sheetname "/X710-AT2 Misc/")
		(sheetfile "x710-at2-mics.kicad_sch")
		(attr smd)
		(fp_rect
			(start -0.925 0.47)
			(end 0.925 -0.47)
			(stroke
				(width 0.05)
				(type default)
			)
			(fill no)
			(layer "B.CrtYd")
		)
		(fp_rect
			(start -0.5 0.25)
			(end 0.5 -0.25)
			(stroke
				(width 0.15)
				(type solid)
			)
			(fill no)
			(layer "B.Fab")
		)
		(fp_text user "${REFERENCE}"
			(at -0.95 -3.168 270)
			(layer "B.Fab")
			(effects
				(font
					(size 0.7 0.7)
					(thickness 0.15)
				)
				(justify left bottom mirror)
			)
		)
		(fp_text user "Author: Antmicro"
			(at -0.95 -4.169 270)
			(layer "B.Fab")
			(effects
				(font
					(size 0.7 0.7)
					(thickness 0.15)
				)
				(justify left bottom mirror)
			)
		)
		(fp_text user "License: Apache-2.0"
			(at -0.95 -5.169 270)
			(layer "B.Fab")
			(effects
				(font
					(size 0.7 0.7)
					(thickness 0.15)
				)
				(justify left bottom mirror)
			)
		)
		(pad "1" smd roundrect
			(at -0.48 0 90)
			(size 0.59 0.64)
			(layers "B.Cu" "B.Mask" "B.Paste")
			(roundrect_rratio 0.25)
			(net 23 "GND")
			(pintype "passive")
		)
		(pad "2" smd roundrect
			(at 0.48 0 90)
			(size 0.59 0.64)
			(layers "B.Cu" "B.Mask" "B.Paste")
			(roundrect_rratio 0.25)
			(net 35 "/X710-AT2 Misc/POR_BYPASS")
			(pintype "passive")
		)
	)
	(footprint "antmicro-footprints:C_0402_1005Metric"
		(layer "B.Cu")
		(at 159 136 180)
		(descr "Capacitor SMD 0402")
		(tags "capacitor SMD 0402")
		(property "Reference" "C298"
			(at -1.75 0.5 0)
			(layer "B.SilkS")
			(effects
				(font
					(size 0.7 0.7)
					(thickness 0.15)
				)
				(justify left bottom mirror)
			)
		)
		(property "Value" "C_1u_25V_0402"
			(at -1.022927 -2.155213 0)
			(layer "B.Fab")
			(effects
				(font
					(size 0.7 0.7)
					(thickness 0.15)
				)
				(justify left bottom mirror)
			)
		)
		(property "Datasheet" "https://www.murata.com/products/productdetail?partno=GRM155R61E105KE11%23"
			(at 0 0 0)
			(layer "B.Fab")
			(hide yes)
			(effects
				(font
					(size 1.27 1.27)
					(thickness 0.15)
				)
				(justify mirror)
			)
		)
		(property "Description" "SMD Multilayer Ceramic Capacitor, 1 µF, 25 V, 0402 [1005 Metric], ± 10%, X5R, GRM Series"
			(at 0 0 0)
			(layer "B.Fab")
			(hide yes)
			(effects
				(font
					(size 1.27 1.27)
					(thickness 0.15)
				)
				(justify mirror)
			)
		)
		(property "MPN" "GRM155R61E105KE11J"
			(at 0 0 180)
			(unlocked yes)
			(layer "B.Fab")
			(hide yes)
			(effects
				(font
					(size 1 1)
					(thickness 0.15)
				)
				(justify mirror)
			)
		)
		(property "Manufacturer" "Murata"
			(at 0 0 180)
			(unlocked yes)
			(layer "B.Fab")
			(hide yes)
			(effects
				(font
					(size 1 1)
					(thickness 0.15)
				)
				(justify mirror)
			)
		)
		(property "License" "Apache-2.0"
			(at 0 0 180)
			(unlocked yes)
			(layer "B.Fab")
			(hide yes)
			(effects
				(font
					(size 1 1)
					(thickness 0.15)
				)
				(justify mirror)
			)
		)
		(property "Author" "Antmicro"
			(at 0 0 180)
			(unlocked yes)
			(layer "B.Fab")
			(hide yes)
			(effects
				(font
					(size 1 1)
					(thickness 0.15)
				)
				(justify mirror)
			)
		)
		(property "Val" "1u"
			(at 0 0 180)
			(unlocked yes)
			(layer "B.Fab")
			(hide yes)
			(effects
				(font
					(size 1 1)
					(thickness 0.15)
				)
				(justify mirror)
			)
		)
		(property "Voltage" "25V"
			(at 0 0 180)
			(unlocked yes)
			(layer "B.Fab")
			(hide yes)
			(effects
				(font
					(size 1 1)
					(thickness 0.15)
				)
				(justify mirror)
			)
		)
		(property "Dielectric" "X5R"
			(at 0 0 180)
			(unlocked yes)
			(layer "B.Fab")
			(hide yes)
			(effects
				(font
					(size 1 1)
					(thickness 0.15)
				)
				(justify mirror)
			)
		)
		(sheetname "/2xRJ45/")
		(sheetfile "2xrj45.kicad_sch")
		(attr smd)
		(fp_rect
			(start -0.925 0.47)
			(end 0.925 -0.47)
			(stroke
				(width 0.05)
				(type default)
			)
			(fill no)
			(layer "B.CrtYd")
		)
		(fp_line
			(start 0.504 0.25)
			(end 0.504 -0.248)
			(stroke
				(width 0.15)
				(type solid)
			)
			(layer "B.Fab")
		)
		(fp_line
			(start 0.504 -0.248)
			(end -0.494 -0.248)
			(stroke
				(width 0.15)
				(type solid)
			)
			(layer "B.Fab")
		)
		(fp_line
			(start -0.494 0.25)
			(end 0.504 0.25)
			(stroke
				(width 0.15)
				(type solid)
			)
			(layer "B.Fab")
		)
		(fp_line
			(start -0.494 -0.248)
			(end -0.494 0.25)
			(stroke
				(width 0.15)
				(type solid)
			)
			(layer "B.Fab")
		)
		(fp_text user "${REFERENCE}"
			(at -0.939 -4.599 0)
			(layer "B.Fab")
			(effects
				(font
					(size 0.7 0.7)
					(thickness 0.15)
				)
				(justify left bottom mirror)
			)
		)
		(fp_text user "Author: Antmicro"
			(at -0.939 -3.399 0)
			(layer "B.Fab")
			(effects
				(font
					(size 0.7 0.7)
					(thickness 0.15)
				)
				(justify left bottom mirror)
			)
		)
		(fp_text user "License: Apache-2.0"
			(at -0.939 -5.799 0)
			(layer "B.Fab")
			(effects
				(font
					(size 0.7 0.7)
					(thickness 0.15)
				)
				(justify left bottom mirror)
			)
		)
		(pad "1" smd roundrect
			(at -0.48 0 180)
			(size 0.59 0.64)
			(layers "B.Cu" "B.Mask" "B.Paste")
			(roundrect_rratio 0.25)
			(net 23 "GND")
			(pintype "passive")
		)
		(pad "2" smd roundrect
			(at 0.48 0 180)
			(size 0.59 0.64)
			(layers "B.Cu" "B.Mask" "B.Paste")
			(roundrect_rratio 0.25)
			(net 133 "/2xRJ45/P0_CT")
			(pintype "passive")
		)
	)
	(footprint "antmicro-footprints:C_Pol_EIA-A"
		(layer "B.Cu")
		(at 141 103.7 -90)
		(property "Reference" "C331"
			(at 2.2 -0.4 90)
			(layer "B.SilkS")
			(effects
				(font
					(size 0.7 0.7)
					(thickness 0.15)
				)
				(justify left bottom mirror)
			)
		)
		(property "Value" "C_Pol_100u_6V_KEMET-T490-A"
			(at 0 -2 90)
			(layer "B.Fab")
			(effects
				(font
					(size 0.7 0.7)
					(thickness 0.15)
				)
				(justify left bottom mirror)
			)
		)
		(property "Datasheet" "https://www.kemet.com/en/us/capacitors/product/T490A107M006ATE800.html"
			(at 0 0 90)
			(layer "B.Fab")
			(hide yes)
			(effects
				(font
					(size 1.27 1.27)
					(thickness 0.15)
				)
				(justify mirror)
			)
		)
		(property "Description" "Surface Mount Tantalum Capacitor,  Solid SMD 6V 100uF 1206 20% ESR=800mOhms"
			(at 0 0 90)
			(layer "B.Fab")
			(hide yes)
			(effects
				(font
					(size 1.27 1.27)
					(thickness 0.15)
				)
				(justify mirror)
			)
		)
		(property "Val" "100u"
			(at 0 0 270)
			(unlocked yes)
			(layer "B.Fab")
			(hide yes)
			(effects
				(font
					(size 1 1)
					(thickness 0.15)
				)
				(justify mirror)
			)
		)
		(property "MPN" "T490A107M006ATE800"
			(at 0 0 270)
			(unlocked yes)
			(layer "B.Fab")
			(hide yes)
			(effects
				(font
					(size 1 1)
					(thickness 0.15)
				)
				(justify mirror)
			)
		)
		(property "Manufacturer" "KEMET"
			(at 0 0 270)
			(unlocked yes)
			(layer "B.Fab")
			(hide yes)
			(effects
				(font
					(size 1 1)
					(thickness 0.15)
				)
				(justify mirror)
			)
		)
		(property "License" "Apache-2.0"
			(at 0 0 270)
			(unlocked yes)
			(layer "B.Fab")
			(hide yes)
			(effects
				(font
					(size 1 1)
					(thickness 0.15)
				)
				(justify mirror)
			)
		)
		(property "Author" "Antmicro"
			(at 0 0 270)
			(unlocked yes)
			(layer "B.Fab")
			(hide yes)
			(effects
				(font
					(size 1 1)
					(thickness 0.15)
				)
				(justify mirror)
			)
		)
		(property "Voltage" "6V"
			(at 0 0 270)
			(unlocked yes)
			(layer "B.Fab")
			(hide yes)
			(effects
				(font
					(size 1 1)
					(thickness 0.15)
				)
				(justify mirror)
			)
		)
		(property "Dielectric" "template_dielectric"
			(at 0 0 270)
			(unlocked yes)
			(layer "B.Fab")
			(hide yes)
			(effects
				(font
					(size 1 1)
					(thickness 0.15)
				)
				(justify mirror)
			)
		)
		(sheetname "/X710-AT2 power/")
		(sheetfile "x710-at2-power.kicad_sch")
		(attr smd)
		(fp_line
			(start -1.95 1.25)
			(end -1.95 0.95)
			(stroke
				(width 0.12)
				(type solid)
			)
			(layer "B.SilkS")
		)
		(fp_line
			(start -2.1 1.1)
			(end -1.8 1.1)
			(stroke
				(width 0.12)
				(type solid)
			)
			(layer "B.SilkS")
		)
		(fp_line
			(start -1.5 0.85)
			(end 1.5 0.85)
			(stroke
				(width 0.12)
				(type solid)
			)
			(layer "B.SilkS")
		)
		(fp_line
			(start -1.5 0.75)
			(end -1.5 0.85)
			(stroke
				(width 0.12)
				(type solid)
			)
			(layer "B.SilkS")
		)
		(fp_line
			(start 1.5 0.75)
			(end 1.5 0.85)
			(stroke
				(width 0.12)
				(type solid)
			)
			(layer "B.SilkS")
		)
		(fp_line
			(start -1.5 -0.75)
			(end -1.5 -0.85)
			(stroke
				(width 0.12)
				(type solid)
			)
			(layer "B.SilkS")
		)
		(fp_line
			(start 1.5 -0.75)
			(end 1.5 -0.85)
			(stroke
				(width 0.12)
				(type solid)
			)
			(layer "B.SilkS")
		)
		(fp_line
			(start 1.5 -0.85)
			(end -1.5 -0.85)
			(stroke
				(width 0.12)
				(type solid)
			)
			(layer "B.SilkS")
		)
		(fp_line
			(start 1.7 1.05)
			(end -1.7 1.05)
			(stroke
				(width 0.05)
				(type solid)
			)
			(layer "B.CrtYd")
		)
		(fp_line
			(start -2.05 0.85)
			(end -2.05 -0.85)
			(stroke
				(width 0.05)
				(type solid)
			)
			(layer "B.CrtYd")
		)
		(fp_line
			(start -1.7 0.85)
			(end -1.7 1.05)
			(stroke
				(width 0.05)
				(type solid)
			)
			(layer "B.CrtYd")
		)
		(fp_line
			(start -1.7 0.85)
			(end -2.05 0.85)
			(stroke
				(width 0.05)
				(type solid)
			)
			(layer "B.CrtYd")
		)
		(fp_line
			(start 1.7 0.85)
			(end 1.7 1.05)
			(stroke
				(width 0.05)
				(type solid)
			)
			(layer "B.CrtYd")
		)
		(fp_line
			(start 2.05 0.85)
			(end 1.7 0.85)
			(stroke
				(width 0.05)
				(type solid)
			)
			(layer "B.CrtYd")
		)
		(fp_line
			(start 2.05 0.85)
			(end 2.05 -0.85)
			(stroke
				(width 0.05)
				(type solid)
			)
			(layer "B.CrtYd")
		)
		(fp_line
			(start -1.7 -0.85)
			(end -2.05 -0.85)
			(stroke
				(width 0.05)
				(type solid)
			)
			(layer "B.CrtYd")
		)
		(fp_line
			(start 2.05 -0.85)
			(end 1.7 -0.85)
			(stroke
				(width 0.05)
				(type solid)
			)
			(layer "B.CrtYd")
		)
		(fp_line
			(start -1.7 -1.05)
			(end -1.7 -0.85)
			(stroke
				(width 0.05)
				(type solid)
			)
			(layer "B.CrtYd")
		)
		(fp_line
			(start 1.7 -1.05)
			(end 1.7 -0.85)
			(stroke
				(width 0.05)
				(type solid)
			)
			(layer "B.CrtYd")
		)
		(fp_line
			(start 1.7 -1.05)
			(end -1.7 -1.05)
			(stroke
				(width 0.05)
				(type solid)
			)
			(layer "B.CrtYd")
		)
		(fp_rect
			(start -1.601 0.802)
			(end 1.6 -0.8)
			(stroke
				(width 0.1)
				(type solid)
			)
			(fill no)
			(layer "B.Fab")
		)
		(fp_text user "License: Apache-2.0"
			(at -2.1 -5.198 90)
			(layer "B.Fab")
			(effects
				(font
					(size 0.7 0.7)
					(thickness 0.15)
				)
				(justify left bottom mirror)
			)
		)
		(fp_text user "Author: Antmicro"
			(at -2.1 -6.198 90)
			(layer "B.Fab")
			(effects
				(font
					(size 0.7 0.7)
					(thickness 0.15)
				)
				(justify left bottom mirror)
			)
		)
		(fp_text user "${REFERENCE}"
			(at -2.1 -4.198 90)
			(layer "B.Fab")
			(effects
				(font
					(size 0.7 0.7)
					(thickness 0.15)
				)
				(justify left bottom mirror)
			)
		)
		(pad "1" smd roundrect
			(at -1.2 0 270)
			(size 1.2 1.2)
			(layers "B.Cu" "B.Mask" "B.Paste")
			(roundrect_rratio 0.1)
			(net 6 "DVDD")
			(pintype "passive")
		)
		(pad "2" smd roundrect
			(at 1.2 0 270)
			(size 1.2 1.2)
			(layers "B.Cu" "B.Mask" "B.Paste")
			(roundrect_rratio 0.1)
			(net 23 "GND")
			(pintype "passive")
		)
	)
	(footprint "antmicro-footprints:C_0402_1005Metric"
		(layer "B.Cu")
		(at 153.031867 79.260117 180)
		(descr "Capacitor SMD 0402")
		(tags "capacitor SMD 0402")
		(property "Reference" "C263"
			(at -21.168135 -9.464883 0)
			(layer "B.SilkS")
			(effects
				(font
					(size 0.7 0.7)
					(thickness 0.15)
				)
				(justify mirror)
			)
		)
		(property "Value" "C_1u_25V_0402"
			(at -1.022927 -2.155213 0)
			(layer "B.Fab")
			(effects
				(font
					(size 0.7 0.7)
					(thickness 0.15)
				)
				(justify left bottom mirror)
			)
		)
		(property "Datasheet" "https://www.murata.com/products/productdetail?partno=GRM155R61E105KE11%23"
			(at 0 0 0)
			(layer "B.Fab")
			(hide yes)
			(effects
				(font
					(size 1.27 1.27)
					(thickness 0.15)
				)
				(justify mirror)
			)
		)
		(property "Description" "SMD Multilayer Ceramic Capacitor, 1 µF, 25 V, 0402 [1005 Metric], ± 10%, X5R, GRM Series"
			(at 0 0 0)
			(layer "B.Fab")
			(hide yes)
			(effects
				(font
					(size 1.27 1.27)
					(thickness 0.15)
				)
				(justify mirror)
			)
		)
		(property "MPN" "GRM155R61E105KE11J"
			(at 0 0 180)
			(unlocked yes)
			(layer "B.Fab")
			(hide yes)
			(effects
				(font
					(size 1 1)
					(thickness 0.15)
				)
				(justify mirror)
			)
		)
		(property "Manufacturer" "Murata"
			(at 0 0 180)
			(unlocked yes)
			(layer "B.Fab")
			(hide yes)
			(effects
				(font
					(size 1 1)
					(thickness 0.15)
				)
				(justify mirror)
			)
		)
		(property "License" "Apache-2.0"
			(at 0 0 180)
			(unlocked yes)
			(layer "B.Fab")
			(hide yes)
			(effects
				(font
					(size 1 1)
					(thickness 0.15)
				)
				(justify mirror)
			)
		)
		(property "Author" "Antmicro"
			(at 0 0 180)
			(unlocked yes)
			(layer "B.Fab")
			(hide yes)
			(effects
				(font
					(size 1 1)
					(thickness 0.15)
				)
				(justify mirror)
			)
		)
		(property "Val" "1u"
			(at 0 0 180)
			(unlocked yes)
			(layer "B.Fab")
			(hide yes)
			(effects
				(font
					(size 1 1)
					(thickness 0.15)
				)
				(justify mirror)
			)
		)
		(property "Voltage" "25V"
			(at 0 0 180)
			(unlocked yes)
			(layer "B.Fab")
			(hide yes)
			(effects
				(font
					(size 1 1)
					(thickness 0.15)
				)
				(justify mirror)
			)
		)
		(property "Dielectric" "X5R"
			(at 0 0 180)
			(unlocked yes)
			(layer "B.Fab")
			(hide yes)
			(effects
				(font
					(size 1 1)
					(thickness 0.15)
				)
				(justify mirror)
			)
		)
		(sheetname "/X710-AT2 power/")
		(sheetfile "x710-at2-power.kicad_sch")
		(attr smd)
		(fp_rect
			(start -0.925 0.47)
			(end 0.925 -0.47)
			(stroke
				(width 0.05)
				(type default)
			)
			(fill no)
			(layer "B.CrtYd")
		)
		(fp_line
			(start 0.504 0.25)
			(end 0.504 -0.248)
			(stroke
				(width 0.15)
				(type solid)
			)
			(layer "B.Fab")
		)
		(fp_line
			(start 0.504 -0.248)
			(end -0.494 -0.248)
			(stroke
				(width 0.15)
				(type solid)
			)
			(layer "B.Fab")
		)
		(fp_line
			(start -0.494 0.25)
			(end 0.504 0.25)
			(stroke
				(width 0.15)
				(type solid)
			)
			(layer "B.Fab")
		)
		(fp_line
			(start -0.494 -0.248)
			(end -0.494 0.25)
			(stroke
				(width 0.15)
				(type solid)
			)
			(layer "B.Fab")
		)
		(fp_text user "License: Apache-2.0"
			(at -0.939 -5.799 0)
			(layer "B.Fab")
			(effects
				(font
					(size 0.7 0.7)
					(thickness 0.15)
				)
				(justify left bottom mirror)
			)
		)
		(fp_text user "${REFERENCE}"
			(at -0.939 -4.599 0)
			(layer "B.Fab")
			(effects
				(font
					(size 0.7 0.7)
					(thickness 0.15)
				)
				(justify left bottom mirror)
			)
		)
		(fp_text user "Author: Antmicro"
			(at -0.939 -3.399 0)
			(layer "B.Fab")
			(effects
				(font
					(size 0.7 0.7)
					(thickness 0.15)
				)
				(justify left bottom mirror)
			)
		)
		(pad "1" smd roundrect
			(at -0.48 0 180)
			(size 0.59 0.64)
			(layers "B.Cu" "B.Mask" "B.Paste")
			(roundrect_rratio 0.25)
			(net 23 "GND")
			(pintype "passive")
		)
		(pad "2" smd roundrect
			(at 0.48 0 180)
			(size 0.59 0.64)
			(layers "B.Cu" "B.Mask" "B.Paste")
			(roundrect_rratio 0.25)
			(net 1 "VCCA")
			(pintype "passive")
		)
	)
	(footprint "antmicro-footprints:C_0402_1005Metric"
		(layer "B.Cu")
		(at 147.481866 76.260118 180)
		(descr "Capacitor SMD 0402")
		(tags "capacitor SMD 0402")
		(property "Reference" "C233"
			(at -18.618135 -9.464883 0)
			(layer "B.SilkS")
			(effects
				(font
					(size 0.7 0.7)
					(thickness 0.15)
				)
				(justify mirror)
			)
		)
		(property "Value" "C_1u_25V_0402"
			(at -1.022927 -2.155213 0)
			(layer "B.Fab")
			(effects
				(font
					(size 0.7 0.7)
					(thickness 0.15)
				)
				(justify left bottom mirror)
			)
		)
		(property "Datasheet" "https://www.murata.com/products/productdetail?partno=GRM155R61E105KE11%23"
			(at 0 0 0)
			(layer "B.Fab")
			(hide yes)
			(effects
				(font
					(size 1.27 1.27)
					(thickness 0.15)
				)
				(justify mirror)
			)
		)
		(property "Description" "SMD Multilayer Ceramic Capacitor, 1 µF, 25 V, 0402 [1005 Metric], ± 10%, X5R, GRM Series"
			(at 0 0 0)
			(layer "B.Fab")
			(hide yes)
			(effects
				(font
					(size 1.27 1.27)
					(thickness 0.15)
				)
				(justify mirror)
			)
		)
		(property "MPN" "GRM155R61E105KE11J"
			(at 0 0 180)
			(unlocked yes)
			(layer "B.Fab")
			(hide yes)
			(effects
				(font
					(size 1 1)
					(thickness 0.15)
				)
				(justify mirror)
			)
		)
		(property "Manufacturer" "Murata"
			(at 0 0 180)
			(unlocked yes)
			(layer "B.Fab")
			(hide yes)
			(effects
				(font
					(size 1 1)
					(thickness 0.15)
				)
				(justify mirror)
			)
		)
		(property "License" "Apache-2.0"
			(at 0 0 180)
			(unlocked yes)
			(layer "B.Fab")
			(hide yes)
			(effects
				(font
					(size 1 1)
					(thickness 0.15)
				)
				(justify mirror)
			)
		)
		(property "Author" "Antmicro"
			(at 0 0 180)
			(unlocked yes)
			(layer "B.Fab")
			(hide yes)
			(effects
				(font
					(size 1 1)
					(thickness 0.15)
				)
				(justify mirror)
			)
		)
		(property "Val" "1u"
			(at 0 0 180)
			(unlocked yes)
			(layer "B.Fab")
			(hide yes)
			(effects
				(font
					(size 1 1)
					(thickness 0.15)
				)
				(justify mirror)
			)
		)
		(property "Voltage" "25V"
			(at 0 0 180)
			(unlocked yes)
			(layer "B.Fab")
			(hide yes)
			(effects
				(font
					(size 1 1)
					(thickness 0.15)
				)
				(justify mirror)
			)
		)
		(property "Dielectric" "X5R"
			(at 0 0 180)
			(unlocked yes)
			(layer "B.Fab")
			(hide yes)
			(effects
				(font
					(size 1 1)
					(thickness 0.15)
				)
				(justify mirror)
			)
		)
		(sheetname "/X710-AT2 power/")
		(sheetfile "x710-at2-power.kicad_sch")
		(attr smd)
		(fp_rect
			(start -0.925 0.47)
			(end 0.925 -0.47)
			(stroke
				(width 0.05)
				(type default)
			)
			(fill no)
			(layer "B.CrtYd")
		)
		(fp_line
			(start 0.504 0.25)
			(end 0.504 -0.248)
			(stroke
				(width 0.15)
				(type solid)
			)
			(layer "B.Fab")
		)
		(fp_line
			(start 0.504 -0.248)
			(end -0.494 -0.248)
			(stroke
				(width 0.15)
				(type solid)
			)
			(layer "B.Fab")
		)
		(fp_line
			(start -0.494 0.25)
			(end 0.504 0.25)
			(stroke
				(width 0.15)
				(type solid)
			)
			(layer "B.Fab")
		)
		(fp_line
			(start -0.494 -0.248)
			(end -0.494 0.25)
			(stroke
				(width 0.15)
				(type solid)
			)
			(layer "B.Fab")
		)
		(fp_text user "${REFERENCE}"
			(at -0.939 -4.599 0)
			(layer "B.Fab")
			(effects
				(font
					(size 0.7 0.7)
					(thickness 0.15)
				)
				(justify left bottom mirror)
			)
		)
		(fp_text user "License: Apache-2.0"
			(at -0.939 -5.799 0)
			(layer "B.Fab")
			(effects
				(font
					(size 0.7 0.7)
					(thickness 0.15)
				)
				(justify left bottom mirror)
			)
		)
		(fp_text user "Author: Antmicro"
			(at -0.939 -3.399 0)
			(layer "B.Fab")
			(effects
				(font
					(size 0.7 0.7)
					(thickness 0.15)
				)
				(justify left bottom mirror)
			)
		)
		(pad "1" smd roundrect
			(at -0.48 0 180)
			(size 0.59 0.64)
			(layers "B.Cu" "B.Mask" "B.Paste")
			(roundrect_rratio 0.25)
			(net 23 "GND")
			(pintype "passive")
		)
		(pad "2" smd roundrect
			(at 0.48 0 180)
			(size 0.59 0.64)
			(layers "B.Cu" "B.Mask" "B.Paste")
			(roundrect_rratio 0.25)
			(net 9 "VCCD")
			(pintype "passive")
		)
	)
	(footprint "antmicro-footprints:R_0402_1005Metric"
		(layer "B.Cu")
		(at 131.424999 125.900001 -90)
		(descr "Resistor SMD 0402")
		(tags "resistor SMD 0402")
		(property "Reference" "R66"
			(at -7.700002 -21.900002 90)
			(layer "B.SilkS")
			(effects
				(font
					(size 0.7 0.7)
					(thickness 0.15)
				)
				(justify mirror)
			)
		)
		(property "Value" "R_4k75_0.5%_0402"
			(at -1.011843 -1.772047 90)
			(layer "B.Fab")
			(effects
				(font
					(size 0.7 0.7)
					(thickness 0.15)
				)
				(justify left bottom mirror)
			)
		)
		(property "Datasheet" "https://industrial.panasonic.com/cdbs/www-data/pdf/RDQ0000/ast-ind-151033.pdf"
			(at 0 0 90)
			(layer "B.Fab")
			(hide yes)
			(effects
				(font
					(size 1.27 1.27)
					(thickness 0.15)
				)
				(justify mirror)
			)
		)
		(property "Description" "SMD Chip Resistor, 4.75 kohm, ± 0.5%, 100 mW, 0402 [1005 Metric], Thick Film, High Temperature"
			(at 0 0 90)
			(layer "B.Fab")
			(hide yes)
			(effects
				(font
					(size 1.27 1.27)
					(thickness 0.15)
				)
				(justify mirror)
			)
		)
		(property "MPN" "ERJ-H2RD4751X"
			(at 0 0 270)
			(unlocked yes)
			(layer "B.Fab")
			(hide yes)
			(effects
				(font
					(size 1 1)
					(thickness 0.15)
				)
				(justify mirror)
			)
		)
		(property "Manufacturer" "Panasonic"
			(at 0 0 270)
			(unlocked yes)
			(layer "B.Fab")
			(hide yes)
			(effects
				(font
					(size 1 1)
					(thickness 0.15)
				)
				(justify mirror)
			)
		)
		(property "License" "Apache-2.0"
			(at 0 0 270)
			(unlocked yes)
			(layer "B.Fab")
			(hide yes)
			(effects
				(font
					(size 1 1)
					(thickness 0.15)
				)
				(justify mirror)
			)
		)
		(property "Val" "4k75"
			(at 0 0 270)
			(unlocked yes)
			(layer "B.Fab")
			(hide yes)
			(effects
				(font
					(size 1 1)
					(thickness 0.15)
				)
				(justify mirror)
			)
		)
		(property "Tolerance" "0.5%"
			(at 0 0 270)
			(unlocked yes)
			(layer "B.Fab")
			(hide yes)
			(effects
				(font
					(size 1 1)
					(thickness 0.15)
				)
				(justify mirror)
			)
		)
		(property "Author" "Antmicro"
			(at 0 0 270)
			(unlocked yes)
			(layer "B.Fab")
			(hide yes)
			(effects
				(font
					(size 1 1)
					(thickness 0.15)
				)
				(justify mirror)
			)
		)
		(sheetname "/TB Controller/")
		(sheetfile "tb.kicad_sch")
		(attr smd)
		(fp_rect
			(start -0.925 0.47)
			(end 0.925 -0.47)
			(stroke
				(width 0.05)
				(type default)
			)
			(fill no)
			(layer "B.CrtYd")
		)
		(fp_rect
			(start -0.5 0.25)
			(end 0.5 -0.25)
			(stroke
				(width 0.15)
				(type solid)
			)
			(fill no)
			(layer "B.Fab")
		)
		(fp_text user "${REFERENCE}"
			(at -0.95 -3.168 90)
			(layer "B.Fab")
			(effects
				(font
					(size 0.7 0.7)
					(thickness 0.15)
				)
				(justify left bottom mirror)
			)
		)
		(fp_text user "Author: Antmicro"
			(at -0.95 -4.169 90)
			(layer "B.Fab")
			(effects
				(font
					(size 0.7 0.7)
					(thickness 0.15)
				)
				(justify left bottom mirror)
			)
		)
		(fp_text user "License: Apache-2.0"
			(at -0.95 -5.169 90)
			(layer "B.Fab")
			(effects
				(font
					(size 0.7 0.7)
					(thickness 0.15)
				)
				(justify left bottom mirror)
			)
		)
		(pad "1" smd roundrect
			(at -0.48 0 270)
			(size 0.59 0.64)
			(layers "B.Cu" "B.Mask" "B.Paste")
			(roundrect_rratio 0.25)
			(net 229 "Net-(U4D-RSENSE)")
			(pintype "passive")
		)
		(pad "2" smd roundrect
			(at 0.48 0 270)
			(size 0.59 0.64)
			(layers "B.Cu" "B.Mask" "B.Paste")
			(roundrect_rratio 0.25)
			(net 230 "Net-(U4D-RBIAS)")
			(pintype "passive")
		)
	)
	(footprint "antmicro-footprints:C_0402_1005Metric"
		(layer "B.Cu")
		(at 147.481866 77.260117 180)
		(descr "Capacitor SMD 0402")
		(tags "capacitor SMD 0402")
		(property "Reference" "C228"
			(at -18.618135 -9.464883 0)
			(layer "B.SilkS")
			(effects
				(font
					(size 0.7 0.7)
					(thickness 0.15)
				)
				(justify mirror)
			)
		)
		(property "Value" "C_1u_25V_0402"
			(at -1.022927 -2.155213 0)
			(layer "B.Fab")
			(effects
				(font
					(size 0.7 0.7)
					(thickness 0.15)
				)
				(justify left bottom mirror)
			)
		)
		(property "Datasheet" "https://www.murata.com/products/productdetail?partno=GRM155R61E105KE11%23"
			(at 0 0 0)
			(layer "B.Fab")
			(hide yes)
			(effects
				(font
					(size 1.27 1.27)
					(thickness 0.15)
				)
				(justify mirror)
			)
		)
		(property "Description" "SMD Multilayer Ceramic Capacitor, 1 µF, 25 V, 0402 [1005 Metric], ± 10%, X5R, GRM Series"
			(at 0 0 0)
			(layer "B.Fab")
			(hide yes)
			(effects
				(font
					(size 1.27 1.27)
					(thickness 0.15)
				)
				(justify mirror)
			)
		)
		(property "MPN" "GRM155R61E105KE11J"
			(at 0 0 180)
			(unlocked yes)
			(layer "B.Fab")
			(hide yes)
			(effects
				(font
					(size 1 1)
					(thickness 0.15)
				)
				(justify mirror)
			)
		)
		(property "Manufacturer" "Murata"
			(at 0 0 180)
			(unlocked yes)
			(layer "B.Fab")
			(hide yes)
			(effects
				(font
					(size 1 1)
					(thickness 0.15)
				)
				(justify mirror)
			)
		)
		(property "License" "Apache-2.0"
			(at 0 0 180)
			(unlocked yes)
			(layer "B.Fab")
			(hide yes)
			(effects
				(font
					(size 1 1)
					(thickness 0.15)
				)
				(justify mirror)
			)
		)
		(property "Author" "Antmicro"
			(at 0 0 180)
			(unlocked yes)
			(layer "B.Fab")
			(hide yes)
			(effects
				(font
					(size 1 1)
					(thickness 0.15)
				)
				(justify mirror)
			)
		)
		(property "Val" "1u"
			(at 0 0 180)
			(unlocked yes)
			(layer "B.Fab")
			(hide yes)
			(effects
				(font
					(size 1 1)
					(thickness 0.15)
				)
				(justify mirror)
			)
		)
		(property "Voltage" "25V"
			(at 0 0 180)
			(unlocked yes)
			(layer "B.Fab")
			(hide yes)
			(effects
				(font
					(size 1 1)
					(thickness 0.15)
				)
				(justify mirror)
			)
		)
		(property "Dielectric" "X5R"
			(at 0 0 180)
			(unlocked yes)
			(layer "B.Fab")
			(hide yes)
			(effects
				(font
					(size 1 1)
					(thickness 0.15)
				)
				(justify mirror)
			)
		)
		(sheetname "/X710-AT2 power/")
		(sheetfile "x710-at2-power.kicad_sch")
		(attr smd)
		(fp_rect
			(start -0.925 0.47)
			(end 0.925 -0.47)
			(stroke
				(width 0.05)
				(type default)
			)
			(fill no)
			(layer "B.CrtYd")
		)
		(fp_line
			(start 0.504 0.25)
			(end 0.504 -0.248)
			(stroke
				(width 0.15)
				(type solid)
			)
			(layer "B.Fab")
		)
		(fp_line
			(start 0.504 -0.248)
			(end -0.494 -0.248)
			(stroke
				(width 0.15)
				(type solid)
			)
			(layer "B.Fab")
		)
		(fp_line
			(start -0.494 0.25)
			(end 0.504 0.25)
			(stroke
				(width 0.15)
				(type solid)
			)
			(layer "B.Fab")
		)
		(fp_line
			(start -0.494 -0.248)
			(end -0.494 0.25)
			(stroke
				(width 0.15)
				(type solid)
			)
			(layer "B.Fab")
		)
		(fp_text user "Author: Antmicro"
			(at -0.939 -3.399 0)
			(layer "B.Fab")
			(effects
				(font
					(size 0.7 0.7)
					(thickness 0.15)
				)
				(justify left bottom mirror)
			)
		)
		(fp_text user "${REFERENCE}"
			(at -0.939 -4.599 0)
			(layer "B.Fab")
			(effects
				(font
					(size 0.7 0.7)
					(thickness 0.15)
				)
				(justify left bottom mirror)
			)
		)
		(fp_text user "License: Apache-2.0"
			(at -0.939 -5.799 0)
			(layer "B.Fab")
			(effects
				(font
					(size 0.7 0.7)
					(thickness 0.15)
				)
				(justify left bottom mirror)
			)
		)
		(pad "1" smd roundrect
			(at -0.48 0 180)
			(size 0.59 0.64)
			(layers "B.Cu" "B.Mask" "B.Paste")
			(roundrect_rratio 0.25)
			(net 23 "GND")
			(pintype "passive")
		)
		(pad "2" smd roundrect
			(at 0.48 0 180)
			(size 0.59 0.64)
			(layers "B.Cu" "B.Mask" "B.Paste")
			(roundrect_rratio 0.25)
			(net 9 "VCCD")
			(pintype "passive")
		)
	)
	(footprint "antmicro-footprints:C_0402_1005Metric"
		(layer "B.Cu")
		(at 151.181866 78.260117 180)
		(descr "Capacitor SMD 0402")
		(tags "capacitor SMD 0402")
		(property "Reference" "C232"
			(at -20.368136 -9.464883 0)
			(layer "B.SilkS")
			(effects
				(font
					(size 0.7 0.7)
					(thickness 0.15)
				)
				(justify mirror)
			)
		)
		(property "Value" "C_1u_25V_0402"
			(at -1.022927 -2.155213 0)
			(layer "B.Fab")
			(effects
				(font
					(size 0.7 0.7)
					(thickness 0.15)
				)
				(justify left bottom mirror)
			)
		)
		(property "Datasheet" "https://www.murata.com/products/productdetail?partno=GRM155R61E105KE11%23"
			(at 0 0 0)
			(layer "B.Fab")
			(hide yes)
			(effects
				(font
					(size 1.27 1.27)
					(thickness 0.15)
				)
				(justify mirror)
			)
		)
		(property "Description" "SMD Multilayer Ceramic Capacitor, 1 µF, 25 V, 0402 [1005 Metric], ± 10%, X5R, GRM Series"
			(at 0 0 0)
			(layer "B.Fab")
			(hide yes)
			(effects
				(font
					(size 1.27 1.27)
					(thickness 0.15)
				)
				(justify mirror)
			)
		)
		(property "MPN" "GRM155R61E105KE11J"
			(at 0 0 180)
			(unlocked yes)
			(layer "B.Fab")
			(hide yes)
			(effects
				(font
					(size 1 1)
					(thickness 0.15)
				)
				(justify mirror)
			)
		)
		(property "Manufacturer" "Murata"
			(at 0 0 180)
			(unlocked yes)
			(layer "B.Fab")
			(hide yes)
			(effects
				(font
					(size 1 1)
					(thickness 0.15)
				)
				(justify mirror)
			)
		)
		(property "License" "Apache-2.0"
			(at 0 0 180)
			(unlocked yes)
			(layer "B.Fab")
			(hide yes)
			(effects
				(font
					(size 1 1)
					(thickness 0.15)
				)
				(justify mirror)
			)
		)
		(property "Author" "Antmicro"
			(at 0 0 180)
			(unlocked yes)
			(layer "B.Fab")
			(hide yes)
			(effects
				(font
					(size 1 1)
					(thickness 0.15)
				)
				(justify mirror)
			)
		)
		(property "Val" "1u"
			(at 0 0 180)
			(unlocked yes)
			(layer "B.Fab")
			(hide yes)
			(effects
				(font
					(size 1 1)
					(thickness 0.15)
				)
				(justify mirror)
			)
		)
		(property "Voltage" "25V"
			(at 0 0 180)
			(unlocked yes)
			(layer "B.Fab")
			(hide yes)
			(effects
				(font
					(size 1 1)
					(thickness 0.15)
				)
				(justify mirror)
			)
		)
		(property "Dielectric" "X5R"
			(at 0 0 180)
			(unlocked yes)
			(layer "B.Fab")
			(hide yes)
			(effects
				(font
					(size 1 1)
					(thickness 0.15)
				)
				(justify mirror)
			)
		)
		(sheetname "/X710-AT2 power/")
		(sheetfile "x710-at2-power.kicad_sch")
		(attr smd)
		(fp_rect
			(start -0.925 0.47)
			(end 0.925 -0.47)
			(stroke
				(width 0.05)
				(type default)
			)
			(fill no)
			(layer "B.CrtYd")
		)
		(fp_line
			(start 0.504 0.25)
			(end 0.504 -0.248)
			(stroke
				(width 0.15)
				(type solid)
			)
			(layer "B.Fab")
		)
		(fp_line
			(start 0.504 -0.248)
			(end -0.494 -0.248)
			(stroke
				(width 0.15)
				(type solid)
			)
			(layer "B.Fab")
		)
		(fp_line
			(start -0.494 0.25)
			(end 0.504 0.25)
			(stroke
				(width 0.15)
				(type solid)
			)
			(layer "B.Fab")
		)
		(fp_line
			(start -0.494 -0.248)
			(end -0.494 0.25)
			(stroke
				(width 0.15)
				(type solid)
			)
			(layer "B.Fab")
		)
		(fp_text user "${REFERENCE}"
			(at -0.939 -4.599 0)
			(layer "B.Fab")
			(effects
				(font
					(size 0.7 0.7)
					(thickness 0.15)
				)
				(justify left bottom mirror)
			)
		)
		(fp_text user "Author: Antmicro"
			(at -0.939 -3.399 0)
			(layer "B.Fab")
			(effects
				(font
					(size 0.7 0.7)
					(thickness 0.15)
				)
				(justify left bottom mirror)
			)
		)
		(fp_text user "License: Apache-2.0"
			(at -0.939 -5.799 0)
			(layer "B.Fab")
			(effects
				(font
					(size 0.7 0.7)
					(thickness 0.15)
				)
				(justify left bottom mirror)
			)
		)
		(pad "1" smd roundrect
			(at -0.48 0 180)
			(size 0.59 0.64)
			(layers "B.Cu" "B.Mask" "B.Paste")
			(roundrect_rratio 0.25)
			(net 23 "GND")
			(pintype "passive")
		)
		(pad "2" smd roundrect
			(at 0.48 0 180)
			(size 0.59 0.64)
			(layers "B.Cu" "B.Mask" "B.Paste")
			(roundrect_rratio 0.25)
			(net 1 "VCCA")
			(pintype "passive")
		)
	)
	(footprint "antmicro-footprints:R_0402_1005Metric"
		(layer "B.Cu")
		(at 136.75 140.9 -90)
		(descr "Resistor SMD 0402")
		(tags "resistor SMD 0402")
		(property "Reference" "R28"
			(at -9.557574 -19.525001 90)
			(layer "B.SilkS")
			(effects
				(font
					(size 0.7 0.7)
					(thickness 0.15)
				)
				(justify mirror)
			)
		)
		(property "Value" "R_100k_0402"
			(at -1.011843 -1.772047 90)
			(layer "B.Fab")
			(effects
				(font
					(size 0.7 0.7)
					(thickness 0.15)
				)
				(justify left bottom mirror)
			)
		)
		(property "Datasheet" "https://www.bourns.com/docs/product-datasheets/cr.pdf"
			(at 0 0 90)
			(layer "B.Fab")
			(hide yes)
			(effects
				(font
					(size 1.27 1.27)
					(thickness 0.15)
				)
				(justify mirror)
			)
		)
		(property "Description" "SMD Chip Resistor, 100 kohm, ± 1%, 62.5 mW, 0402 [1005 Metric], Thick Film, General Purpose"
			(at 0 0 90)
			(layer "B.Fab")
			(hide yes)
			(effects
				(font
					(size 1.27 1.27)
					(thickness 0.15)
				)
				(justify mirror)
			)
		)
		(property "MPN" "CR0402-FX-1003GLF"
			(at 0 0 270)
			(unlocked yes)
			(layer "B.Fab")
			(hide yes)
			(effects
				(font
					(size 1 1)
					(thickness 0.15)
				)
				(justify mirror)
			)
		)
		(property "Manufacturer" "Bourns"
			(at 0 0 270)
			(unlocked yes)
			(layer "B.Fab")
			(hide yes)
			(effects
				(font
					(size 1 1)
					(thickness 0.15)
				)
				(justify mirror)
			)
		)
		(property "License" "Apache-2.0"
			(at 0 0 270)
			(unlocked yes)
			(layer "B.Fab")
			(hide yes)
			(effects
				(font
					(size 1 1)
					(thickness 0.15)
				)
				(justify mirror)
			)
		)
		(property "Val" "100k"
			(at 0 0 270)
			(unlocked yes)
			(layer "B.Fab")
			(hide yes)
			(effects
				(font
					(size 1 1)
					(thickness 0.15)
				)
				(justify mirror)
			)
		)
		(property "Tolerance" "1%"
			(at 0 0 270)
			(unlocked yes)
			(layer "B.Fab")
			(hide yes)
			(effects
				(font
					(size 1 1)
					(thickness 0.15)
				)
				(justify mirror)
			)
		)
		(property "Author" "Antmicro"
			(at 0 0 270)
			(unlocked yes)
			(layer "B.Fab")
			(hide yes)
			(effects
				(font
					(size 1 1)
					(thickness 0.15)
				)
				(justify mirror)
			)
		)
		(sheetname "/PD and TB DC-DC/")
		(sheetfile "PD_and_TB_DC_DC.kicad_sch")
		(attr smd)
		(fp_rect
			(start -0.925 0.47)
			(end 0.925 -0.47)
			(stroke
				(width 0.05)
				(type default)
			)
			(fill no)
			(layer "B.CrtYd")
		)
		(fp_rect
			(start -0.5 0.25)
			(end 0.5 -0.25)
			(stroke
				(width 0.15)
				(type solid)
			)
			(fill no)
			(layer "B.Fab")
		)
		(fp_text user "Author: Antmicro"
			(at -0.95 -4.169 90)
			(layer "B.Fab")
			(effects
				(font
					(size 0.7 0.7)
					(thickness 0.15)
				)
				(justify left bottom mirror)
			)
		)
		(fp_text user "${REFERENCE}"
			(at -0.95 -3.168 90)
			(layer "B.Fab")
			(effects
				(font
					(size 0.7 0.7)
					(thickness 0.15)
				)
				(justify left bottom mirror)
			)
		)
		(fp_text user "License: Apache-2.0"
			(at -0.95 -5.169 90)
			(layer "B.Fab")
			(effects
				(font
					(size 0.7 0.7)
					(thickness 0.15)
				)
				(justify left bottom mirror)
			)
		)
		(pad "1" smd roundrect
			(at -0.48 0 270)
			(size 0.59 0.64)
			(layers "B.Cu" "B.Mask" "B.Paste")
			(roundrect_rratio 0.25)
			(net 211 "Net-(U3-BUSPOWERZ(GPIO10))")
			(pintype "passive")
		)
		(pad "2" smd roundrect
			(at 0.48 0 270)
			(size 0.59 0.64)
			(layers "B.Cu" "B.Mask" "B.Paste")
			(roundrect_rratio 0.25)
			(net 304 "/PD and TB DC-DC/TPS_3V3")
			(pintype "passive")
		)
	)
	(footprint "antmicro-footprints:R_0402_1005Metric"
		(layer "B.Cu")
		(at 139.199999 133.600001 180)
		(descr "Resistor SMD 0402")
		(tags "resistor SMD 0402")
		(property "Reference" "R8"
			(at -19.525001 8.1 0)
			(layer "B.SilkS")
			(effects
				(font
					(size 0.7 0.7)
					(thickness 0.15)
				)
				(justify mirror)
			)
		)
		(property "Value" "R_10k_0402"
			(at -1.011843 -1.772047 0)
			(layer "B.Fab")
			(effects
				(font
					(size 0.7 0.7)
					(thickness 0.15)
				)
				(justify left bottom mirror)
			)
		)
		(property "Datasheet" "https://www.bourns.com/docs/product-datasheets/cr.pdf"
			(at 0 0 0)
			(layer "B.Fab")
			(hide yes)
			(effects
				(font
					(size 1.27 1.27)
					(thickness 0.15)
				)
				(justify mirror)
			)
		)
		(property "Description" "SMD Chip Resistor, 10 kohm, ± 1%, 62.5 mW, 0402 [1005 Metric], Thick Film, General Purpose"
			(at 0 0 0)
			(layer "B.Fab")
			(hide yes)
			(effects
				(font
					(size 1.27 1.27)
					(thickness 0.15)
				)
				(justify mirror)
			)
		)
		(property "MPN" "CR0402-FX-1002GLF"
			(at 0 0 180)
			(unlocked yes)
			(layer "B.Fab")
			(hide yes)
			(effects
				(font
					(size 1 1)
					(thickness 0.15)
				)
				(justify mirror)
			)
		)
		(property "Manufacturer" "Bourns"
			(at 0 0 180)
			(unlocked yes)
			(layer "B.Fab")
			(hide yes)
			(effects
				(font
					(size 1 1)
					(thickness 0.15)
				)
				(justify mirror)
			)
		)
		(property "License" "Apache-2.0"
			(at 0 0 180)
			(unlocked yes)
			(layer "B.Fab")
			(hide yes)
			(effects
				(font
					(size 1 1)
					(thickness 0.15)
				)
				(justify mirror)
			)
		)
		(property "Val" "10k"
			(at 0 0 180)
			(unlocked yes)
			(layer "B.Fab")
			(hide yes)
			(effects
				(font
					(size 1 1)
					(thickness 0.15)
				)
				(justify mirror)
			)
		)
		(property "Tolerance" "1%"
			(at 0 0 180)
			(unlocked yes)
			(layer "B.Fab")
			(hide yes)
			(effects
				(font
					(size 1 1)
					(thickness 0.15)
				)
				(justify mirror)
			)
		)
		(property "Author" "Antmicro"
			(at 0 0 180)
			(unlocked yes)
			(layer "B.Fab")
			(hide yes)
			(effects
				(font
					(size 1 1)
					(thickness 0.15)
				)
				(justify mirror)
			)
		)
		(sheetname "/PD and TB DC-DC/")
		(sheetfile "PD_and_TB_DC_DC.kicad_sch")
		(attr smd)
		(fp_rect
			(start -0.925 0.47)
			(end 0.925 -0.47)
			(stroke
				(width 0.05)
				(type default)
			)
			(fill no)
			(layer "B.CrtYd")
		)
		(fp_rect
			(start -0.5 0.25)
			(end 0.5 -0.25)
			(stroke
				(width 0.15)
				(type solid)
			)
			(fill no)
			(layer "B.Fab")
		)
		(fp_text user "License: Apache-2.0"
			(at -0.95 -5.169 0)
			(layer "B.Fab")
			(effects
				(font
					(size 0.7 0.7)
					(thickness 0.15)
				)
				(justify left bottom mirror)
			)
		)
		(fp_text user "Author: Antmicro"
			(at -0.95 -4.169 0)
			(layer "B.Fab")
			(effects
				(font
					(size 0.7 0.7)
					(thickness 0.15)
				)
				(justify left bottom mirror)
			)
		)
		(fp_text user "${REFERENCE}"
			(at -0.95 -3.168 0)
			(layer "B.Fab")
			(effects
				(font
					(size 0.7 0.7)
					(thickness 0.15)
				)
				(justify left bottom mirror)
			)
		)
		(pad "1" smd roundrect
			(at -0.48 0 180)
			(size 0.59 0.64)
			(layers "B.Cu" "B.Mask" "B.Paste")
			(roundrect_rratio 0.25)
			(net 372 "/PD and TB DC-DC/I2C1.IRQ")
			(pintype "passive")
		)
		(pad "2" smd roundrect
			(at 0.48 0 180)
			(size 0.59 0.64)
			(layers "B.Cu" "B.Mask" "B.Paste")
			(roundrect_rratio 0.25)
			(net 57 "+3V3_TB")
			(pintype "passive")
		)
	)
	(footprint "antmicro-footprints:TP_SMD_0.75mm"
		(layer "B.Cu")
		(at 152.2 62.935117 -90)
		(property "Reference" "TP25"
			(at -3.135117 -0.2 90)
			(layer "B.SilkS")
			(effects
				(font
					(size 0.7 0.7)
					(thickness 0.15)
				)
				(justify left bottom mirror)
			)
		)
		(property "Value" "TP_0.75mm_SMD"
			(at 0 -1.2 90)
			(layer "B.Fab")
			(effects
				(font
					(size 0.7 0.7)
					(thickness 0.15)
				)
				(justify left bottom mirror)
			)
		)
		(property "Description" "SMT test point"
			(at 0 0 90)
			(layer "B.Fab")
			(hide yes)
			(effects
				(font
					(size 1.27 1.27)
					(thickness 0.15)
				)
				(justify mirror)
			)
		)
		(property "MPN" ""
			(at 0 0 270)
			(unlocked yes)
			(layer "B.Fab")
			(hide yes)
			(effects
				(font
					(size 1 1)
					(thickness 0.15)
				)
				(justify mirror)
			)
		)
		(property "Manufacturer" ""
			(at 0 0 270)
			(unlocked yes)
			(layer "B.Fab")
			(hide yes)
			(effects
				(font
					(size 1 1)
					(thickness 0.15)
				)
				(justify mirror)
			)
		)
		(property "Author" "Antmicro"
			(at 0 0 270)
			(unlocked yes)
			(layer "B.Fab")
			(hide yes)
			(effects
				(font
					(size 1 1)
					(thickness 0.15)
				)
				(justify mirror)
			)
		)
		(property "License" "Apache-2.0"
			(at 0 0 270)
			(unlocked yes)
			(layer "B.Fab")
			(hide yes)
			(effects
				(font
					(size 1 1)
					(thickness 0.15)
				)
				(justify mirror)
			)
		)
		(sheetname "/X710-AT2 Misc/")
		(sheetfile "x710-at2-mics.kicad_sch")
		(attr exclude_from_pos_files exclude_from_bom)
		(fp_circle
			(center 0 0)
			(end 0.475 0)
			(stroke
				(width 0.05)
				(type default)
			)
			(fill no)
			(layer "B.CrtYd")
		)
		(fp_text user "License: Apache-2.0"
			(at -0.4 -5.101 90)
			(layer "B.Fab")
			(effects
				(font
					(size 0.7 0.7)
					(thickness 0.15)
				)
				(justify left bottom mirror)
			)
		)
		(fp_text user "${REFERENCE}"
			(at -0.4 -2.7 90)
			(layer "B.Fab")
			(effects
				(font
					(size 0.7 0.7)
					(thickness 0.15)
				)
				(justify left bottom mirror)
			)
		)
		(fp_text user "Author: Antmicro"
			(at -0.4 -3.901 90)
			(layer "B.Fab")
			(effects
				(font
					(size 0.7 0.7)
					(thickness 0.15)
				)
				(justify left bottom mirror)
			)
		)
		(pad "1" smd circle
			(at 0 0 270)
			(size 0.75 0.75)
			(layers "B.Cu" "B.Mask")
			(net 143 "/X710-AT2 Misc/NCSI.TX_EN")
			(pinfunction "1")
			(pintype "passive")
		)
	)
	(footprint "antmicro-footprints:C_0402_1005Metric"
		(layer "B.Cu")
		(at 154.261865 88.265117 180)
		(descr "Capacitor SMD 0402")
		(tags "capacitor SMD 0402")
		(property "Reference" "C195"
			(at -17.938134 -9.464883 0)
			(layer "B.SilkS")
			(effects
				(font
					(size 0.7 0.7)
					(thickness 0.15)
				)
				(justify mirror)
			)
		)
		(property "Value" "C_1u_25V_0402"
			(at -1.022927 -2.155213 0)
			(layer "B.Fab")
			(effects
				(font
					(size 0.7 0.7)
					(thickness 0.15)
				)
				(justify left bottom mirror)
			)
		)
		(property "Datasheet" "https://www.murata.com/products/productdetail?partno=GRM155R61E105KE11%23"
			(at 0 0 0)
			(layer "B.Fab")
			(hide yes)
			(effects
				(font
					(size 1.27 1.27)
					(thickness 0.15)
				)
				(justify mirror)
			)
		)
		(property "Description" "SMD Multilayer Ceramic Capacitor, 1 µF, 25 V, 0402 [1005 Metric], ± 10%, X5R, GRM Series"
			(at 0 0 0)
			(layer "B.Fab")
			(hide yes)
			(effects
				(font
					(size 1.27 1.27)
					(thickness 0.15)
				)
				(justify mirror)
			)
		)
		(property "MPN" "GRM155R61E105KE11J"
			(at 0 0 180)
			(unlocked yes)
			(layer "B.Fab")
			(hide yes)
			(effects
				(font
					(size 1 1)
					(thickness 0.15)
				)
				(justify mirror)
			)
		)
		(property "Manufacturer" "Murata"
			(at 0 0 180)
			(unlocked yes)
			(layer "B.Fab")
			(hide yes)
			(effects
				(font
					(size 1 1)
					(thickness 0.15)
				)
				(justify mirror)
			)
		)
		(property "License" "Apache-2.0"
			(at 0 0 180)
			(unlocked yes)
			(layer "B.Fab")
			(hide yes)
			(effects
				(font
					(size 1 1)
					(thickness 0.15)
				)
				(justify mirror)
			)
		)
		(property "Author" "Antmicro"
			(at 0 0 180)
			(unlocked yes)
			(layer "B.Fab")
			(hide yes)
			(effects
				(font
					(size 1 1)
					(thickness 0.15)
				)
				(justify mirror)
			)
		)
		(property "Val" "1u"
			(at 0 0 180)
			(unlocked yes)
			(layer "B.Fab")
			(hide yes)
			(effects
				(font
					(size 1 1)
					(thickness 0.15)
				)
				(justify mirror)
			)
		)
		(property "Voltage" "25V"
			(at 0 0 180)
			(unlocked yes)
			(layer "B.Fab")
			(hide yes)
			(effects
				(font
					(size 1 1)
					(thickness 0.15)
				)
				(justify mirror)
			)
		)
		(property "Dielectric" "X5R"
			(at 0 0 180)
			(unlocked yes)
			(layer "B.Fab")
			(hide yes)
			(effects
				(font
					(size 1 1)
					(thickness 0.15)
				)
				(justify mirror)
			)
		)
		(sheetname "/X710-AT2 power/")
		(sheetfile "x710-at2-power.kicad_sch")
		(attr smd)
		(fp_rect
			(start -0.925 0.47)
			(end 0.925 -0.47)
			(stroke
				(width 0.05)
				(type default)
			)
			(fill no)
			(layer "B.CrtYd")
		)
		(fp_line
			(start 0.504 0.25)
			(end 0.504 -0.248)
			(stroke
				(width 0.15)
				(type solid)
			)
			(layer "B.Fab")
		)
		(fp_line
			(start 0.504 -0.248)
			(end -0.494 -0.248)
			(stroke
				(width 0.15)
				(type solid)
			)
			(layer "B.Fab")
		)
		(fp_line
			(start -0.494 0.25)
			(end 0.504 0.25)
			(stroke
				(width 0.15)
				(type solid)
			)
			(layer "B.Fab")
		)
		(fp_line
			(start -0.494 -0.248)
			(end -0.494 0.25)
			(stroke
				(width 0.15)
				(type solid)
			)
			(layer "B.Fab")
		)
		(fp_text user "License: Apache-2.0"
			(at -0.939 -5.799 0)
			(layer "B.Fab")
			(effects
				(font
					(size 0.7 0.7)
					(thickness 0.15)
				)
				(justify left bottom mirror)
			)
		)
		(fp_text user "Author: Antmicro"
			(at -0.939 -3.399 0)
			(layer "B.Fab")
			(effects
				(font
					(size 0.7 0.7)
					(thickness 0.15)
				)
				(justify left bottom mirror)
			)
		)
		(fp_text user "${REFERENCE}"
			(at -0.939 -4.599 0)
			(layer "B.Fab")
			(effects
				(font
					(size 0.7 0.7)
					(thickness 0.15)
				)
				(justify left bottom mirror)
			)
		)
		(pad "1" smd roundrect
			(at -0.48 0 180)
			(size 0.59 0.64)
			(layers "B.Cu" "B.Mask" "B.Paste")
			(roundrect_rratio 0.25)
			(net 23 "GND")
			(pintype "passive")
		)
		(pad "2" smd roundrect
			(at 0.48 0 180)
			(size 0.59 0.64)
			(layers "B.Cu" "B.Mask" "B.Paste")
			(roundrect_rratio 0.25)
			(net 12 "XFI_VDD")
			(pintype "passive")
		)
	)
	(footprint "antmicro-footprints:TP_SMD_0.75mm"
		(layer "B.Cu")
		(at 120.5 86 90)
		(property "Reference" "TP1"
			(at 0.8 1.5 270)
			(layer "B.SilkS")
			(effects
				(font
					(size 0.7 0.7)
					(thickness 0.15)
				)
				(justify left bottom mirror)
			)
		)
		(property "Value" "TP_0.75mm_SMD"
			(at 0 -1.2 270)
			(layer "B.Fab")
			(effects
				(font
					(size 0.7 0.7)
					(thickness 0.15)
				)
				(justify left bottom mirror)
			)
		)
		(property "Description" "SMT test point"
			(at 0 0 270)
			(layer "B.Fab")
			(hide yes)
			(effects
				(font
					(size 1.27 1.27)
					(thickness 0.15)
				)
				(justify mirror)
			)
		)
		(property "License" "Apache-2.0"
			(at 0 0 90)
			(unlocked yes)
			(layer "B.Fab")
			(hide yes)
			(effects
				(font
					(size 1 1)
					(thickness 0.15)
				)
				(justify mirror)
			)
		)
		(property "Manufacturer" ""
			(at 0 0 90)
			(unlocked yes)
			(layer "B.Fab")
			(hide yes)
			(effects
				(font
					(size 1 1)
					(thickness 0.15)
				)
				(justify mirror)
			)
		)
		(property "MPN" ""
			(at 0 0 90)
			(unlocked yes)
			(layer "B.Fab")
			(hide yes)
			(effects
				(font
					(size 1 1)
					(thickness 0.15)
				)
				(justify mirror)
			)
		)
		(property "Author" "Antmicro"
			(at 0 0 90)
			(unlocked yes)
			(layer "B.Fab")
			(hide yes)
			(effects
				(font
					(size 1 1)
					(thickness 0.15)
				)
				(justify mirror)
			)
		)
		(sheetname "/PD and TB DC-DC/")
		(sheetfile "PD_and_TB_DC_DC.kicad_sch")
		(attr exclude_from_pos_files exclude_from_bom)
		(fp_circle
			(center 0 0)
			(end 0.475 0)
			(stroke
				(width 0.05)
				(type default)
			)
			(fill no)
			(layer "B.CrtYd")
		)
		(fp_text user "${REFERENCE}"
			(at -0.4 -2.7 270)
			(layer "B.Fab")
			(effects
				(font
					(size 0.7 0.7)
					(thickness 0.15)
				)
				(justify left bottom mirror)
			)
		)
		(fp_text user "License: Apache-2.0"
			(at -0.4 -5.101 270)
			(layer "B.Fab")
			(effects
				(font
					(size 0.7 0.7)
					(thickness 0.15)
				)
				(justify left bottom mirror)
			)
		)
		(fp_text user "Author: Antmicro"
			(at -0.4 -3.901 270)
			(layer "B.Fab")
			(effects
				(font
					(size 0.7 0.7)
					(thickness 0.15)
				)
				(justify left bottom mirror)
			)
		)
		(pad "1" smd circle
			(at 0 0 90)
			(size 0.75 0.75)
			(layers "B.Cu" "B.Mask")
			(net 53 "+5V_USB")
			(pinfunction "1")
			(pintype "passive")
		)
	)
	(footprint "antmicro-footprints:R_0402_1005Metric"
		(layer "B.Cu")
		(at 120 94.75 180)
		(descr "Resistor SMD 0402")
		(tags "resistor SMD 0402")
		(property "Reference" "R73"
			(at -0.7 -5.6 0)
			(layer "B.SilkS")
			(effects
				(font
					(size 0.7 0.7)
					(thickness 0.15)
				)
				(justify left bottom mirror)
			)
		)
		(property "Value" "R_100k_0402"
			(at -1.011843 -1.772047 0)
			(layer "B.Fab")
			(effects
				(font
					(size 0.7 0.7)
					(thickness 0.15)
				)
				(justify left bottom mirror)
			)
		)
		(property "Datasheet" "https://www.bourns.com/docs/product-datasheets/cr.pdf"
			(at 0 0 0)
			(layer "B.Fab")
			(hide yes)
			(effects
				(font
					(size 1.27 1.27)
					(thickness 0.15)
				)
				(justify mirror)
			)
		)
		(property "Description" "SMD Chip Resistor, 100 kohm, ± 1%, 62.5 mW, 0402 [1005 Metric], Thick Film, General Purpose"
			(at 0 0 0)
			(layer "B.Fab")
			(hide yes)
			(effects
				(font
					(size 1.27 1.27)
					(thickness 0.15)
				)
				(justify mirror)
			)
		)
		(property "MPN" "CR0402-FX-1003GLF"
			(at 0 0 180)
			(unlocked yes)
			(layer "B.Fab")
			(hide yes)
			(effects
				(font
					(size 1 1)
					(thickness 0.15)
				)
				(justify mirror)
			)
		)
		(property "Manufacturer" "Bourns"
			(at 0 0 180)
			(unlocked yes)
			(layer "B.Fab")
			(hide yes)
			(effects
				(font
					(size 1 1)
					(thickness 0.15)
				)
				(justify mirror)
			)
		)
		(property "License" "Apache-2.0"
			(at 0 0 180)
			(unlocked yes)
			(layer "B.Fab")
			(hide yes)
			(effects
				(font
					(size 1 1)
					(thickness 0.15)
				)
				(justify mirror)
			)
		)
		(property "Val" "100k"
			(at 0 0 180)
			(unlocked yes)
			(layer "B.Fab")
			(hide yes)
			(effects
				(font
					(size 1 1)
					(thickness 0.15)
				)
				(justify mirror)
			)
		)
		(property "Tolerance" "1%"
			(at 0 0 180)
			(unlocked yes)
			(layer "B.Fab")
			(hide yes)
			(effects
				(font
					(size 1 1)
					(thickness 0.15)
				)
				(justify mirror)
			)
		)
		(property "Author" "Antmicro"
			(at 0 0 180)
			(unlocked yes)
			(layer "B.Fab")
			(hide yes)
			(effects
				(font
					(size 1 1)
					(thickness 0.15)
				)
				(justify mirror)
			)
		)
		(sheetname "/TB Controller - Power/")
		(sheetfile "tb-power.kicad_sch")
		(attr smd)
		(fp_rect
			(start -0.925 0.47)
			(end 0.925 -0.47)
			(stroke
				(width 0.05)
				(type default)
			)
			(fill no)
			(layer "B.CrtYd")
		)
		(fp_rect
			(start -0.5 0.25)
			(end 0.5 -0.25)
			(stroke
				(width 0.15)
				(type solid)
			)
			(fill no)
			(layer "B.Fab")
		)
		(fp_text user "Author: Antmicro"
			(at -0.95 -4.169 0)
			(layer "B.Fab")
			(effects
				(font
					(size 0.7 0.7)
					(thickness 0.15)
				)
				(justify left bottom mirror)
			)
		)
		(fp_text user "${REFERENCE}"
			(at -0.95 -3.168 0)
			(layer "B.Fab")
			(effects
				(font
					(size 0.7 0.7)
					(thickness 0.15)
				)
				(justify left bottom mirror)
			)
		)
		(fp_text user "License: Apache-2.0"
			(at -0.95 -5.169 0)
			(layer "B.Fab")
			(effects
				(font
					(size 0.7 0.7)
					(thickness 0.15)
				)
				(justify left bottom mirror)
			)
		)
		(pad "1" smd roundrect
			(at -0.48 0 180)
			(size 0.59 0.64)
			(layers "B.Cu" "B.Mask" "B.Paste")
			(roundrect_rratio 0.25)
			(net 23 "GND")
			(pintype "passive")
		)
		(pad "2" smd roundrect
			(at 0.48 0 180)
			(size 0.59 0.64)
			(layers "B.Cu" "B.Mask" "B.Paste")
			(roundrect_rratio 0.25)
			(net 196 "Net-(Q1-B)")
			(pintype "passive")
		)
	)
	(footprint "antmicro-footprints:C_0402_1005Metric"
		(layer "B.Cu")
		(at 147.481865 80.260117 180)
		(descr "Capacitor SMD 0402")
		(tags "capacitor SMD 0402")
		(property "Reference" "C212"
			(at -18.618135 -9.464883 0)
			(layer "B.SilkS")
			(effects
				(font
					(size 0.7 0.7)
					(thickness 0.15)
				)
				(justify mirror)
			)
		)
		(property "Value" "C_1u_25V_0402"
			(at -1.022927 -2.155213 0)
			(layer "B.Fab")
			(effects
				(font
					(size 0.7 0.7)
					(thickness 0.15)
				)
				(justify left bottom mirror)
			)
		)
		(property "Datasheet" "https://www.murata.com/products/productdetail?partno=GRM155R61E105KE11%23"
			(at 0 0 0)
			(layer "B.Fab")
			(hide yes)
			(effects
				(font
					(size 1.27 1.27)
					(thickness 0.15)
				)
				(justify mirror)
			)
		)
		(property "Description" "SMD Multilayer Ceramic Capacitor, 1 µF, 25 V, 0402 [1005 Metric], ± 10%, X5R, GRM Series"
			(at 0 0 0)
			(layer "B.Fab")
			(hide yes)
			(effects
				(font
					(size 1.27 1.27)
					(thickness 0.15)
				)
				(justify mirror)
			)
		)
		(property "MPN" "GRM155R61E105KE11J"
			(at 0 0 180)
			(unlocked yes)
			(layer "B.Fab")
			(hide yes)
			(effects
				(font
					(size 1 1)
					(thickness 0.15)
				)
				(justify mirror)
			)
		)
		(property "Manufacturer" "Murata"
			(at 0 0 180)
			(unlocked yes)
			(layer "B.Fab")
			(hide yes)
			(effects
				(font
					(size 1 1)
					(thickness 0.15)
				)
				(justify mirror)
			)
		)
		(property "License" "Apache-2.0"
			(at 0 0 180)
			(unlocked yes)
			(layer "B.Fab")
			(hide yes)
			(effects
				(font
					(size 1 1)
					(thickness 0.15)
				)
				(justify mirror)
			)
		)
		(property "Author" "Antmicro"
			(at 0 0 180)
			(unlocked yes)
			(layer "B.Fab")
			(hide yes)
			(effects
				(font
					(size 1 1)
					(thickness 0.15)
				)
				(justify mirror)
			)
		)
		(property "Val" "1u"
			(at 0 0 180)
			(unlocked yes)
			(layer "B.Fab")
			(hide yes)
			(effects
				(font
					(size 1 1)
					(thickness 0.15)
				)
				(justify mirror)
			)
		)
		(property "Voltage" "25V"
			(at 0 0 180)
			(unlocked yes)
			(layer "B.Fab")
			(hide yes)
			(effects
				(font
					(size 1 1)
					(thickness 0.15)
				)
				(justify mirror)
			)
		)
		(property "Dielectric" "X5R"
			(at 0 0 180)
			(unlocked yes)
			(layer "B.Fab")
			(hide yes)
			(effects
				(font
					(size 1 1)
					(thickness 0.15)
				)
				(justify mirror)
			)
		)
		(sheetname "/X710-AT2 power/")
		(sheetfile "x710-at2-power.kicad_sch")
		(attr smd)
		(fp_rect
			(start -0.925 0.47)
			(end 0.925 -0.47)
			(stroke
				(width 0.05)
				(type default)
			)
			(fill no)
			(layer "B.CrtYd")
		)
		(fp_line
			(start 0.504 0.25)
			(end 0.504 -0.248)
			(stroke
				(width 0.15)
				(type solid)
			)
			(layer "B.Fab")
		)
		(fp_line
			(start 0.504 -0.248)
			(end -0.494 -0.248)
			(stroke
				(width 0.15)
				(type solid)
			)
			(layer "B.Fab")
		)
		(fp_line
			(start -0.494 0.25)
			(end 0.504 0.25)
			(stroke
				(width 0.15)
				(type solid)
			)
			(layer "B.Fab")
		)
		(fp_line
			(start -0.494 -0.248)
			(end -0.494 0.25)
			(stroke
				(width 0.15)
				(type solid)
			)
			(layer "B.Fab")
		)
		(fp_text user "License: Apache-2.0"
			(at -0.939 -5.799 0)
			(layer "B.Fab")
			(effects
				(font
					(size 0.7 0.7)
					(thickness 0.15)
				)
				(justify left bottom mirror)
			)
		)
		(fp_text user "${REFERENCE}"
			(at -0.939 -4.599 0)
			(layer "B.Fab")
			(effects
				(font
					(size 0.7 0.7)
					(thickness 0.15)
				)
				(justify left bottom mirror)
			)
		)
		(fp_text user "Author: Antmicro"
			(at -0.939 -3.399 0)
			(layer "B.Fab")
			(effects
				(font
					(size 0.7 0.7)
					(thickness 0.15)
				)
				(justify left bottom mirror)
			)
		)
		(pad "1" smd roundrect
			(at -0.48 0 180)
			(size 0.59 0.64)
			(layers "B.Cu" "B.Mask" "B.Paste")
			(roundrect_rratio 0.25)
			(net 23 "GND")
			(pintype "passive")
		)
		(pad "2" smd roundrect
			(at 0.48 0 180)
			(size 0.59 0.64)
			(layers "B.Cu" "B.Mask" "B.Paste")
			(roundrect_rratio 0.25)
			(net 9 "VCCD")
			(pintype "passive")
		)
	)
	(footprint "antmicro-footprints:R_0402_1005Metric"
		(layer "B.Cu")
		(at 158.831866 75.760117 180)
		(descr "Resistor SMD 0402")
		(tags "resistor SMD 0402")
		(property "Reference" "R162"
			(at -20.168136 -8.989883 0)
			(layer "B.SilkS")
			(effects
				(font
					(size 0.7 0.7)
					(thickness 0.15)
				)
				(justify mirror)
			)
		)
		(property "Value" "R_1k_0402"
			(at -1.011843 -1.772047 0)
			(layer "B.Fab")
			(effects
				(font
					(size 0.7 0.7)
					(thickness 0.15)
				)
				(justify left bottom mirror)
			)
		)
		(property "Datasheet" "https://www.bourns.com/docs/product-datasheets/cr.pdf"
			(at 0 0 0)
			(layer "B.Fab")
			(hide yes)
			(effects
				(font
					(size 1.27 1.27)
					(thickness 0.15)
				)
				(justify mirror)
			)
		)
		(property "Description" "SMD Chip Resistor, 1 kohm, ± 1%, 63 mW, 0402 [1005 Metric], Thick Film, General Purpose"
			(at 0 0 0)
			(layer "B.Fab")
			(hide yes)
			(effects
				(font
					(size 1.27 1.27)
					(thickness 0.15)
				)
				(justify mirror)
			)
		)
		(property "MPN" "CR0402-FX-1001GLF"
			(at 0 0 180)
			(unlocked yes)
			(layer "B.Fab")
			(hide yes)
			(effects
				(font
					(size 1 1)
					(thickness 0.15)
				)
				(justify mirror)
			)
		)
		(property "Manufacturer" "Bourns"
			(at 0 0 180)
			(unlocked yes)
			(layer "B.Fab")
			(hide yes)
			(effects
				(font
					(size 1 1)
					(thickness 0.15)
				)
				(justify mirror)
			)
		)
		(property "License" "Apache-2.0"
			(at 0 0 180)
			(unlocked yes)
			(layer "B.Fab")
			(hide yes)
			(effects
				(font
					(size 1 1)
					(thickness 0.15)
				)
				(justify mirror)
			)
		)
		(property "Author" "Antmicro"
			(at 0 0 180)
			(unlocked yes)
			(layer "B.Fab")
			(hide yes)
			(effects
				(font
					(size 1 1)
					(thickness 0.15)
				)
				(justify mirror)
			)
		)
		(property "Val" "1k"
			(at 0 0 180)
			(unlocked yes)
			(layer "B.Fab")
			(hide yes)
			(effects
				(font
					(size 1 1)
					(thickness 0.15)
				)
				(justify mirror)
			)
		)
		(property "Tolerance" "1%"
			(at 0 0 180)
			(unlocked yes)
			(layer "B.Fab")
			(hide yes)
			(effects
				(font
					(size 1 1)
					(thickness 0.15)
				)
				(justify mirror)
			)
		)
		(sheetname "/X710-AT2 Misc/")
		(sheetfile "x710-at2-mics.kicad_sch")
		(attr smd)
		(fp_rect
			(start -0.925 0.47)
			(end 0.925 -0.47)
			(stroke
				(width 0.05)
				(type default)
			)
			(fill no)
			(layer "B.CrtYd")
		)
		(fp_rect
			(start -0.5 0.25)
			(end 0.5 -0.25)
			(stroke
				(width 0.15)
				(type solid)
			)
			(fill no)
			(layer "B.Fab")
		)
		(fp_text user "${REFERENCE}"
			(at -0.95 -3.168 0)
			(layer "B.Fab")
			(effects
				(font
					(size 0.7 0.7)
					(thickness 0.15)
				)
				(justify left bottom mirror)
			)
		)
		(fp_text user "Author: Antmicro"
			(at -0.95 -4.169 0)
			(layer "B.Fab")
			(effects
				(font
					(size 0.7 0.7)
					(thickness 0.15)
				)
				(justify left bottom mirror)
			)
		)
		(fp_text user "License: Apache-2.0"
			(at -0.95 -5.169 0)
			(layer "B.Fab")
			(effects
				(font
					(size 0.7 0.7)
					(thickness 0.15)
				)
				(justify left bottom mirror)
			)
		)
		(pad "1" smd roundrect
			(at -0.48 0 180)
			(size 0.59 0.64)
			(layers "B.Cu" "B.Mask" "B.Paste")
			(roundrect_rratio 0.25)
			(net 23 "GND")
			(pintype "passive")
		)
		(pad "2" smd roundrect
			(at 0.48 0 180)
			(size 0.59 0.64)
			(layers "B.Cu" "B.Mask" "B.Paste")
			(roundrect_rratio 0.25)
			(net 132 "/X710-AT2 Misc/XTAL_BYPASS")
			(pintype "passive")
		)
	)
	(footprint "antmicro-footprints:R_0402_1005Metric"
		(layer "B.Cu")
		(at 134.75 140.9 90)
		(descr "Resistor SMD 0402")
		(tags "resistor SMD 0402")
		(property "Reference" "R17"
			(at 9.557574 19.525001 270)
			(layer "B.SilkS")
			(effects
				(font
					(size 0.7 0.7)
					(thickness 0.15)
				)
				(justify mirror)
			)
		)
		(property "Value" "R_10k_0402"
			(at -1.011843 -1.772047 270)
			(layer "B.Fab")
			(effects
				(font
					(size 0.7 0.7)
					(thickness 0.15)
				)
				(justify left bottom mirror)
			)
		)
		(property "Datasheet" "https://www.bourns.com/docs/product-datasheets/cr.pdf"
			(at 0 0 270)
			(layer "B.Fab")
			(hide yes)
			(effects
				(font
					(size 1.27 1.27)
					(thickness 0.15)
				)
				(justify mirror)
			)
		)
		(property "Description" "SMD Chip Resistor, 10 kohm, ± 1%, 62.5 mW, 0402 [1005 Metric], Thick Film, General Purpose"
			(at 0 0 270)
			(layer "B.Fab")
			(hide yes)
			(effects
				(font
					(size 1.27 1.27)
					(thickness 0.15)
				)
				(justify mirror)
			)
		)
		(property "MPN" "CR0402-FX-1002GLF"
			(at 0 0 90)
			(unlocked yes)
			(layer "B.Fab")
			(hide yes)
			(effects
				(font
					(size 1 1)
					(thickness 0.15)
				)
				(justify mirror)
			)
		)
		(property "Manufacturer" "Bourns"
			(at 0 0 90)
			(unlocked yes)
			(layer "B.Fab")
			(hide yes)
			(effects
				(font
					(size 1 1)
					(thickness 0.15)
				)
				(justify mirror)
			)
		)
		(property "License" "Apache-2.0"
			(at 0 0 90)
			(unlocked yes)
			(layer "B.Fab")
			(hide yes)
			(effects
				(font
					(size 1 1)
					(thickness 0.15)
				)
				(justify mirror)
			)
		)
		(property "Val" "10k"
			(at 0 0 90)
			(unlocked yes)
			(layer "B.Fab")
			(hide yes)
			(effects
				(font
					(size 1 1)
					(thickness 0.15)
				)
				(justify mirror)
			)
		)
		(property "Tolerance" "1%"
			(at 0 0 90)
			(unlocked yes)
			(layer "B.Fab")
			(hide yes)
			(effects
				(font
					(size 1 1)
					(thickness 0.15)
				)
				(justify mirror)
			)
		)
		(property "Author" "Antmicro"
			(at 0 0 90)
			(unlocked yes)
			(layer "B.Fab")
			(hide yes)
			(effects
				(font
					(size 1 1)
					(thickness 0.15)
				)
				(justify mirror)
			)
		)
		(sheetname "/PD and TB DC-DC/")
		(sheetfile "PD_and_TB_DC_DC.kicad_sch")
		(attr smd)
		(fp_rect
			(start -0.925 0.47)
			(end 0.925 -0.47)
			(stroke
				(width 0.05)
				(type default)
			)
			(fill no)
			(layer "B.CrtYd")
		)
		(fp_rect
			(start -0.5 0.25)
			(end 0.5 -0.25)
			(stroke
				(width 0.15)
				(type solid)
			)
			(fill no)
			(layer "B.Fab")
		)
		(fp_text user "${REFERENCE}"
			(at -0.95 -3.168 270)
			(layer "B.Fab")
			(effects
				(font
					(size 0.7 0.7)
					(thickness 0.15)
				)
				(justify left bottom mirror)
			)
		)
		(fp_text user "License: Apache-2.0"
			(at -0.95 -5.169 270)
			(layer "B.Fab")
			(effects
				(font
					(size 0.7 0.7)
					(thickness 0.15)
				)
				(justify left bottom mirror)
			)
		)
		(fp_text user "Author: Antmicro"
			(at -0.95 -4.169 270)
			(layer "B.Fab")
			(effects
				(font
					(size 0.7 0.7)
					(thickness 0.15)
				)
				(justify left bottom mirror)
			)
		)
		(pad "1" smd roundrect
			(at -0.48 0 90)
			(size 0.59 0.64)
			(layers "B.Cu" "B.Mask" "B.Paste")
			(roundrect_rratio 0.25)
			(net 304 "/PD and TB DC-DC/TPS_3V3")
			(pintype "passive")
		)
		(pad "2" smd roundrect
			(at 0.48 0 90)
			(size 0.59 0.64)
			(layers "B.Cu" "B.Mask" "B.Paste")
			(roundrect_rratio 0.25)
			(net 203 "Net-(U3-GPIO6)")
			(pintype "passive")
		)
	)
	(footprint "antmicro-footprints:R_0402_1005Metric"
		(layer "B.Cu")
		(at 155.131866 70.035117 -90)
		(descr "Resistor SMD 0402")
		(tags "resistor SMD 0402")
		(property "Reference" "R168"
			(at 9.464883 -19.468134 90)
			(layer "B.SilkS")
			(effects
				(font
					(size 0.7 0.7)
					(thickness 0.15)
				)
				(justify mirror)
			)
		)
		(property "Value" "R_22R_0402"
			(at -1.011843 -1.772047 90)
			(layer "B.Fab")
			(effects
				(font
					(size 0.7 0.7)
					(thickness 0.15)
				)
				(justify left bottom mirror)
			)
		)
		(property "Datasheet" "https://www.bourns.com/docs/product-datasheets/cr.pdf"
			(at 0 0 90)
			(layer "B.Fab")
			(hide yes)
			(effects
				(font
					(size 1.27 1.27)
					(thickness 0.15)
				)
				(justify mirror)
			)
		)
		(property "Description" "SMD Chip Resistor, 22 ohm, ± 1%, 62.5 mW, 0402 [1005 Metric], Thick Film, General Purpose"
			(at 0 0 90)
			(layer "B.Fab")
			(hide yes)
			(effects
				(font
					(size 1.27 1.27)
					(thickness 0.15)
				)
				(justify mirror)
			)
		)
		(property "MPN" "CR0402-FX-22R0GLF"
			(at 0 0 270)
			(unlocked yes)
			(layer "B.Fab")
			(hide yes)
			(effects
				(font
					(size 1 1)
					(thickness 0.15)
				)
				(justify mirror)
			)
		)
		(property "Manufacturer" "Bourns"
			(at 0 0 270)
			(unlocked yes)
			(layer "B.Fab")
			(hide yes)
			(effects
				(font
					(size 1 1)
					(thickness 0.15)
				)
				(justify mirror)
			)
		)
		(property "License" "Apache-2.0"
			(at 0 0 270)
			(unlocked yes)
			(layer "B.Fab")
			(hide yes)
			(effects
				(font
					(size 1 1)
					(thickness 0.15)
				)
				(justify mirror)
			)
		)
		(property "Author" "Antmicro"
			(at 0 0 270)
			(unlocked yes)
			(layer "B.Fab")
			(hide yes)
			(effects
				(font
					(size 1 1)
					(thickness 0.15)
				)
				(justify mirror)
			)
		)
		(property "Val" "22R"
			(at 0 0 270)
			(unlocked yes)
			(layer "B.Fab")
			(hide yes)
			(effects
				(font
					(size 1 1)
					(thickness 0.15)
				)
				(justify mirror)
			)
		)
		(property "Tolerance" "1%"
			(at 0 0 270)
			(unlocked yes)
			(layer "B.Fab")
			(hide yes)
			(effects
				(font
					(size 1 1)
					(thickness 0.15)
				)
				(justify mirror)
			)
		)
		(sheetname "/X710-AT2 Misc/")
		(sheetfile "x710-at2-mics.kicad_sch")
		(attr smd)
		(fp_rect
			(start -0.925 0.47)
			(end 0.925 -0.47)
			(stroke
				(width 0.05)
				(type default)
			)
			(fill no)
			(layer "B.CrtYd")
		)
		(fp_rect
			(start -0.5 0.25)
			(end 0.5 -0.25)
			(stroke
				(width 0.15)
				(type solid)
			)
			(fill no)
			(layer "B.Fab")
		)
		(fp_text user "Author: Antmicro"
			(at -0.95 -4.169 90)
			(layer "B.Fab")
			(effects
				(font
					(size 0.7 0.7)
					(thickness 0.15)
				)
				(justify left bottom mirror)
			)
		)
		(fp_text user "License: Apache-2.0"
			(at -0.95 -5.169 90)
			(layer "B.Fab")
			(effects
				(font
					(size 0.7 0.7)
					(thickness 0.15)
				)
				(justify left bottom mirror)
			)
		)
		(fp_text user "${REFERENCE}"
			(at -0.95 -3.168 90)
			(layer "B.Fab")
			(effects
				(font
					(size 0.7 0.7)
					(thickness 0.15)
				)
				(justify left bottom mirror)
			)
		)
		(pad "1" smd roundrect
			(at -0.48 0 270)
			(size 0.59 0.64)
			(layers "B.Cu" "B.Mask" "B.Paste")
			(roundrect_rratio 0.25)
			(net 139 "/X710-AT2 Misc/NCSI.RXD_0")
			(pintype "passive")
		)
		(pad "2" smd roundrect
			(at 0.48 0 270)
			(size 0.59 0.64)
			(layers "B.Cu" "B.Mask" "B.Paste")
			(roundrect_rratio 0.25)
			(net 442 "Net-(U14D-NCSI_RXD_0)")
			(pintype "passive")
		)
	)
	(footprint "antmicro-footprints:R_0402_1005Metric"
		(layer "B.Cu")
		(at 140.399999 137.580998 180)
		(descr "Resistor SMD 0402")
		(tags "resistor SMD 0402")
		(property "Reference" "R14"
			(at -19.525001 8.1 0)
			(layer "B.SilkS")
			(effects
				(font
					(size 0.7 0.7)
					(thickness 0.15)
				)
				(justify mirror)
			)
		)
		(property "Value" "R_10k_0402"
			(at -1.011843 -1.772047 0)
			(layer "B.Fab")
			(effects
				(font
					(size 0.7 0.7)
					(thickness 0.15)
				)
				(justify left bottom mirror)
			)
		)
		(property "Datasheet" "https://www.bourns.com/docs/product-datasheets/cr.pdf"
			(at 0 0 0)
			(layer "B.Fab")
			(hide yes)
			(effects
				(font
					(size 1.27 1.27)
					(thickness 0.15)
				)
				(justify mirror)
			)
		)
		(property "Description" "SMD Chip Resistor, 10 kohm, ± 1%, 62.5 mW, 0402 [1005 Metric], Thick Film, General Purpose"
			(at 0 0 0)
			(layer "B.Fab")
			(hide yes)
			(effects
				(font
					(size 1.27 1.27)
					(thickness 0.15)
				)
				(justify mirror)
			)
		)
		(property "MPN" "CR0402-FX-1002GLF"
			(at 0 0 180)
			(unlocked yes)
			(layer "B.Fab")
			(hide yes)
			(effects
				(font
					(size 1 1)
					(thickness 0.15)
				)
				(justify mirror)
			)
		)
		(property "Manufacturer" "Bourns"
			(at 0 0 180)
			(unlocked yes)
			(layer "B.Fab")
			(hide yes)
			(effects
				(font
					(size 1 1)
					(thickness 0.15)
				)
				(justify mirror)
			)
		)
		(property "License" "Apache-2.0"
			(at 0 0 180)
			(unlocked yes)
			(layer "B.Fab")
			(hide yes)
			(effects
				(font
					(size 1 1)
					(thickness 0.15)
				)
				(justify mirror)
			)
		)
		(property "Val" "10k"
			(at 0 0 180)
			(unlocked yes)
			(layer "B.Fab")
			(hide yes)
			(effects
				(font
					(size 1 1)
					(thickness 0.15)
				)
				(justify mirror)
			)
		)
		(property "Tolerance" "1%"
			(at 0 0 180)
			(unlocked yes)
			(layer "B.Fab")
			(hide yes)
			(effects
				(font
					(size 1 1)
					(thickness 0.15)
				)
				(justify mirror)
			)
		)
		(property "Author" "Antmicro"
			(at 0 0 180)
			(unlocked yes)
			(layer "B.Fab")
			(hide yes)
			(effects
				(font
					(size 1 1)
					(thickness 0.15)
				)
				(justify mirror)
			)
		)
		(sheetname "/PD and TB DC-DC/")
		(sheetfile "PD_and_TB_DC_DC.kicad_sch")
		(attr smd)
		(fp_rect
			(start -0.925 0.47)
			(end 0.925 -0.47)
			(stroke
				(width 0.05)
				(type default)
			)
			(fill no)
			(layer "B.CrtYd")
		)
		(fp_rect
			(start -0.5 0.25)
			(end 0.5 -0.25)
			(stroke
				(width 0.15)
				(type solid)
			)
			(fill no)
			(layer "B.Fab")
		)
		(fp_text user "${REFERENCE}"
			(at -0.95 -3.168 0)
			(layer "B.Fab")
			(effects
				(font
					(size 0.7 0.7)
					(thickness 0.15)
				)
				(justify left bottom mirror)
			)
		)
		(fp_text user "License: Apache-2.0"
			(at -0.95 -5.169 0)
			(layer "B.Fab")
			(effects
				(font
					(size 0.7 0.7)
					(thickness 0.15)
				)
				(justify left bottom mirror)
			)
		)
		(fp_text user "Author: Antmicro"
			(at -0.95 -4.169 0)
			(layer "B.Fab")
			(effects
				(font
					(size 0.7 0.7)
					(thickness 0.15)
				)
				(justify left bottom mirror)
			)
		)
		(pad "1" smd roundrect
			(at -0.48 0 180)
			(size 0.59 0.64)
			(layers "B.Cu" "B.Mask" "B.Paste")
			(roundrect_rratio 0.25)
			(net 304 "/PD and TB DC-DC/TPS_3V3")
			(pintype "passive")
		)
		(pad "2" smd roundrect
			(at 0.48 0 180)
			(size 0.59 0.64)
			(layers "B.Cu" "B.Mask" "B.Paste")
			(roundrect_rratio 0.25)
			(net 200 "Net-(U3-I2C_IRQ2Z)")
			(pintype "passive")
		)
	)
	(footprint "antmicro-footprints:C_0402_1005Metric"
		(layer "B.Cu")
		(at 127.05 126.375)
		(descr "Capacitor SMD 0402")
		(tags "capacitor SMD 0402")
		(property "Reference" "C93"
			(at 21.900002 -7.700002 180)
			(layer "B.SilkS")
			(effects
				(font
					(size 0.7 0.7)
					(thickness 0.15)
				)
				(justify mirror)
			)
		)
		(property "Value" "C_1u_0402"
			(at -1.022927 -2.155213 180)
			(layer "B.Fab")
			(effects
				(font
					(size 0.7 0.7)
					(thickness 0.15)
				)
				(justify left bottom mirror)
			)
		)
		(property "Datasheet" "https://product.tdk.com/en/search/capacitor/ceramic/mlcc/info?part_no=C1005X6S1A105K050BC"
			(at 0 0 180)
			(layer "B.Fab")
			(hide yes)
			(effects
				(font
					(size 1.27 1.27)
					(thickness 0.15)
				)
				(justify mirror)
			)
		)
		(property "Description" "SMD Multilayer Ceramic Capacitor, 1 µF, 10 V, 0402 [1005 Metric], ± 10%, X6S, C"
			(at 0 0 180)
			(layer "B.Fab")
			(hide yes)
			(effects
				(font
					(size 1.27 1.27)
					(thickness 0.15)
				)
				(justify mirror)
			)
		)
		(property "MPN" "C1005X6S1A105K050BC"
			(at 0 0 0)
			(unlocked yes)
			(layer "B.Fab")
			(hide yes)
			(effects
				(font
					(size 1 1)
					(thickness 0.15)
				)
				(justify mirror)
			)
		)
		(property "Manufacturer" "TDK"
			(at 0 0 0)
			(unlocked yes)
			(layer "B.Fab")
			(hide yes)
			(effects
				(font
					(size 1 1)
					(thickness 0.15)
				)
				(justify mirror)
			)
		)
		(property "License" "Apache-2.0"
			(at 0 0 0)
			(unlocked yes)
			(layer "B.Fab")
			(hide yes)
			(effects
				(font
					(size 1 1)
					(thickness 0.15)
				)
				(justify mirror)
			)
		)
		(property "Val" "1u"
			(at 0 0 0)
			(unlocked yes)
			(layer "B.Fab")
			(hide yes)
			(effects
				(font
					(size 1 1)
					(thickness 0.15)
				)
				(justify mirror)
			)
		)
		(property "Voltage" ""
			(at 0 0 0)
			(unlocked yes)
			(layer "B.Fab")
			(hide yes)
			(effects
				(font
					(size 1 1)
					(thickness 0.15)
				)
				(justify mirror)
			)
		)
		(property "Dielectric" ""
			(at 0 0 0)
			(unlocked yes)
			(layer "B.Fab")
			(hide yes)
			(effects
				(font
					(size 1 1)
					(thickness 0.15)
				)
				(justify mirror)
			)
		)
		(property "Author" "Antmicro"
			(at 0 0 0)
			(unlocked yes)
			(layer "B.Fab")
			(hide yes)
			(effects
				(font
					(size 1 1)
					(thickness 0.15)
				)
				(justify mirror)
			)
		)
		(sheetname "/TB Controller - Power/")
		(sheetfile "tb-power.kicad_sch")
		(attr smd)
		(fp_rect
			(start -0.925 0.47)
			(end 0.925 -0.47)
			(stroke
				(width 0.05)
				(type default)
			)
			(fill no)
			(layer "B.CrtYd")
		)
		(fp_line
			(start -0.494 -0.248)
			(end -0.494 0.25)
			(stroke
				(width 0.15)
				(type solid)
			)
			(layer "B.Fab")
		)
		(fp_line
			(start -0.494 0.25)
			(end 0.504 0.25)
			(stroke
				(width 0.15)
				(type solid)
			)
			(layer "B.Fab")
		)
		(fp_line
			(start 0.504 -0.248)
			(end -0.494 -0.248)
			(stroke
				(width 0.15)
				(type solid)
			)
			(layer "B.Fab")
		)
		(fp_line
			(start 0.504 0.25)
			(end 0.504 -0.248)
			(stroke
				(width 0.15)
				(type solid)
			)
			(layer "B.Fab")
		)
		(fp_text user "License: Apache-2.0"
			(at -0.939 -5.799 180)
			(layer "B.Fab")
			(effects
				(font
					(size 0.7 0.7)
					(thickness 0.15)
				)
				(justify left bottom mirror)
			)
		)
		(fp_text user "${REFERENCE}"
			(at -0.939 -4.599 180)
			(layer "B.Fab")
			(effects
				(font
					(size 0.7 0.7)
					(thickness 0.15)
				)
				(justify left bottom mirror)
			)
		)
		(fp_text user "Author: Antmicro"
			(at -0.939 -3.399 180)
			(layer "B.Fab")
			(effects
				(font
					(size 0.7 0.7)
					(thickness 0.15)
				)
				(justify left bottom mirror)
			)
		)
		(pad "1" smd roundrect
			(at -0.48 0)
			(size 0.59 0.64)
			(layers "B.Cu" "B.Mask" "B.Paste")
			(roundrect_rratio 0.25)
			(net 23 "GND")
			(pintype "passive")
		)
		(pad "2" smd roundrect
			(at 0.48 0)
			(size 0.59 0.64)
			(layers "B.Cu" "B.Mask" "B.Paste")
			(roundrect_rratio 0.25)
			(net 68 "/TB Controller - Power/VCC_0P9")
			(pintype "passive")
		)
	)
	(footprint "antmicro-footprints:C_0402_1005Metric"
		(layer "B.Cu")
		(at 138.350001 134.599997)
		(descr "Capacitor SMD 0402")
		(tags "capacitor SMD 0402")
		(property "Reference" "C21"
			(at 19.525001 -8.1 180)
			(layer "B.SilkS")
			(effects
				(font
					(size 0.7 0.7)
					(thickness 0.15)
				)
				(justify mirror)
			)
		)
		(property "Value" "C_2u2_0402"
			(at -1.022927 -2.155213 180)
			(layer "B.Fab")
			(effects
				(font
					(size 0.7 0.7)
					(thickness 0.15)
				)
				(justify left bottom mirror)
			)
		)
		(property "Datasheet" "https://product.tdk.com/en/search/capacitor/ceramic/mlcc/info?part_no=C1005X5R1A225K050BC"
			(at 0 0 180)
			(layer "B.Fab")
			(hide yes)
			(effects
				(font
					(size 1.27 1.27)
					(thickness 0.15)
				)
				(justify mirror)
			)
		)
		(property "Description" "SMD Multilayer Ceramic Capacitor, 2.2 µF, 10 V, 0402 [1005 Metric], ± 10%, X5R, C"
			(at 0 0 180)
			(layer "B.Fab")
			(hide yes)
			(effects
				(font
					(size 1.27 1.27)
					(thickness 0.15)
				)
				(justify mirror)
			)
		)
		(property "MPN" "C1005X5R1A225K050BC"
			(at 0 0 0)
			(unlocked yes)
			(layer "B.Fab")
			(hide yes)
			(effects
				(font
					(size 1 1)
					(thickness 0.15)
				)
				(justify mirror)
			)
		)
		(property "Manufacturer" "TDK"
			(at 0 0 0)
			(unlocked yes)
			(layer "B.Fab")
			(hide yes)
			(effects
				(font
					(size 1 1)
					(thickness 0.15)
				)
				(justify mirror)
			)
		)
		(property "License" "Apache-2.0"
			(at 0 0 0)
			(unlocked yes)
			(layer "B.Fab")
			(hide yes)
			(effects
				(font
					(size 1 1)
					(thickness 0.15)
				)
				(justify mirror)
			)
		)
		(property "Val" "2u2"
			(at 0 0 0)
			(unlocked yes)
			(layer "B.Fab")
			(hide yes)
			(effects
				(font
					(size 1 1)
					(thickness 0.15)
				)
				(justify mirror)
			)
		)
		(property "Voltage" ""
			(at 0 0 0)
			(unlocked yes)
			(layer "B.Fab")
			(hide yes)
			(effects
				(font
					(size 1 1)
					(thickness 0.15)
				)
				(justify mirror)
			)
		)
		(property "Dielectric" ""
			(at 0 0 0)
			(unlocked yes)
			(layer "B.Fab")
			(hide yes)
			(effects
				(font
					(size 1 1)
					(thickness 0.15)
				)
				(justify mirror)
			)
		)
		(property "Author" "Antmicro"
			(at 0 0 0)
			(unlocked yes)
			(layer "B.Fab")
			(hide yes)
			(effects
				(font
					(size 1 1)
					(thickness 0.15)
				)
				(justify mirror)
			)
		)
		(sheetname "/PD and TB DC-DC/")
		(sheetfile "PD_and_TB_DC_DC.kicad_sch")
		(attr smd)
		(fp_rect
			(start -0.925 0.47)
			(end 0.925 -0.47)
			(stroke
				(width 0.05)
				(type default)
			)
			(fill no)
			(layer "B.CrtYd")
		)
		(fp_line
			(start -0.494 -0.248)
			(end -0.494 0.25)
			(stroke
				(width 0.15)
				(type solid)
			)
			(layer "B.Fab")
		)
		(fp_line
			(start -0.494 0.25)
			(end 0.504 0.25)
			(stroke
				(width 0.15)
				(type solid)
			)
			(layer "B.Fab")
		)
		(fp_line
			(start 0.504 -0.248)
			(end -0.494 -0.248)
			(stroke
				(width 0.15)
				(type solid)
			)
			(layer "B.Fab")
		)
		(fp_line
			(start 0.504 0.25)
			(end 0.504 -0.248)
			(stroke
				(width 0.15)
				(type solid)
			)
			(layer "B.Fab")
		)
		(fp_text user "${REFERENCE}"
			(at -0.939 -4.599 180)
			(layer "B.Fab")
			(effects
				(font
					(size 0.7 0.7)
					(thickness 0.15)
				)
				(justify left bottom mirror)
			)
		)
		(fp_text user "Author: Antmicro"
			(at -0.939 -3.399 180)
			(layer "B.Fab")
			(effects
				(font
					(size 0.7 0.7)
					(thickness 0.15)
				)
				(justify left bottom mirror)
			)
		)
		(fp_text user "License: Apache-2.0"
			(at -0.939 -5.799 180)
			(layer "B.Fab")
			(effects
				(font
					(size 0.7 0.7)
					(thickness 0.15)
				)
				(justify left bottom mirror)
			)
		)
		(pad "1" smd roundrect
			(at -0.48 0)
			(size 0.59 0.64)
			(layers "B.Cu" "B.Mask" "B.Paste")
			(roundrect_rratio 0.25)
			(net 175 "Net-(U3-LDO_1V8D)")
			(pintype "passive")
		)
		(pad "2" smd roundrect
			(at 0.48 0)
			(size 0.59 0.64)
			(layers "B.Cu" "B.Mask" "B.Paste")
			(roundrect_rratio 0.25)
			(net 23 "GND")
			(pintype "passive")
		)
	)
	(footprint "antmicro-footprints:R_0402_1005Metric"
		(layer "B.Cu")
		(at 153.031867 83.185117)
		(descr "Resistor SMD 0402")
		(tags "resistor SMD 0402")
		(property "Reference" "R163"
			(at 20.368136 9.464883 180)
			(layer "B.SilkS")
			(effects
				(font
					(size 0.7 0.7)
					(thickness 0.15)
				)
				(justify mirror)
			)
		)
		(property "Value" "R_1k_0402"
			(at -1.011843 -1.772047 180)
			(layer "B.Fab")
			(effects
				(font
					(size 0.7 0.7)
					(thickness 0.15)
				)
				(justify left bottom mirror)
			)
		)
		(property "Datasheet" "https://www.bourns.com/docs/product-datasheets/cr.pdf"
			(at 0 0 180)
			(layer "B.Fab")
			(hide yes)
			(effects
				(font
					(size 1.27 1.27)
					(thickness 0.15)
				)
				(justify mirror)
			)
		)
		(property "Description" "SMD Chip Resistor, 1 kohm, ± 1%, 63 mW, 0402 [1005 Metric], Thick Film, General Purpose"
			(at 0 0 180)
			(layer "B.Fab")
			(hide yes)
			(effects
				(font
					(size 1.27 1.27)
					(thickness 0.15)
				)
				(justify mirror)
			)
		)
		(property "MPN" "CR0402-FX-1001GLF"
			(at 0 0 0)
			(unlocked yes)
			(layer "B.Fab")
			(hide yes)
			(effects
				(font
					(size 1 1)
					(thickness 0.15)
				)
				(justify mirror)
			)
		)
		(property "Manufacturer" "Bourns"
			(at 0 0 0)
			(unlocked yes)
			(layer "B.Fab")
			(hide yes)
			(effects
				(font
					(size 1 1)
					(thickness 0.15)
				)
				(justify mirror)
			)
		)
		(property "License" "Apache-2.0"
			(at 0 0 0)
			(unlocked yes)
			(layer "B.Fab")
			(hide yes)
			(effects
				(font
					(size 1 1)
					(thickness 0.15)
				)
				(justify mirror)
			)
		)
		(property "Author" "Antmicro"
			(at 0 0 0)
			(unlocked yes)
			(layer "B.Fab")
			(hide yes)
			(effects
				(font
					(size 1 1)
					(thickness 0.15)
				)
				(justify mirror)
			)
		)
		(property "Val" "1k"
			(at 0 0 0)
			(unlocked yes)
			(layer "B.Fab")
			(hide yes)
			(effects
				(font
					(size 1 1)
					(thickness 0.15)
				)
				(justify mirror)
			)
		)
		(property "Tolerance" "1%"
			(at 0 0 0)
			(unlocked yes)
			(layer "B.Fab")
			(hide yes)
			(effects
				(font
					(size 1 1)
					(thickness 0.15)
				)
				(justify mirror)
			)
		)
		(sheetname "/X710-AT2 Misc/")
		(sheetfile "x710-at2-mics.kicad_sch")
		(attr smd)
		(fp_rect
			(start -0.925 0.47)
			(end 0.925 -0.47)
			(stroke
				(width 0.05)
				(type default)
			)
			(fill no)
			(layer "B.CrtYd")
		)
		(fp_rect
			(start -0.5 0.25)
			(end 0.5 -0.25)
			(stroke
				(width 0.15)
				(type solid)
			)
			(fill no)
			(layer "B.Fab")
		)
		(fp_text user "${REFERENCE}"
			(at -0.95 -3.168 180)
			(layer "B.Fab")
			(effects
				(font
					(size 0.7 0.7)
					(thickness 0.15)
				)
				(justify left bottom mirror)
			)
		)
		(fp_text user "Author: Antmicro"
			(at -0.95 -4.169 180)
			(layer "B.Fab")
			(effects
				(font
					(size 0.7 0.7)
					(thickness 0.15)
				)
				(justify left bottom mirror)
			)
		)
		(fp_text user "License: Apache-2.0"
			(at -0.95 -5.169 180)
			(layer "B.Fab")
			(effects
				(font
					(size 0.7 0.7)
					(thickness 0.15)
				)
				(justify left bottom mirror)
			)
		)
		(pad "1" smd roundrect
			(at -0.48 0)
			(size 0.59 0.64)
			(layers "B.Cu" "B.Mask" "B.Paste")
			(roundrect_rratio 0.25)
			(net 23 "GND")
			(pintype "passive")
		)
		(pad "2" smd roundrect
			(at 0.48 0)
			(size 0.59 0.64)
			(layers "B.Cu" "B.Mask" "B.Paste")
			(roundrect_rratio 0.25)
			(net 88 "/X710-AT2 Misc/~{PHY_TRST}")
			(pintype "passive")
		)
	)
	(footprint "antmicro-footprints:Fiducial_1mm_Mask2mm"
		(layer "B.Cu")
		(at 175 47.5 180)
		(descr "Circular Fiducial, 1mm bare copper, 3mm soldermask opening")
		(tags "fiducial")
		(property "Reference" "FD4"
			(at -1 -2.7 0)
			(layer "B.SilkS")
			(effects
				(font
					(size 0.7 0.7)
					(thickness 0.15)
				)
				(justify left bottom mirror)
			)
		)
		(property "Value" "Fiducial_1mm_Mask2mm"
			(at 0 -2.2 0)
			(layer "B.Fab")
			(effects
				(font
					(size 0.7 0.7)
					(thickness 0.15)
				)
				(justify left bottom mirror)
			)
		)
		(property "Description" "Fiducial mask"
			(at 0 0 0)
			(layer "B.Fab")
			(hide yes)
			(effects
				(font
					(size 1.27 1.27)
					(thickness 0.15)
				)
				(justify mirror)
			)
		)
		(property "Author" "Antmicro"
			(at 0 0 180)
			(unlocked yes)
			(layer "B.Fab")
			(hide yes)
			(effects
				(font
					(size 1 1)
					(thickness 0.15)
				)
				(justify mirror)
			)
		)
		(property "License" "Apache-2.0"
			(at 0 0 180)
			(unlocked yes)
			(layer "B.Fab")
			(hide yes)
			(effects
				(font
					(size 1 1)
					(thickness 0.15)
				)
				(justify mirror)
			)
		)
		(sheetname "/")
		(sheetfile "thunderbolt-to-10gbe-adapter.kicad_sch")
		(attr exclude_from_pos_files exclude_from_bom)
		(fp_circle
			(center 0 0)
			(end 1.24 0)
			(stroke
				(width 0.05)
				(type solid)
			)
			(fill no)
			(layer "B.CrtYd")
		)
		(fp_circle
			(center 0 0)
			(end 0.999 0)
			(stroke
				(width 0.15)
				(type solid)
			)
			(fill no)
			(layer "B.Fab")
		)
		(fp_text user "${REFERENCE}"
			(at -1.25 -4.603 0)
			(layer "B.Fab")
			(effects
				(font
					(size 0.7 0.7)
					(thickness 0.15)
				)
				(justify left bottom mirror)
			)
		)
		(fp_text user "Author: Antmicro"
			(at -1.25 -5.803 0)
			(layer "B.Fab")
			(effects
				(font
					(size 0.7 0.7)
					(thickness 0.15)
				)
				(justify left bottom mirror)
			)
		)
		(fp_text user "License: Apache-2.0"
			(at -1.25 -7.003 0)
			(layer "B.Fab")
			(effects
				(font
					(size 0.7 0.7)
					(thickness 0.15)
				)
				(justify left bottom mirror)
			)
		)
		(pad "" smd circle
			(at 0 0 180)
			(size 1 1)
			(layers "B.Cu" "B.Mask")
			(solder_mask_margin 0.5)
			(clearance 0.5)
		)
	)
	(footprint "antmicro-footprints:C_Pol_EIA-B"
		(layer "B.Cu")
		(at 117.8 142 -90)
		(property "Reference" "C6"
			(at -0.75 -2.7 90)
			(layer "B.SilkS")
			(effects
				(font
					(size 0.7 0.7)
					(thickness 0.15)
				)
				(justify left bottom mirror)
			)
		)
		(property "Value" "C_Pol_330u_6.3V_KEMET-T520-B"
			(at 0 -2.85 90)
			(layer "B.Fab")
			(effects
				(font
					(size 0.7 0.7)
					(thickness 0.15)
				)
				(justify left bottom mirror)
			)
		)
		(property "Datasheet" "https://www.kemet.com/en/us/capacitors/product/T520B337M006ATE040.html"
			(at 0 0 90)
			(layer "B.Fab")
			(hide yes)
			(effects
				(font
					(size 1.27 1.27)
					(thickness 0.15)
				)
				(justify mirror)
			)
		)
		(property "Description" "Tantalum Polymer Capacitor, KO-CAP®, 330 µF, ± 20%, 6.3 V, B, 0.04 ohm, 1411 [3528 Metric]"
			(at 0 0 90)
			(layer "B.Fab")
			(hide yes)
			(effects
				(font
					(size 1.27 1.27)
					(thickness 0.15)
				)
				(justify mirror)
			)
		)
		(property "Val" "330u"
			(at 0 0 270)
			(unlocked yes)
			(layer "B.Fab")
			(hide yes)
			(effects
				(font
					(size 1 1)
					(thickness 0.15)
				)
				(justify mirror)
			)
		)
		(property "MPN" "T520B337M006ATE040"
			(at 0 0 270)
			(unlocked yes)
			(layer "B.Fab")
			(hide yes)
			(effects
				(font
					(size 1 1)
					(thickness 0.15)
				)
				(justify mirror)
			)
		)
		(property "Manufacturer" "KEMET"
			(at 0 0 270)
			(unlocked yes)
			(layer "B.Fab")
			(hide yes)
			(effects
				(font
					(size 1 1)
					(thickness 0.15)
				)
				(justify mirror)
			)
		)
		(property "License" "Apache-2.0"
			(at 0 0 270)
			(unlocked yes)
			(layer "B.Fab")
			(hide yes)
			(effects
				(font
					(size 1 1)
					(thickness 0.15)
				)
				(justify mirror)
			)
		)
		(property "Author" "Antmicro"
			(at 0 0 270)
			(unlocked yes)
			(layer "B.Fab")
			(hide yes)
			(effects
				(font
					(size 1 1)
					(thickness 0.15)
				)
				(justify mirror)
			)
		)
		(property "Voltage" "6.3V"
			(at 0 0 270)
			(unlocked yes)
			(layer "B.Fab")
			(hide yes)
			(effects
				(font
					(size 1 1)
					(thickness 0.15)
				)
				(justify mirror)
			)
		)
		(property "Dielectric" "template_dielectric"
			(at 0 0 270)
			(unlocked yes)
			(layer "B.Fab")
			(hide yes)
			(effects
				(font
					(size 1 1)
					(thickness 0.15)
				)
				(justify mirror)
			)
		)
		(sheetname "/USB-C connector/")
		(sheetfile "USB-C_connector.kicad_sch")
		(attr smd dnp)
		(fp_line
			(start -2.521 1.676)
			(end -2.123 1.676)
			(stroke
				(width 0.15)
				(type solid)
			)
			(layer "B.SilkS")
		)
		(fp_line
			(start -1.8 1.6)
			(end 1.8 1.6)
			(stroke
				(width 0.15)
				(type solid)
			)
			(layer "B.SilkS")
		)
		(fp_line
			(start -2.325 1.475)
			(end -2.325 1.878)
			(stroke
				(width 0.15)
				(type solid)
			)
			(layer "B.SilkS")
		)
		(fp_line
			(start -1.8 1.3)
			(end -1.8 1.6)
			(stroke
				(width 0.15)
				(type solid)
			)
			(layer "B.SilkS")
		)
		(fp_line
			(start 1.8 1.3)
			(end 1.8 1.6)
			(stroke
				(width 0.15)
				(type solid)
			)
			(layer "B.SilkS")
		)
		(fp_line
			(start -1.8 -1.3)
			(end -1.8 -1.6)
			(stroke
				(width 0.15)
				(type solid)
			)
			(layer "B.SilkS")
		)
		(fp_line
			(start 1.8 -1.3)
			(end 1.8 -1.6)
			(stroke
				(width 0.15)
				(type solid)
			)
			(layer "B.SilkS")
		)
		(fp_line
			(start 1.8 -1.6)
			(end -1.8 -1.6)
			(stroke
				(width 0.15)
				(type solid)
			)
			(layer "B.SilkS")
		)
		(fp_line
			(start -1.97 1.75)
			(end -1.97 1.35)
			(stroke
				(width 0.05)
				(type solid)
			)
			(layer "B.CrtYd")
		)
		(fp_line
			(start 1.959 1.75)
			(end -1.97 1.75)
			(stroke
				(width 0.05)
				(type solid)
			)
			(layer "B.CrtYd")
		)
		(fp_line
			(start 1.959 1.75)
			(end 1.959 1.35)
			(stroke
				(width 0.05)
				(type solid)
			)
			(layer "B.CrtYd")
		)
		(fp_line
			(start -2.411 1.35)
			(end -2.41 -1.35)
			(stroke
				(width 0.05)
				(type solid)
			)
			(layer "B.CrtYd")
		)
		(fp_line
			(start -1.97 1.35)
			(end -2.41 1.35)
			(stroke
				(width 0.05)
				(type solid)
			)
			(layer "B.CrtYd")
		)
		(fp_line
			(start 2.399 1.35)
			(end 1.959 1.35)
			(stroke
				(width 0.05)
				(type solid)
			)
			(layer "B.CrtYd")
		)
		(fp_line
			(start 2.399 1.35)
			(end 2.4 -1.35)
			(stroke
				(width 0.05)
				(type solid)
			)
			(layer "B.CrtYd")
		)
		(fp_line
			(start -1.97 -1.35)
			(end -2.41 -1.35)
			(stroke
				(width 0.05)
				(type solid)
			)
			(layer "B.CrtYd")
		)
		(fp_line
			(start -1.97 -1.35)
			(end -1.97 -1.75)
			(stroke
				(width 0.05)
				(type solid)
			)
			(layer "B.CrtYd")
		)
		(fp_line
			(start 1.96 -1.35)
			(end 1.96 -1.75)
			(stroke
				(width 0.05)
				(type solid)
			)
			(layer "B.CrtYd")
		)
		(fp_line
			(start 2.4 -1.35)
			(end 1.96 -1.35)
			(stroke
				(width 0.05)
				(type solid)
			)
			(layer "B.CrtYd")
		)
		(fp_line
			(start 1.96 -1.75)
			(end -1.97 -1.75)
			(stroke
				(width 0.05)
				(type solid)
			)
			(layer "B.CrtYd")
		)
		(fp_line
			(start -1.7 -1.324)
			(end -1.551 -1.475)
			(stroke
				(width 0.15)
				(type solid)
			)
			(layer "B.Fab")
		)
		(fp_rect
			(start -1.72 1.5)
			(end 1.719 -1.499)
			(stroke
				(width 0.15)
				(type solid)
			)
			(fill no)
			(layer "B.Fab")
		)
		(fp_text user "License: Apache-2.0"
			(at -2.665 -5.65 90)
			(layer "B.Fab")
			(effects
				(font
					(size 0.7 0.7)
					(thickness 0.15)
				)
				(justify left bottom mirror)
			)
		)
		(fp_text user "Author: Antmicro"
			(at -2.665 -6.85 90)
			(layer "B.Fab")
			(effects
				(font
					(size 0.7 0.7)
					(thickness 0.15)
				)
				(justify left bottom mirror)
			)
		)
		(fp_text user "${REFERENCE}"
			(at -2.665 -4.45 90)
			(layer "B.Fab")
			(effects
				(font
					(size 0.7 0.7)
					(thickness 0.15)
				)
				(justify left bottom mirror)
			)
		)
		(pad "1" smd roundrect
			(at -1.551 0 270)
			(size 1.2 2.2)
			(layers "B.Cu" "B.Mask" "B.Paste")
			(roundrect_rratio 0.1)
			(net 53 "+5V_USB")
			(pintype "passive")
		)
		(pad "2" smd roundrect
			(at 1.55 0 270)
			(size 1.2 2.2)
			(layers "B.Cu" "B.Mask" "B.Paste")
			(roundrect_rratio 0.1)
			(net 23 "GND")
			(pintype "passive")
		)
	)
	(footprint "antmicro-footprints:C_0402_1005Metric"
		(layer "B.Cu")
		(at 149.331866 80.260117 180)
		(descr "Capacitor SMD 0402")
		(tags "capacitor SMD 0402")
		(property "Reference" "C260"
			(at -19.468135 -9.464883 0)
			(layer "B.SilkS")
			(effects
				(font
					(size 0.7 0.7)
					(thickness 0.15)
				)
				(justify mirror)
			)
		)
		(property "Value" "C_1u_25V_0402"
			(at -1.022927 -2.155213 0)
			(layer "B.Fab")
			(effects
				(font
					(size 0.7 0.7)
					(thickness 0.15)
				)
				(justify left bottom mirror)
			)
		)
		(property "Datasheet" "https://www.murata.com/products/productdetail?partno=GRM155R61E105KE11%23"
			(at 0 0 0)
			(layer "B.Fab")
			(hide yes)
			(effects
				(font
					(size 1.27 1.27)
					(thickness 0.15)
				)
				(justify mirror)
			)
		)
		(property "Description" "SMD Multilayer Ceramic Capacitor, 1 µF, 25 V, 0402 [1005 Metric], ± 10%, X5R, GRM Series"
			(at 0 0 0)
			(layer "B.Fab")
			(hide yes)
			(effects
				(font
					(size 1.27 1.27)
					(thickness 0.15)
				)
				(justify mirror)
			)
		)
		(property "MPN" "GRM155R61E105KE11J"
			(at 0 0 180)
			(unlocked yes)
			(layer "B.Fab")
			(hide yes)
			(effects
				(font
					(size 1 1)
					(thickness 0.15)
				)
				(justify mirror)
			)
		)
		(property "Manufacturer" "Murata"
			(at 0 0 180)
			(unlocked yes)
			(layer "B.Fab")
			(hide yes)
			(effects
				(font
					(size 1 1)
					(thickness 0.15)
				)
				(justify mirror)
			)
		)
		(property "License" "Apache-2.0"
			(at 0 0 180)
			(unlocked yes)
			(layer "B.Fab")
			(hide yes)
			(effects
				(font
					(size 1 1)
					(thickness 0.15)
				)
				(justify mirror)
			)
		)
		(property "Author" "Antmicro"
			(at 0 0 180)
			(unlocked yes)
			(layer "B.Fab")
			(hide yes)
			(effects
				(font
					(size 1 1)
					(thickness 0.15)
				)
				(justify mirror)
			)
		)
		(property "Val" "1u"
			(at 0 0 180)
			(unlocked yes)
			(layer "B.Fab")
			(hide yes)
			(effects
				(font
					(size 1 1)
					(thickness 0.15)
				)
				(justify mirror)
			)
		)
		(property "Voltage" "25V"
			(at 0 0 180)
			(unlocked yes)
			(layer "B.Fab")
			(hide yes)
			(effects
				(font
					(size 1 1)
					(thickness 0.15)
				)
				(justify mirror)
			)
		)
		(property "Dielectric" "X5R"
			(at 0 0 180)
			(unlocked yes)
			(layer "B.Fab")
			(hide yes)
			(effects
				(font
					(size 1 1)
					(thickness 0.15)
				)
				(justify mirror)
			)
		)
		(sheetname "/X710-AT2 power/")
		(sheetfile "x710-at2-power.kicad_sch")
		(attr smd)
		(fp_rect
			(start -0.925 0.47)
			(end 0.925 -0.47)
			(stroke
				(width 0.05)
				(type default)
			)
			(fill no)
			(layer "B.CrtYd")
		)
		(fp_line
			(start 0.504 0.25)
			(end 0.504 -0.248)
			(stroke
				(width 0.15)
				(type solid)
			)
			(layer "B.Fab")
		)
		(fp_line
			(start 0.504 -0.248)
			(end -0.494 -0.248)
			(stroke
				(width 0.15)
				(type solid)
			)
			(layer "B.Fab")
		)
		(fp_line
			(start -0.494 0.25)
			(end 0.504 0.25)
			(stroke
				(width 0.15)
				(type solid)
			)
			(layer "B.Fab")
		)
		(fp_line
			(start -0.494 -0.248)
			(end -0.494 0.25)
			(stroke
				(width 0.15)
				(type solid)
			)
			(layer "B.Fab")
		)
		(fp_text user "${REFERENCE}"
			(at -0.939 -4.599 0)
			(layer "B.Fab")
			(effects
				(font
					(size 0.7 0.7)
					(thickness 0.15)
				)
				(justify left bottom mirror)
			)
		)
		(fp_text user "License: Apache-2.0"
			(at -0.939 -5.799 0)
			(layer "B.Fab")
			(effects
				(font
					(size 0.7 0.7)
					(thickness 0.15)
				)
				(justify left bottom mirror)
			)
		)
		(fp_text user "Author: Antmicro"
			(at -0.939 -3.399 0)
			(layer "B.Fab")
			(effects
				(font
					(size 0.7 0.7)
					(thickness 0.15)
				)
				(justify left bottom mirror)
			)
		)
		(pad "1" smd roundrect
			(at -0.48 0 180)
			(size 0.59 0.64)
			(layers "B.Cu" "B.Mask" "B.Paste")
			(roundrect_rratio 0.25)
			(net 23 "GND")
			(pintype "passive")
		)
		(pad "2" smd roundrect
			(at 0.48 0 180)
			(size 0.59 0.64)
			(layers "B.Cu" "B.Mask" "B.Paste")
			(roundrect_rratio 0.25)
			(net 9 "VCCD")
			(pintype "passive")
		)
	)
	(footprint "antmicro-footprints:R_0402_1005Metric"
		(layer "B.Cu")
		(at 117.5 91.7 -90)
		(descr "Resistor SMD 0402")
		(tags "resistor SMD 0402")
		(property "Reference" "R72"
			(at 6.3 -0.3 90)
			(layer "B.SilkS")
			(effects
				(font
					(size 0.7 0.7)
					(thickness 0.15)
				)
				(justify left bottom mirror)
			)
		)
		(property "Value" "R_1k_0402"
			(at -1.011843 -1.772047 90)
			(layer "B.Fab")
			(effects
				(font
					(size 0.7 0.7)
					(thickness 0.15)
				)
				(justify left bottom mirror)
			)
		)
		(property "Datasheet" "https://www.bourns.com/docs/product-datasheets/cr.pdf"
			(at 0 0 90)
			(layer "B.Fab")
			(hide yes)
			(effects
				(font
					(size 1.27 1.27)
					(thickness 0.15)
				)
				(justify mirror)
			)
		)
		(property "Description" "SMD Chip Resistor, 1 kohm, ± 1%, 63 mW, 0402 [1005 Metric], Thick Film, General Purpose"
			(at 0 0 90)
			(layer "B.Fab")
			(hide yes)
			(effects
				(font
					(size 1.27 1.27)
					(thickness 0.15)
				)
				(justify mirror)
			)
		)
		(property "MPN" "CR0402-FX-1001GLF"
			(at 0 0 270)
			(unlocked yes)
			(layer "B.Fab")
			(hide yes)
			(effects
				(font
					(size 1 1)
					(thickness 0.15)
				)
				(justify mirror)
			)
		)
		(property "Manufacturer" "Bourns"
			(at 0 0 270)
			(unlocked yes)
			(layer "B.Fab")
			(hide yes)
			(effects
				(font
					(size 1 1)
					(thickness 0.15)
				)
				(justify mirror)
			)
		)
		(property "License" "Apache-2.0"
			(at 0 0 270)
			(unlocked yes)
			(layer "B.Fab")
			(hide yes)
			(effects
				(font
					(size 1 1)
					(thickness 0.15)
				)
				(justify mirror)
			)
		)
		(property "Val" "1k"
			(at 0 0 270)
			(unlocked yes)
			(layer "B.Fab")
			(hide yes)
			(effects
				(font
					(size 1 1)
					(thickness 0.15)
				)
				(justify mirror)
			)
		)
		(property "Tolerance" "1%"
			(at 0 0 270)
			(unlocked yes)
			(layer "B.Fab")
			(hide yes)
			(effects
				(font
					(size 1 1)
					(thickness 0.15)
				)
				(justify mirror)
			)
		)
		(property "Author" "Antmicro"
			(at 0 0 270)
			(unlocked yes)
			(layer "B.Fab")
			(hide yes)
			(effects
				(font
					(size 1 1)
					(thickness 0.15)
				)
				(justify mirror)
			)
		)
		(sheetname "/TB Controller - Power/")
		(sheetfile "tb-power.kicad_sch")
		(attr smd)
		(fp_rect
			(start -0.925 0.47)
			(end 0.925 -0.47)
			(stroke
				(width 0.05)
				(type default)
			)
			(fill no)
			(layer "B.CrtYd")
		)
		(fp_rect
			(start -0.5 0.25)
			(end 0.5 -0.25)
			(stroke
				(width 0.15)
				(type solid)
			)
			(fill no)
			(layer "B.Fab")
		)
		(fp_text user "Author: Antmicro"
			(at -0.95 -4.169 90)
			(layer "B.Fab")
			(effects
				(font
					(size 0.7 0.7)
					(thickness 0.15)
				)
				(justify left bottom mirror)
			)
		)
		(fp_text user "License: Apache-2.0"
			(at -0.95 -5.169 90)
			(layer "B.Fab")
			(effects
				(font
					(size 0.7 0.7)
					(thickness 0.15)
				)
				(justify left bottom mirror)
			)
		)
		(fp_text user "${REFERENCE}"
			(at -0.95 -3.168 90)
			(layer "B.Fab")
			(effects
				(font
					(size 0.7 0.7)
					(thickness 0.15)
				)
				(justify left bottom mirror)
			)
		)
		(pad "1" smd roundrect
			(at -0.48 0 270)
			(size 0.59 0.64)
			(layers "B.Cu" "B.Mask" "B.Paste")
			(roundrect_rratio 0.25)
			(net 356 "/TB Controller - Power/0P9_BUFFERED")
			(pintype "passive")
		)
		(pad "2" smd roundrect
			(at 0.48 0 270)
			(size 0.59 0.64)
			(layers "B.Cu" "B.Mask" "B.Paste")
			(roundrect_rratio 0.25)
			(net 196 "Net-(Q1-B)")
			(pintype "passive")
		)
	)
	(footprint "antmicro-footprints:R_0402_1005Metric"
		(layer "B.Cu")
		(at 147.681866 92.485117 -90)
		(descr "Resistor SMD 0402")
		(tags "resistor SMD 0402")
		(property "Reference" "R150"
			(at 10.814884 -18.718134 90)
			(layer "B.SilkS")
			(effects
				(font
					(size 0.7 0.7)
					(thickness 0.15)
				)
				(justify mirror)
			)
		)
		(property "Value" "R_10k_0402"
			(at -1.011843 -1.772047 90)
			(layer "B.Fab")
			(effects
				(font
					(size 0.7 0.7)
					(thickness 0.15)
				)
				(justify left bottom mirror)
			)
		)
		(property "Datasheet" "https://www.bourns.com/docs/product-datasheets/cr.pdf"
			(at 0 0 90)
			(layer "B.Fab")
			(hide yes)
			(effects
				(font
					(size 1.27 1.27)
					(thickness 0.15)
				)
				(justify mirror)
			)
		)
		(property "Description" "SMD Chip Resistor, 10 kohm, ± 1%, 62.5 mW, 0402 [1005 Metric], Thick Film, General Purpose"
			(at 0 0 90)
			(layer "B.Fab")
			(hide yes)
			(effects
				(font
					(size 1.27 1.27)
					(thickness 0.15)
				)
				(justify mirror)
			)
		)
		(property "MPN" "CR0402-FX-1002GLF"
			(at 0 0 270)
			(unlocked yes)
			(layer "B.Fab")
			(hide yes)
			(effects
				(font
					(size 1 1)
					(thickness 0.15)
				)
				(justify mirror)
			)
		)
		(property "Manufacturer" "Bourns"
			(at 0 0 270)
			(unlocked yes)
			(layer "B.Fab")
			(hide yes)
			(effects
				(font
					(size 1 1)
					(thickness 0.15)
				)
				(justify mirror)
			)
		)
		(property "License" "Apache-2.0"
			(at 0 0 270)
			(unlocked yes)
			(layer "B.Fab")
			(hide yes)
			(effects
				(font
					(size 1 1)
					(thickness 0.15)
				)
				(justify mirror)
			)
		)
		(property "Author" "Antmicro"
			(at 0 0 270)
			(unlocked yes)
			(layer "B.Fab")
			(hide yes)
			(effects
				(font
					(size 1 1)
					(thickness 0.15)
				)
				(justify mirror)
			)
		)
		(property "Val" "10k"
			(at 0 0 270)
			(unlocked yes)
			(layer "B.Fab")
			(hide yes)
			(effects
				(font
					(size 1 1)
					(thickness 0.15)
				)
				(justify mirror)
			)
		)
		(property "Tolerance" "1%"
			(at 0 0 270)
			(unlocked yes)
			(layer "B.Fab")
			(hide yes)
			(effects
				(font
					(size 1 1)
					(thickness 0.15)
				)
				(justify mirror)
			)
		)
		(sheetname "/X710-AT2 Misc/")
		(sheetfile "x710-at2-mics.kicad_sch")
		(attr smd dnp)
		(fp_rect
			(start -0.925 0.47)
			(end 0.925 -0.47)
			(stroke
				(width 0.05)
				(type default)
			)
			(fill no)
			(layer "B.CrtYd")
		)
		(fp_rect
			(start -0.5 0.25)
			(end 0.5 -0.25)
			(stroke
				(width 0.15)
				(type solid)
			)
			(fill no)
			(layer "B.Fab")
		)
		(fp_text user "Author: Antmicro"
			(at -0.95 -4.169 90)
			(layer "B.Fab")
			(effects
				(font
					(size 0.7 0.7)
					(thickness 0.15)
				)
				(justify left bottom mirror)
			)
		)
		(fp_text user "${REFERENCE}"
			(at -0.95 -3.168 90)
			(layer "B.Fab")
			(effects
				(font
					(size 0.7 0.7)
					(thickness 0.15)
				)
				(justify left bottom mirror)
			)
		)
		(fp_text user "License: Apache-2.0"
			(at -0.95 -5.169 90)
			(layer "B.Fab")
			(effects
				(font
					(size 0.7 0.7)
					(thickness 0.15)
				)
				(justify left bottom mirror)
			)
		)
		(pad "1" smd roundrect
			(at -0.48 0 270)
			(size 0.59 0.64)
			(layers "B.Cu" "B.Mask" "B.Paste")
			(roundrect_rratio 0.25)
			(net 35 "/X710-AT2 Misc/POR_BYPASS")
			(pintype "passive")
		)
		(pad "2" smd roundrect
			(at 0.48 0 270)
			(size 0.59 0.64)
			(layers "B.Cu" "B.Mask" "B.Paste")
			(roundrect_rratio 0.25)
			(net 7 "+3V3")
			(pintype "passive")
		)
	)
	(footprint "antmicro-footprints:R_0402_1005Metric"
		(layer "B.Cu")
		(at 180.82 76)
		(descr "Resistor SMD 0402")
		(tags "resistor SMD 0402")
		(property "Reference" "R96"
			(at 3 0.4 180)
			(layer "B.SilkS")
			(effects
				(font
					(size 0.7 0.7)
					(thickness 0.15)
				)
				(justify left bottom mirror)
			)
		)
		(property "Value" "R_330R_0402"
			(at -1.011843 -1.772047 180)
			(layer "B.Fab")
			(effects
				(font
					(size 0.7 0.7)
					(thickness 0.15)
				)
				(justify left bottom mirror)
			)
		)
		(property "Datasheet" "https://www.bourns.com/docs/product-datasheets/cr.pdf"
			(at 0 0 180)
			(layer "B.Fab")
			(hide yes)
			(effects
				(font
					(size 1.27 1.27)
					(thickness 0.15)
				)
				(justify mirror)
			)
		)
		(property "Description" "SMD Chip Resistor, 330 ohm, ± 1%, 62.5 mW, 0402 [1005 Metric], Thick Film, General Purpose"
			(at 0 0 180)
			(layer "B.Fab")
			(hide yes)
			(effects
				(font
					(size 1.27 1.27)
					(thickness 0.15)
				)
				(justify mirror)
			)
		)
		(property "MPN" "CR0402-FX-3300GLF"
			(at 0 0 0)
			(unlocked yes)
			(layer "B.Fab")
			(hide yes)
			(effects
				(font
					(size 1 1)
					(thickness 0.15)
				)
				(justify mirror)
			)
		)
		(property "Manufacturer" "Bourns"
			(at 0 0 0)
			(unlocked yes)
			(layer "B.Fab")
			(hide yes)
			(effects
				(font
					(size 1 1)
					(thickness 0.15)
				)
				(justify mirror)
			)
		)
		(property "License" "Apache-2.0"
			(at 0 0 0)
			(unlocked yes)
			(layer "B.Fab")
			(hide yes)
			(effects
				(font
					(size 1 1)
					(thickness 0.15)
				)
				(justify mirror)
			)
		)
		(property "Author" "Antmicro"
			(at 0 0 0)
			(unlocked yes)
			(layer "B.Fab")
			(hide yes)
			(effects
				(font
					(size 1 1)
					(thickness 0.15)
				)
				(justify mirror)
			)
		)
		(property "Val" "330R"
			(at 0 0 0)
			(unlocked yes)
			(layer "B.Fab")
			(hide yes)
			(effects
				(font
					(size 1 1)
					(thickness 0.15)
				)
				(justify mirror)
			)
		)
		(property "Tolerance" "1%"
			(at 0 0 0)
			(unlocked yes)
			(layer "B.Fab")
			(hide yes)
			(effects
				(font
					(size 1 1)
					(thickness 0.15)
				)
				(justify mirror)
			)
		)
		(sheetname "/X710 DCDC converters/")
		(sheetfile "DCDC_converters_X710.kicad_sch")
		(attr smd)
		(fp_rect
			(start -0.925 0.47)
			(end 0.925 -0.47)
			(stroke
				(width 0.05)
				(type default)
			)
			(fill no)
			(layer "B.CrtYd")
		)
		(fp_rect
			(start -0.5 0.25)
			(end 0.5 -0.25)
			(stroke
				(width 0.15)
				(type solid)
			)
			(fill no)
			(layer "B.Fab")
		)
		(fp_text user "License: Apache-2.0"
			(at -0.95 -5.169 180)
			(layer "B.Fab")
			(effects
				(font
					(size 0.7 0.7)
					(thickness 0.15)
				)
				(justify left bottom mirror)
			)
		)
		(fp_text user "${REFERENCE}"
			(at -0.95 -3.168 180)
			(layer "B.Fab")
			(effects
				(font
					(size 0.7 0.7)
					(thickness 0.15)
				)
				(justify left bottom mirror)
			)
		)
		(fp_text user "Author: Antmicro"
			(at -0.95 -4.169 180)
			(layer "B.Fab")
			(effects
				(font
					(size 0.7 0.7)
					(thickness 0.15)
				)
				(justify left bottom mirror)
			)
		)
		(pad "1" smd roundrect
			(at -0.48 0)
			(size 0.59 0.64)
			(layers "B.Cu" "B.Mask" "B.Paste")
			(roundrect_rratio 0.25)
			(net 431 "Net-(Q5-C)")
			(pintype "passive")
		)
		(pad "2" smd roundrect
			(at 0.48 0)
			(size 0.59 0.64)
			(layers "B.Cu" "B.Mask" "B.Paste")
			(roundrect_rratio 0.25)
			(net 417 "Net-(D10-C)")
			(pintype "passive")
		)
	)
	(footprint "antmicro-footprints:C_0402_1005Metric"
		(layer "B.Cu")
		(at 129.474999 125.9 90)
		(descr "Capacitor SMD 0402")
		(tags "capacitor SMD 0402")
		(property "Reference" "C79"
			(at 7.700002 21.900002 270)
			(layer "B.SilkS")
			(effects
				(font
					(size 0.7 0.7)
					(thickness 0.15)
				)
				(justify mirror)
			)
		)
		(property "Value" "C_1u_0402"
			(at -1.022927 -2.155213 270)
			(layer "B.Fab")
			(effects
				(font
					(size 0.7 0.7)
					(thickness 0.15)
				)
				(justify left bottom mirror)
			)
		)
		(property "Datasheet" "https://product.tdk.com/en/search/capacitor/ceramic/mlcc/info?part_no=C1005X6S1A105K050BC"
			(at 0 0 270)
			(layer "B.Fab")
			(hide yes)
			(effects
				(font
					(size 1.27 1.27)
					(thickness 0.15)
				)
				(justify mirror)
			)
		)
		(property "Description" "SMD Multilayer Ceramic Capacitor, 1 µF, 10 V, 0402 [1005 Metric], ± 10%, X6S, C"
			(at 0 0 270)
			(layer "B.Fab")
			(hide yes)
			(effects
				(font
					(size 1.27 1.27)
					(thickness 0.15)
				)
				(justify mirror)
			)
		)
		(property "MPN" "C1005X6S1A105K050BC"
			(at 0 0 90)
			(unlocked yes)
			(layer "B.Fab")
			(hide yes)
			(effects
				(font
					(size 1 1)
					(thickness 0.15)
				)
				(justify mirror)
			)
		)
		(property "Manufacturer" "TDK"
			(at 0 0 90)
			(unlocked yes)
			(layer "B.Fab")
			(hide yes)
			(effects
				(font
					(size 1 1)
					(thickness 0.15)
				)
				(justify mirror)
			)
		)
		(property "License" "Apache-2.0"
			(at 0 0 90)
			(unlocked yes)
			(layer "B.Fab")
			(hide yes)
			(effects
				(font
					(size 1 1)
					(thickness 0.15)
				)
				(justify mirror)
			)
		)
		(property "Val" "1u"
			(at 0 0 90)
			(unlocked yes)
			(layer "B.Fab")
			(hide yes)
			(effects
				(font
					(size 1 1)
					(thickness 0.15)
				)
				(justify mirror)
			)
		)
		(property "Voltage" ""
			(at 0 0 90)
			(unlocked yes)
			(layer "B.Fab")
			(hide yes)
			(effects
				(font
					(size 1 1)
					(thickness 0.15)
				)
				(justify mirror)
			)
		)
		(property "Dielectric" ""
			(at 0 0 90)
			(unlocked yes)
			(layer "B.Fab")
			(hide yes)
			(effects
				(font
					(size 1 1)
					(thickness 0.15)
				)
				(justify mirror)
			)
		)
		(property "Author" "Antmicro"
			(at 0 0 90)
			(unlocked yes)
			(layer "B.Fab")
			(hide yes)
			(effects
				(font
					(size 1 1)
					(thickness 0.15)
				)
				(justify mirror)
			)
		)
		(sheetname "/TB Controller - Power/")
		(sheetfile "tb-power.kicad_sch")
		(attr smd)
		(fp_rect
			(start -0.925 0.47)
			(end 0.925 -0.47)
			(stroke
				(width 0.05)
				(type default)
			)
			(fill no)
			(layer "B.CrtYd")
		)
		(fp_line
			(start 0.504 -0.248)
			(end -0.494 -0.248)
			(stroke
				(width 0.15)
				(type solid)
			)
			(layer "B.Fab")
		)
		(fp_line
			(start -0.494 -0.248)
			(end -0.494 0.25)
			(stroke
				(width 0.15)
				(type solid)
			)
			(layer "B.Fab")
		)
		(fp_line
			(start 0.504 0.25)
			(end 0.504 -0.248)
			(stroke
				(width 0.15)
				(type solid)
			)
			(layer "B.Fab")
		)
		(fp_line
			(start -0.494 0.25)
			(end 0.504 0.25)
			(stroke
				(width 0.15)
				(type solid)
			)
			(layer "B.Fab")
		)
		(fp_text user "License: Apache-2.0"
			(at -0.939 -5.799 270)
			(layer "B.Fab")
			(effects
				(font
					(size 0.7 0.7)
					(thickness 0.15)
				)
				(justify left bottom mirror)
			)
		)
		(fp_text user "Author: Antmicro"
			(at -0.939 -3.399 270)
			(layer "B.Fab")
			(effects
				(font
					(size 0.7 0.7)
					(thickness 0.15)
				)
				(justify left bottom mirror)
			)
		)
		(fp_text user "${REFERENCE}"
			(at -0.939 -4.599 270)
			(layer "B.Fab")
			(effects
				(font
					(size 0.7 0.7)
					(thickness 0.15)
				)
				(justify left bottom mirror)
			)
		)
		(pad "1" smd roundrect
			(at -0.48 0 90)
			(size 0.59 0.64)
			(layers "B.Cu" "B.Mask" "B.Paste")
			(roundrect_rratio 0.25)
			(net 23 "GND")
			(pintype "passive")
		)
		(pad "2" smd roundrect
			(at 0.48 0 90)
			(size 0.59 0.64)
			(layers "B.Cu" "B.Mask" "B.Paste")
			(roundrect_rratio 0.25)
			(net 68 "/TB Controller - Power/VCC_0P9")
			(pintype "passive")
		)
	)
	(footprint "antmicro-footprints:C_0402_1005Metric"
		(layer "B.Cu")
		(at 154.261866 84.265117 180)
		(descr "Capacitor SMD 0402")
		(tags "capacitor SMD 0402")
		(property "Reference" "C189"
			(at -18.538135 -9.464883 0)
			(layer "B.SilkS")
			(effects
				(font
					(size 0.7 0.7)
					(thickness 0.15)
				)
				(justify mirror)
			)
		)
		(property "Value" "C_1u_25V_0402"
			(at -1.022927 -2.155213 0)
			(layer "B.Fab")
			(effects
				(font
					(size 0.7 0.7)
					(thickness 0.15)
				)
				(justify left bottom mirror)
			)
		)
		(property "Datasheet" "https://www.murata.com/products/productdetail?partno=GRM155R61E105KE11%23"
			(at 0 0 0)
			(layer "B.Fab")
			(hide yes)
			(effects
				(font
					(size 1.27 1.27)
					(thickness 0.15)
				)
				(justify mirror)
			)
		)
		(property "Description" "SMD Multilayer Ceramic Capacitor, 1 µF, 25 V, 0402 [1005 Metric], ± 10%, X5R, GRM Series"
			(at 0 0 0)
			(layer "B.Fab")
			(hide yes)
			(effects
				(font
					(size 1.27 1.27)
					(thickness 0.15)
				)
				(justify mirror)
			)
		)
		(property "MPN" "GRM155R61E105KE11J"
			(at 0 0 180)
			(unlocked yes)
			(layer "B.Fab")
			(hide yes)
			(effects
				(font
					(size 1 1)
					(thickness 0.15)
				)
				(justify mirror)
			)
		)
		(property "Manufacturer" "Murata"
			(at 0 0 180)
			(unlocked yes)
			(layer "B.Fab")
			(hide yes)
			(effects
				(font
					(size 1 1)
					(thickness 0.15)
				)
				(justify mirror)
			)
		)
		(property "License" "Apache-2.0"
			(at 0 0 180)
			(unlocked yes)
			(layer "B.Fab")
			(hide yes)
			(effects
				(font
					(size 1 1)
					(thickness 0.15)
				)
				(justify mirror)
			)
		)
		(property "Author" "Antmicro"
			(at 0 0 180)
			(unlocked yes)
			(layer "B.Fab")
			(hide yes)
			(effects
				(font
					(size 1 1)
					(thickness 0.15)
				)
				(justify mirror)
			)
		)
		(property "Val" "1u"
			(at 0 0 180)
			(unlocked yes)
			(layer "B.Fab")
			(hide yes)
			(effects
				(font
					(size 1 1)
					(thickness 0.15)
				)
				(justify mirror)
			)
		)
		(property "Voltage" "25V"
			(at 0 0 180)
			(unlocked yes)
			(layer "B.Fab")
			(hide yes)
			(effects
				(font
					(size 1 1)
					(thickness 0.15)
				)
				(justify mirror)
			)
		)
		(property "Dielectric" "X5R"
			(at 0 0 180)
			(unlocked yes)
			(layer "B.Fab")
			(hide yes)
			(effects
				(font
					(size 1 1)
					(thickness 0.15)
				)
				(justify mirror)
			)
		)
		(sheetname "/X710-AT2 power/")
		(sheetfile "x710-at2-power.kicad_sch")
		(attr smd)
		(fp_rect
			(start -0.925 0.47)
			(end 0.925 -0.47)
			(stroke
				(width 0.05)
				(type default)
			)
			(fill no)
			(layer "B.CrtYd")
		)
		(fp_line
			(start 0.504 0.25)
			(end 0.504 -0.248)
			(stroke
				(width 0.15)
				(type solid)
			)
			(layer "B.Fab")
		)
		(fp_line
			(start 0.504 -0.248)
			(end -0.494 -0.248)
			(stroke
				(width 0.15)
				(type solid)
			)
			(layer "B.Fab")
		)
		(fp_line
			(start -0.494 0.25)
			(end 0.504 0.25)
			(stroke
				(width 0.15)
				(type solid)
			)
			(layer "B.Fab")
		)
		(fp_line
			(start -0.494 -0.248)
			(end -0.494 0.25)
			(stroke
				(width 0.15)
				(type solid)
			)
			(layer "B.Fab")
		)
		(fp_text user "License: Apache-2.0"
			(at -0.939 -5.799 0)
			(layer "B.Fab")
			(effects
				(font
					(size 0.7 0.7)
					(thickness 0.15)
				)
				(justify left bottom mirror)
			)
		)
		(fp_text user "Author: Antmicro"
			(at -0.939 -3.399 0)
			(layer "B.Fab")
			(effects
				(font
					(size 0.7 0.7)
					(thickness 0.15)
				)
				(justify left bottom mirror)
			)
		)
		(fp_text user "${REFERENCE}"
			(at -0.939 -4.599 0)
			(layer "B.Fab")
			(effects
				(font
					(size 0.7 0.7)
					(thickness 0.15)
				)
				(justify left bottom mirror)
			)
		)
		(pad "1" smd roundrect
			(at -0.48 0 180)
			(size 0.59 0.64)
			(layers "B.Cu" "B.Mask" "B.Paste")
			(roundrect_rratio 0.25)
			(net 23 "GND")
			(pintype "passive")
		)
		(pad "2" smd roundrect
			(at 0.48 0 180)
			(size 0.59 0.64)
			(layers "B.Cu" "B.Mask" "B.Paste")
			(roundrect_rratio 0.25)
			(net 12 "XFI_VDD")
			(pintype "passive")
		)
	)
	(footprint "antmicro-footprints:R_0402_1005Metric"
		(layer "B.Cu")
		(at 180.8 74.5)
		(descr "Resistor SMD 0402")
		(tags "resistor SMD 0402")
		(property "Reference" "R86"
			(at 3 0.4 180)
			(layer "B.SilkS")
			(effects
				(font
					(size 0.7 0.7)
					(thickness 0.15)
				)
				(justify left bottom mirror)
			)
		)
		(property "Value" "R_330R_0402"
			(at -1.011843 -1.772047 180)
			(layer "B.Fab")
			(effects
				(font
					(size 0.7 0.7)
					(thickness 0.15)
				)
				(justify left bottom mirror)
			)
		)
		(property "Datasheet" "https://www.bourns.com/docs/product-datasheets/cr.pdf"
			(at 0 0 180)
			(layer "B.Fab")
			(hide yes)
			(effects
				(font
					(size 1.27 1.27)
					(thickness 0.15)
				)
				(justify mirror)
			)
		)
		(property "Description" "SMD Chip Resistor, 330 ohm, ± 1%, 62.5 mW, 0402 [1005 Metric], Thick Film, General Purpose"
			(at 0 0 180)
			(layer "B.Fab")
			(hide yes)
			(effects
				(font
					(size 1.27 1.27)
					(thickness 0.15)
				)
				(justify mirror)
			)
		)
		(property "MPN" "CR0402-FX-3300GLF"
			(at 0 0 0)
			(unlocked yes)
			(layer "B.Fab")
			(hide yes)
			(effects
				(font
					(size 1 1)
					(thickness 0.15)
				)
				(justify mirror)
			)
		)
		(property "Manufacturer" "Bourns"
			(at 0 0 0)
			(unlocked yes)
			(layer "B.Fab")
			(hide yes)
			(effects
				(font
					(size 1 1)
					(thickness 0.15)
				)
				(justify mirror)
			)
		)
		(property "License" "Apache-2.0"
			(at 0 0 0)
			(unlocked yes)
			(layer "B.Fab")
			(hide yes)
			(effects
				(font
					(size 1 1)
					(thickness 0.15)
				)
				(justify mirror)
			)
		)
		(property "Author" "Antmicro"
			(at 0 0 0)
			(unlocked yes)
			(layer "B.Fab")
			(hide yes)
			(effects
				(font
					(size 1 1)
					(thickness 0.15)
				)
				(justify mirror)
			)
		)
		(property "Val" "330R"
			(at 0 0 0)
			(unlocked yes)
			(layer "B.Fab")
			(hide yes)
			(effects
				(font
					(size 1 1)
					(thickness 0.15)
				)
				(justify mirror)
			)
		)
		(property "Tolerance" "1%"
			(at 0 0 0)
			(unlocked yes)
			(layer "B.Fab")
			(hide yes)
			(effects
				(font
					(size 1 1)
					(thickness 0.15)
				)
				(justify mirror)
			)
		)
		(sheetname "/X710 DCDC converters/")
		(sheetfile "DCDC_converters_X710.kicad_sch")
		(attr smd)
		(fp_rect
			(start -0.925 0.47)
			(end 0.925 -0.47)
			(stroke
				(width 0.05)
				(type default)
			)
			(fill no)
			(layer "B.CrtYd")
		)
		(fp_rect
			(start -0.5 0.25)
			(end 0.5 -0.25)
			(stroke
				(width 0.15)
				(type solid)
			)
			(fill no)
			(layer "B.Fab")
		)
		(fp_text user "License: Apache-2.0"
			(at -0.95 -5.169 180)
			(layer "B.Fab")
			(effects
				(font
					(size 0.7 0.7)
					(thickness 0.15)
				)
				(justify left bottom mirror)
			)
		)
		(fp_text user "${REFERENCE}"
			(at -0.95 -3.168 180)
			(layer "B.Fab")
			(effects
				(font
					(size 0.7 0.7)
					(thickness 0.15)
				)
				(justify left bottom mirror)
			)
		)
		(fp_text user "Author: Antmicro"
			(at -0.95 -4.169 180)
			(layer "B.Fab")
			(effects
				(font
					(size 0.7 0.7)
					(thickness 0.15)
				)
				(justify left bottom mirror)
			)
		)
		(pad "1" smd roundrect
			(at -0.48 0)
			(size 0.59 0.64)
			(layers "B.Cu" "B.Mask" "B.Paste")
			(roundrect_rratio 0.25)
			(net 430 "Net-(Q4-C)")
			(pintype "passive")
		)
		(pad "2" smd roundrect
			(at 0.48 0)
			(size 0.59 0.64)
			(layers "B.Cu" "B.Mask" "B.Paste")
			(roundrect_rratio 0.25)
			(net 416 "Net-(D9-C)")
			(pintype "passive")
		)
	)
	(footprint "antmicro-footprints:C_0402_1005Metric"
		(layer "B.Cu")
		(at 149.331866 81.260117 180)
		(descr "Capacitor SMD 0402")
		(tags "capacitor SMD 0402")
		(property "Reference" "C219"
			(at -19.468135 -9.464883 0)
			(layer "B.SilkS")
			(effects
				(font
					(size 0.7 0.7)
					(thickness 0.15)
				)
				(justify mirror)
			)
		)
		(property "Value" "C_1u_25V_0402"
			(at -1.022927 -2.155213 0)
			(layer "B.Fab")
			(effects
				(font
					(size 0.7 0.7)
					(thickness 0.15)
				)
				(justify left bottom mirror)
			)
		)
		(property "Datasheet" "https://www.murata.com/products/productdetail?partno=GRM155R61E105KE11%23"
			(at 0 0 0)
			(layer "B.Fab")
			(hide yes)
			(effects
				(font
					(size 1.27 1.27)
					(thickness 0.15)
				)
				(justify mirror)
			)
		)
		(property "Description" "SMD Multilayer Ceramic Capacitor, 1 µF, 25 V, 0402 [1005 Metric], ± 10%, X5R, GRM Series"
			(at 0 0 0)
			(layer "B.Fab")
			(hide yes)
			(effects
				(font
					(size 1.27 1.27)
					(thickness 0.15)
				)
				(justify mirror)
			)
		)
		(property "MPN" "GRM155R61E105KE11J"
			(at 0 0 180)
			(unlocked yes)
			(layer "B.Fab")
			(hide yes)
			(effects
				(font
					(size 1 1)
					(thickness 0.15)
				)
				(justify mirror)
			)
		)
		(property "Manufacturer" "Murata"
			(at 0 0 180)
			(unlocked yes)
			(layer "B.Fab")
			(hide yes)
			(effects
				(font
					(size 1 1)
					(thickness 0.15)
				)
				(justify mirror)
			)
		)
		(property "License" "Apache-2.0"
			(at 0 0 180)
			(unlocked yes)
			(layer "B.Fab")
			(hide yes)
			(effects
				(font
					(size 1 1)
					(thickness 0.15)
				)
				(justify mirror)
			)
		)
		(property "Author" "Antmicro"
			(at 0 0 180)
			(unlocked yes)
			(layer "B.Fab")
			(hide yes)
			(effects
				(font
					(size 1 1)
					(thickness 0.15)
				)
				(justify mirror)
			)
		)
		(property "Val" "1u"
			(at 0 0 180)
			(unlocked yes)
			(layer "B.Fab")
			(hide yes)
			(effects
				(font
					(size 1 1)
					(thickness 0.15)
				)
				(justify mirror)
			)
		)
		(property "Voltage" "25V"
			(at 0 0 180)
			(unlocked yes)
			(layer "B.Fab")
			(hide yes)
			(effects
				(font
					(size 1 1)
					(thickness 0.15)
				)
				(justify mirror)
			)
		)
		(property "Dielectric" "X5R"
			(at 0 0 180)
			(unlocked yes)
			(layer "B.Fab")
			(hide yes)
			(effects
				(font
					(size 1 1)
					(thickness 0.15)
				)
				(justify mirror)
			)
		)
		(sheetname "/X710-AT2 power/")
		(sheetfile "x710-at2-power.kicad_sch")
		(attr smd)
		(fp_rect
			(start -0.925 0.47)
			(end 0.925 -0.47)
			(stroke
				(width 0.05)
				(type default)
			)
			(fill no)
			(layer "B.CrtYd")
		)
		(fp_line
			(start 0.504 0.25)
			(end 0.504 -0.248)
			(stroke
				(width 0.15)
				(type solid)
			)
			(layer "B.Fab")
		)
		(fp_line
			(start 0.504 -0.248)
			(end -0.494 -0.248)
			(stroke
				(width 0.15)
				(type solid)
			)
			(layer "B.Fab")
		)
		(fp_line
			(start -0.494 0.25)
			(end 0.504 0.25)
			(stroke
				(width 0.15)
				(type solid)
			)
			(layer "B.Fab")
		)
		(fp_line
			(start -0.494 -0.248)
			(end -0.494 0.25)
			(stroke
				(width 0.15)
				(type solid)
			)
			(layer "B.Fab")
		)
		(fp_text user "${REFERENCE}"
			(at -0.939 -4.599 0)
			(layer "B.Fab")
			(effects
				(font
					(size 0.7 0.7)
					(thickness 0.15)
				)
				(justify left bottom mirror)
			)
		)
		(fp_text user "Author: Antmicro"
			(at -0.939 -3.399 0)
			(layer "B.Fab")
			(effects
				(font
					(size 0.7 0.7)
					(thickness 0.15)
				)
				(justify left bottom mirror)
			)
		)
		(fp_text user "License: Apache-2.0"
			(at -0.939 -5.799 0)
			(layer "B.Fab")
			(effects
				(font
					(size 0.7 0.7)
					(thickness 0.15)
				)
				(justify left bottom mirror)
			)
		)
		(pad "1" smd roundrect
			(at -0.48 0 180)
			(size 0.59 0.64)
			(layers "B.Cu" "B.Mask" "B.Paste")
			(roundrect_rratio 0.25)
			(net 23 "GND")
			(pintype "passive")
		)
		(pad "2" smd roundrect
			(at 0.48 0 180)
			(size 0.59 0.64)
			(layers "B.Cu" "B.Mask" "B.Paste")
			(roundrect_rratio 0.25)
			(net 9 "VCCD")
			(pintype "passive")
		)
	)
	(footprint "antmicro-footprints:C_0402_1005Metric"
		(layer "B.Cu")
		(at 156.111865 84.205116 180)
		(descr "Capacitor SMD 0402")
		(tags "capacitor SMD 0402")
		(property "Reference" "C202"
			(at -19.873134 -9.464883 0)
			(layer "B.SilkS")
			(effects
				(font
					(size 0.7 0.7)
					(thickness 0.15)
				)
				(justify mirror)
			)
		)
		(property "Value" "C_1u_25V_0402"
			(at -1.022927 -2.155213 0)
			(layer "B.Fab")
			(effects
				(font
					(size 0.7 0.7)
					(thickness 0.15)
				)
				(justify left bottom mirror)
			)
		)
		(property "Datasheet" "https://www.murata.com/products/productdetail?partno=GRM155R61E105KE11%23"
			(at 0 0 0)
			(layer "B.Fab")
			(hide yes)
			(effects
				(font
					(size 1.27 1.27)
					(thickness 0.15)
				)
				(justify mirror)
			)
		)
		(property "Description" "SMD Multilayer Ceramic Capacitor, 1 µF, 25 V, 0402 [1005 Metric], ± 10%, X5R, GRM Series"
			(at 0 0 0)
			(layer "B.Fab")
			(hide yes)
			(effects
				(font
					(size 1.27 1.27)
					(thickness 0.15)
				)
				(justify mirror)
			)
		)
		(property "MPN" "GRM155R61E105KE11J"
			(at 0 0 180)
			(unlocked yes)
			(layer "B.Fab")
			(hide yes)
			(effects
				(font
					(size 1 1)
					(thickness 0.15)
				)
				(justify mirror)
			)
		)
		(property "Manufacturer" "Murata"
			(at 0 0 180)
			(unlocked yes)
			(layer "B.Fab")
			(hide yes)
			(effects
				(font
					(size 1 1)
					(thickness 0.15)
				)
				(justify mirror)
			)
		)
		(property "License" "Apache-2.0"
			(at 0 0 180)
			(unlocked yes)
			(layer "B.Fab")
			(hide yes)
			(effects
				(font
					(size 1 1)
					(thickness 0.15)
				)
				(justify mirror)
			)
		)
		(property "Author" "Antmicro"
			(at 0 0 180)
			(unlocked yes)
			(layer "B.Fab")
			(hide yes)
			(effects
				(font
					(size 1 1)
					(thickness 0.15)
				)
				(justify mirror)
			)
		)
		(property "Val" "1u"
			(at 0 0 180)
			(unlocked yes)
			(layer "B.Fab")
			(hide yes)
			(effects
				(font
					(size 1 1)
					(thickness 0.15)
				)
				(justify mirror)
			)
		)
		(property "Voltage" "25V"
			(at 0 0 180)
			(unlocked yes)
			(layer "B.Fab")
			(hide yes)
			(effects
				(font
					(size 1 1)
					(thickness 0.15)
				)
				(justify mirror)
			)
		)
		(property "Dielectric" "X5R"
			(at 0 0 180)
			(unlocked yes)
			(layer "B.Fab")
			(hide yes)
			(effects
				(font
					(size 1 1)
					(thickness 0.15)
				)
				(justify mirror)
			)
		)
		(sheetname "/X710-AT2 power/")
		(sheetfile "x710-at2-power.kicad_sch")
		(attr smd)
		(fp_rect
			(start -0.925 0.47)
			(end 0.925 -0.47)
			(stroke
				(width 0.05)
				(type default)
			)
			(fill no)
			(layer "B.CrtYd")
		)
		(fp_line
			(start 0.504 0.25)
			(end 0.504 -0.248)
			(stroke
				(width 0.15)
				(type solid)
			)
			(layer "B.Fab")
		)
		(fp_line
			(start 0.504 -0.248)
			(end -0.494 -0.248)
			(stroke
				(width 0.15)
				(type solid)
			)
			(layer "B.Fab")
		)
		(fp_line
			(start -0.494 0.25)
			(end 0.504 0.25)
			(stroke
				(width 0.15)
				(type solid)
			)
			(layer "B.Fab")
		)
		(fp_line
			(start -0.494 -0.248)
			(end -0.494 0.25)
			(stroke
				(width 0.15)
				(type solid)
			)
			(layer "B.Fab")
		)
		(fp_text user "Author: Antmicro"
			(at -0.939 -3.399 0)
			(layer "B.Fab")
			(effects
				(font
					(size 0.7 0.7)
					(thickness 0.15)
				)
				(justify left bottom mirror)
			)
		)
		(fp_text user "${REFERENCE}"
			(at -0.939 -4.599 0)
			(layer "B.Fab")
			(effects
				(font
					(size 0.7 0.7)
					(thickness 0.15)
				)
				(justify left bottom mirror)
			)
		)
		(fp_text user "License: Apache-2.0"
			(at -0.939 -5.799 0)
			(layer "B.Fab")
			(effects
				(font
					(size 0.7 0.7)
					(thickness 0.15)
				)
				(justify left bottom mirror)
			)
		)
		(pad "1" smd roundrect
			(at -0.48 0 180)
			(size 0.59 0.64)
			(layers "B.Cu" "B.Mask" "B.Paste")
			(roundrect_rratio 0.25)
			(net 23 "GND")
			(pintype "passive")
		)
		(pad "2" smd roundrect
			(at 0.48 0 180)
			(size 0.59 0.64)
			(layers "B.Cu" "B.Mask" "B.Paste")
			(roundrect_rratio 0.25)
			(net 6 "DVDD")
			(pintype "passive")
		)
	)
	(footprint "antmicro-footprints:C_0402_1005Metric"
		(layer "B.Cu")
		(at 163.25 133.25)
		(descr "Capacitor SMD 0402")
		(tags "capacitor SMD 0402")
		(property "Reference" "C290"
			(at 4.5 -2.75 180)
			(layer "B.SilkS")
			(effects
				(font
					(size 0.7 0.7)
					(thickness 0.15)
				)
				(justify left bottom mirror)
			)
		)
		(property "Value" "C_1u_25V_0402"
			(at -1.022927 -2.155213 180)
			(layer "B.Fab")
			(effects
				(font
					(size 0.7 0.7)
					(thickness 0.15)
				)
				(justify left bottom mirror)
			)
		)
		(property "Datasheet" "https://www.murata.com/products/productdetail?partno=GRM155R61E105KE11%23"
			(at 0 0 180)
			(layer "B.Fab")
			(hide yes)
			(effects
				(font
					(size 1.27 1.27)
					(thickness 0.15)
				)
				(justify mirror)
			)
		)
		(property "Description" "SMD Multilayer Ceramic Capacitor, 1 µF, 25 V, 0402 [1005 Metric], ± 10%, X5R, GRM Series"
			(at 0 0 180)
			(layer "B.Fab")
			(hide yes)
			(effects
				(font
					(size 1.27 1.27)
					(thickness 0.15)
				)
				(justify mirror)
			)
		)
		(property "MPN" "GRM155R61E105KE11J"
			(at 0 0 0)
			(unlocked yes)
			(layer "B.Fab")
			(hide yes)
			(effects
				(font
					(size 1 1)
					(thickness 0.15)
				)
				(justify mirror)
			)
		)
		(property "Manufacturer" "Murata"
			(at 0 0 0)
			(unlocked yes)
			(layer "B.Fab")
			(hide yes)
			(effects
				(font
					(size 1 1)
					(thickness 0.15)
				)
				(justify mirror)
			)
		)
		(property "License" "Apache-2.0"
			(at 0 0 0)
			(unlocked yes)
			(layer "B.Fab")
			(hide yes)
			(effects
				(font
					(size 1 1)
					(thickness 0.15)
				)
				(justify mirror)
			)
		)
		(property "Author" "Antmicro"
			(at 0 0 0)
			(unlocked yes)
			(layer "B.Fab")
			(hide yes)
			(effects
				(font
					(size 1 1)
					(thickness 0.15)
				)
				(justify mirror)
			)
		)
		(property "Val" "1u"
			(at 0 0 0)
			(unlocked yes)
			(layer "B.Fab")
			(hide yes)
			(effects
				(font
					(size 1 1)
					(thickness 0.15)
				)
				(justify mirror)
			)
		)
		(property "Voltage" "25V"
			(at 0 0 0)
			(unlocked yes)
			(layer "B.Fab")
			(hide yes)
			(effects
				(font
					(size 1 1)
					(thickness 0.15)
				)
				(justify mirror)
			)
		)
		(property "Dielectric" "X5R"
			(at 0 0 0)
			(unlocked yes)
			(layer "B.Fab")
			(hide yes)
			(effects
				(font
					(size 1 1)
					(thickness 0.15)
				)
				(justify mirror)
			)
		)
		(sheetname "/2xRJ45/")
		(sheetfile "2xrj45.kicad_sch")
		(attr smd)
		(fp_rect
			(start -0.925 0.47)
			(end 0.925 -0.47)
			(stroke
				(width 0.05)
				(type default)
			)
			(fill no)
			(layer "B.CrtYd")
		)
		(fp_line
			(start -0.494 -0.248)
			(end -0.494 0.25)
			(stroke
				(width 0.15)
				(type solid)
			)
			(layer "B.Fab")
		)
		(fp_line
			(start -0.494 0.25)
			(end 0.504 0.25)
			(stroke
				(width 0.15)
				(type solid)
			)
			(layer "B.Fab")
		)
		(fp_line
			(start 0.504 -0.248)
			(end -0.494 -0.248)
			(stroke
				(width 0.15)
				(type solid)
			)
			(layer "B.Fab")
		)
		(fp_line
			(start 0.504 0.25)
			(end 0.504 -0.248)
			(stroke
				(width 0.15)
				(type solid)
			)
			(layer "B.Fab")
		)
		(fp_text user "License: Apache-2.0"
			(at -0.939 -5.799 180)
			(layer "B.Fab")
			(effects
				(font
					(size 0.7 0.7)
					(thickness 0.15)
				)
				(justify left bottom mirror)
			)
		)
		(fp_text user "Author: Antmicro"
			(at -0.939 -3.399 180)
			(layer "B.Fab")
			(effects
				(font
					(size 0.7 0.7)
					(thickness 0.15)
				)
				(justify left bottom mirror)
			)
		)
		(fp_text user "${REFERENCE}"
			(at -0.939 -4.599 180)
			(layer "B.Fab")
			(effects
				(font
					(size 0.7 0.7)
					(thickness 0.15)
				)
				(justify left bottom mirror)
			)
		)
		(pad "1" smd roundrect
			(at -0.48 0)
			(size 0.59 0.64)
			(layers "B.Cu" "B.Mask" "B.Paste")
			(roundrect_rratio 0.25)
			(net 23 "GND")
			(pintype "passive")
		)
		(pad "2" smd roundrect
			(at 0.48 0)
			(size 0.59 0.64)
			(layers "B.Cu" "B.Mask" "B.Paste")
			(roundrect_rratio 0.25)
			(net 135 "+1V88_CT")
			(pintype "passive")
		)
	)
	(footprint "antmicro-footprints:TP_SMD_0.75mm"
		(layer "B.Cu")
		(at 136.25 57.75 90)
		(property "Reference" "TP39"
			(at 3.15 0.45 270)
			(layer "B.SilkS")
			(effects
				(font
					(size 0.7 0.7)
					(thickness 0.15)
				)
				(justify left bottom mirror)
			)
		)
		(property "Value" "TP_0.75mm_SMD"
			(at 0 -1.2 270)
			(layer "B.Fab")
			(effects
				(font
					(size 0.7 0.7)
					(thickness 0.15)
				)
				(justify left bottom mirror)
			)
		)
		(property "Description" "SMT test point"
			(at 0 0 270)
			(layer "B.Fab")
			(hide yes)
			(effects
				(font
					(size 1.27 1.27)
					(thickness 0.15)
				)
				(justify mirror)
			)
		)
		(property "MPN" ""
			(at 0 0 90)
			(unlocked yes)
			(layer "B.Fab")
			(hide yes)
			(effects
				(font
					(size 1 1)
					(thickness 0.15)
				)
				(justify mirror)
			)
		)
		(property "Manufacturer" ""
			(at 0 0 90)
			(unlocked yes)
			(layer "B.Fab")
			(hide yes)
			(effects
				(font
					(size 1 1)
					(thickness 0.15)
				)
				(justify mirror)
			)
		)
		(property "Author" "Antmicro"
			(at 0 0 90)
			(unlocked yes)
			(layer "B.Fab")
			(hide yes)
			(effects
				(font
					(size 1 1)
					(thickness 0.15)
				)
				(justify mirror)
			)
		)
		(property "License" "Apache-2.0"
			(at 0 0 90)
			(unlocked yes)
			(layer "B.Fab")
			(hide yes)
			(effects
				(font
					(size 1 1)
					(thickness 0.15)
				)
				(justify mirror)
			)
		)
		(sheetname "/Power input/")
		(sheetfile "power_input.kicad_sch")
		(attr exclude_from_pos_files exclude_from_bom)
		(fp_circle
			(center 0 0)
			(end 0.475 0)
			(stroke
				(width 0.05)
				(type default)
			)
			(fill no)
			(layer "B.CrtYd")
		)
		(fp_text user "Author: Antmicro"
			(at -0.4 -3.901 270)
			(layer "B.Fab")
			(effects
				(font
					(size 0.7 0.7)
					(thickness 0.15)
				)
				(justify left bottom mirror)
			)
		)
		(fp_text user "License: Apache-2.0"
			(at -0.4 -5.101 270)
			(layer "B.Fab")
			(effects
				(font
					(size 0.7 0.7)
					(thickness 0.15)
				)
				(justify left bottom mirror)
			)
		)
		(fp_text user "${REFERENCE}"
			(at -0.4 -2.7 270)
			(layer "B.Fab")
			(effects
				(font
					(size 0.7 0.7)
					(thickness 0.15)
				)
				(justify left bottom mirror)
			)
		)
		(pad "1" smd circle
			(at 0 0 90)
			(size 0.75 0.75)
			(layers "B.Cu" "B.Mask")
			(net 13 "/Power input/5V_JACK")
			(pinfunction "1")
			(pintype "passive")
		)
	)
	(footprint "antmicro-footprints:C_0402_1005Metric"
		(layer "B.Cu")
		(at 128.5 123.95 -90)
		(descr "Capacitor SMD 0402")
		(tags "capacitor SMD 0402")
		(property "Reference" "C69"
			(at -7.700002 -21.900002 90)
			(layer "B.SilkS")
			(effects
				(font
					(size 0.7 0.7)
					(thickness 0.15)
				)
				(justify mirror)
			)
		)
		(property "Value" "C_1u_0402"
			(at -1.022927 -2.155213 90)
			(layer "B.Fab")
			(effects
				(font
					(size 0.7 0.7)
					(thickness 0.15)
				)
				(justify left bottom mirror)
			)
		)
		(property "Datasheet" "https://product.tdk.com/en/search/capacitor/ceramic/mlcc/info?part_no=C1005X6S1A105K050BC"
			(at 0 0 90)
			(layer "B.Fab")
			(hide yes)
			(effects
				(font
					(size 1.27 1.27)
					(thickness 0.15)
				)
				(justify mirror)
			)
		)
		(property "Description" "SMD Multilayer Ceramic Capacitor, 1 µF, 10 V, 0402 [1005 Metric], ± 10%, X6S, C"
			(at 0 0 90)
			(layer "B.Fab")
			(hide yes)
			(effects
				(font
					(size 1.27 1.27)
					(thickness 0.15)
				)
				(justify mirror)
			)
		)
		(property "MPN" "C1005X6S1A105K050BC"
			(at 0 0 270)
			(unlocked yes)
			(layer "B.Fab")
			(hide yes)
			(effects
				(font
					(size 1 1)
					(thickness 0.15)
				)
				(justify mirror)
			)
		)
		(property "Manufacturer" "TDK"
			(at 0 0 270)
			(unlocked yes)
			(layer "B.Fab")
			(hide yes)
			(effects
				(font
					(size 1 1)
					(thickness 0.15)
				)
				(justify mirror)
			)
		)
		(property "License" "Apache-2.0"
			(at 0 0 270)
			(unlocked yes)
			(layer "B.Fab")
			(hide yes)
			(effects
				(font
					(size 1 1)
					(thickness 0.15)
				)
				(justify mirror)
			)
		)
		(property "Val" "1u"
			(at 0 0 270)
			(unlocked yes)
			(layer "B.Fab")
			(hide yes)
			(effects
				(font
					(size 1 1)
					(thickness 0.15)
				)
				(justify mirror)
			)
		)
		(property "Voltage" ""
			(at 0 0 270)
			(unlocked yes)
			(layer "B.Fab")
			(hide yes)
			(effects
				(font
					(size 1 1)
					(thickness 0.15)
				)
				(justify mirror)
			)
		)
		(property "Dielectric" ""
			(at 0 0 270)
			(unlocked yes)
			(layer "B.Fab")
			(hide yes)
			(effects
				(font
					(size 1 1)
					(thickness 0.15)
				)
				(justify mirror)
			)
		)
		(property "Author" "Antmicro"
			(at 0 0 270)
			(unlocked yes)
			(layer "B.Fab")
			(hide yes)
			(effects
				(font
					(size 1 1)
					(thickness 0.15)
				)
				(justify mirror)
			)
		)
		(sheetname "/TB Controller - Power/")
		(sheetfile "tb-power.kicad_sch")
		(attr smd)
		(fp_rect
			(start -0.925 0.47)
			(end 0.925 -0.47)
			(stroke
				(width 0.05)
				(type default)
			)
			(fill no)
			(layer "B.CrtYd")
		)
		(fp_line
			(start -0.494 0.25)
			(end 0.504 0.25)
			(stroke
				(width 0.15)
				(type solid)
			)
			(layer "B.Fab")
		)
		(fp_line
			(start 0.504 0.25)
			(end 0.504 -0.248)
			(stroke
				(width 0.15)
				(type solid)
			)
			(layer "B.Fab")
		)
		(fp_line
			(start -0.494 -0.248)
			(end -0.494 0.25)
			(stroke
				(width 0.15)
				(type solid)
			)
			(layer "B.Fab")
		)
		(fp_line
			(start 0.504 -0.248)
			(end -0.494 -0.248)
			(stroke
				(width 0.15)
				(type solid)
			)
			(layer "B.Fab")
		)
		(fp_text user "License: Apache-2.0"
			(at -0.939 -5.799 90)
			(layer "B.Fab")
			(effects
				(font
					(size 0.7 0.7)
					(thickness 0.15)
				)
				(justify left bottom mirror)
			)
		)
		(fp_text user "${REFERENCE}"
			(at -0.939 -4.599 90)
			(layer "B.Fab")
			(effects
				(font
					(size 0.7 0.7)
					(thickness 0.15)
				)
				(justify left bottom mirror)
			)
		)
		(fp_text user "Author: Antmicro"
			(at -0.939 -3.399 90)
			(layer "B.Fab")
			(effects
				(font
					(size 0.7 0.7)
					(thickness 0.15)
				)
				(justify left bottom mirror)
			)
		)
		(pad "1" smd roundrect
			(at -0.48 0 270)
			(size 0.59 0.64)
			(layers "B.Cu" "B.Mask" "B.Paste")
			(roundrect_rratio 0.25)
			(net 23 "GND")
			(pintype "passive")
		)
		(pad "2" smd roundrect
			(at 0.48 0 270)
			(size 0.59 0.64)
			(layers "B.Cu" "B.Mask" "B.Paste")
			(roundrect_rratio 0.25)
			(net 402 "Net-(C52-Pad2)")
			(pintype "passive")
		)
	)
	(footprint "antmicro-footprints:TP_SMD_0.75mm"
		(layer "B.Cu")
		(at 159.731866 67.435118 90)
		(property "Reference" "TP22"
			(at 0.035118 3.268134 180)
			(layer "B.SilkS")
			(effects
				(font
					(size 0.7 0.7)
					(thickness 0.15)
				)
				(justify left bottom mirror)
			)
		)
		(property "Value" "TP_0.75mm_SMD"
			(at 0 -1.2 270)
			(layer "B.Fab")
			(effects
				(font
					(size 0.7 0.7)
					(thickness 0.15)
				)
				(justify left bottom mirror)
			)
		)
		(property "Description" "SMT test point"
			(at 0 0 270)
			(layer "B.Fab")
			(hide yes)
			(effects
				(font
					(size 1.27 1.27)
					(thickness 0.15)
				)
				(justify mirror)
			)
		)
		(property "MPN" ""
			(at 0 0 90)
			(unlocked yes)
			(layer "B.Fab")
			(hide yes)
			(effects
				(font
					(size 1 1)
					(thickness 0.15)
				)
				(justify mirror)
			)
		)
		(property "Manufacturer" ""
			(at 0 0 90)
			(unlocked yes)
			(layer "B.Fab")
			(hide yes)
			(effects
				(font
					(size 1 1)
					(thickness 0.15)
				)
				(justify mirror)
			)
		)
		(property "Author" "Antmicro"
			(at 0 0 90)
			(unlocked yes)
			(layer "B.Fab")
			(hide yes)
			(effects
				(font
					(size 1 1)
					(thickness 0.15)
				)
				(justify mirror)
			)
		)
		(property "License" "Apache-2.0"
			(at 0 0 90)
			(unlocked yes)
			(layer "B.Fab")
			(hide yes)
			(effects
				(font
					(size 1 1)
					(thickness 0.15)
				)
				(justify mirror)
			)
		)
		(sheetname "/X710-AT2 Misc/")
		(sheetfile "x710-at2-mics.kicad_sch")
		(attr exclude_from_pos_files exclude_from_bom)
		(fp_circle
			(center 0 0)
			(end 0.475 0)
			(stroke
				(width 0.05)
				(type default)
			)
			(fill no)
			(layer "B.CrtYd")
		)
		(fp_text user "Author: Antmicro"
			(at -0.4 -3.901 270)
			(layer "B.Fab")
			(effects
				(font
					(size 0.7 0.7)
					(thickness 0.15)
				)
				(justify left bottom mirror)
			)
		)
		(fp_text user "${REFERENCE}"
			(at -0.4 -2.7 270)
			(layer "B.Fab")
			(effects
				(font
					(size 0.7 0.7)
					(thickness 0.15)
				)
				(justify left bottom mirror)
			)
		)
		(fp_text user "License: Apache-2.0"
			(at -0.4 -5.101 270)
			(layer "B.Fab")
			(effects
				(font
					(size 0.7 0.7)
					(thickness 0.15)
				)
				(justify left bottom mirror)
			)
		)
		(pad "1" smd circle
			(at 0 0 90)
			(size 0.75 0.75)
			(layers "B.Cu" "B.Mask")
			(net 141 "/X710-AT2 Misc/NCSI.ARB_OUT")
			(pinfunction "1")
			(pintype "passive")
		)
	)
	(footprint "antmicro-footprints:C_0402_1005Metric"
		(layer "B.Cu")
		(at 162.6 105 90)
		(descr "Capacitor SMD 0402")
		(tags "capacitor SMD 0402")
		(property "Reference" "C152"
			(at 1.4 1.5 270)
			(layer "B.SilkS")
			(effects
				(font
					(size 0.7 0.7)
					(thickness 0.15)
				)
				(justify left bottom mirror)
			)
		)
		(property "Value" "C_100n_0402"
			(at -1.022927 -2.155213 270)
			(layer "B.Fab")
			(effects
				(font
					(size 0.7 0.7)
					(thickness 0.15)
				)
				(justify left bottom mirror)
			)
		)
		(property "Datasheet" "https://www.murata.com/products/productdetail?partno=GRM155R61H104KE14%23"
			(at 0 0 270)
			(layer "B.Fab")
			(hide yes)
			(effects
				(font
					(size 1.27 1.27)
					(thickness 0.15)
				)
				(justify mirror)
			)
		)
		(property "Description" "SMD Multilayer Ceramic Capacitor, 0.1 µF, 50 V, 0402 [1005 Metric], ± 10%, X5R, GRM Series"
			(at 0 0 270)
			(layer "B.Fab")
			(hide yes)
			(effects
				(font
					(size 1.27 1.27)
					(thickness 0.15)
				)
				(justify mirror)
			)
		)
		(property "MPN" "GRM155R61H104KE14D"
			(at 0 0 90)
			(unlocked yes)
			(layer "B.Fab")
			(hide yes)
			(effects
				(font
					(size 1 1)
					(thickness 0.15)
				)
				(justify mirror)
			)
		)
		(property "Manufacturer" "Murata"
			(at 0 0 90)
			(unlocked yes)
			(layer "B.Fab")
			(hide yes)
			(effects
				(font
					(size 1 1)
					(thickness 0.15)
				)
				(justify mirror)
			)
		)
		(property "License" "Apache-2.0"
			(at 0 0 90)
			(unlocked yes)
			(layer "B.Fab")
			(hide yes)
			(effects
				(font
					(size 1 1)
					(thickness 0.15)
				)
				(justify mirror)
			)
		)
		(property "Author" "Antmicro"
			(at 0 0 90)
			(unlocked yes)
			(layer "B.Fab")
			(hide yes)
			(effects
				(font
					(size 1 1)
					(thickness 0.15)
				)
				(justify mirror)
			)
		)
		(property "Val" "100n"
			(at 0 0 90)
			(unlocked yes)
			(layer "B.Fab")
			(hide yes)
			(effects
				(font
					(size 1 1)
					(thickness 0.15)
				)
				(justify mirror)
			)
		)
		(property "Voltage" "50V"
			(at 0 0 90)
			(unlocked yes)
			(layer "B.Fab")
			(hide yes)
			(effects
				(font
					(size 1 1)
					(thickness 0.15)
				)
				(justify mirror)
			)
		)
		(property "Dielectric" "X5R"
			(at 0 0 90)
			(unlocked yes)
			(layer "B.Fab")
			(hide yes)
			(effects
				(font
					(size 1 1)
					(thickness 0.15)
				)
				(justify mirror)
			)
		)
		(sheetname "/X710 DCDC converters/")
		(sheetfile "DCDC_converters_X710.kicad_sch")
		(attr smd)
		(fp_rect
			(start -0.925 0.47)
			(end 0.925 -0.47)
			(stroke
				(width 0.05)
				(type default)
			)
			(fill no)
			(layer "B.CrtYd")
		)
		(fp_line
			(start 0.504 -0.248)
			(end -0.494 -0.248)
			(stroke
				(width 0.15)
				(type solid)
			)
			(layer "B.Fab")
		)
		(fp_line
			(start -0.494 -0.248)
			(end -0.494 0.25)
			(stroke
				(width 0.15)
				(type solid)
			)
			(layer "B.Fab")
		)
		(fp_line
			(start 0.504 0.25)
			(end 0.504 -0.248)
			(stroke
				(width 0.15)
				(type solid)
			)
			(layer "B.Fab")
		)
		(fp_line
			(start -0.494 0.25)
			(end 0.504 0.25)
			(stroke
				(width 0.15)
				(type solid)
			)
			(layer "B.Fab")
		)
		(fp_text user "Author: Antmicro"
			(at -0.939 -3.399 270)
			(layer "B.Fab")
			(effects
				(font
					(size 0.7 0.7)
					(thickness 0.15)
				)
				(justify left bottom mirror)
			)
		)
		(fp_text user "License: Apache-2.0"
			(at -0.939 -5.799 270)
			(layer "B.Fab")
			(effects
				(font
					(size 0.7 0.7)
					(thickness 0.15)
				)
				(justify left bottom mirror)
			)
		)
		(fp_text user "${REFERENCE}"
			(at -0.939 -4.599 270)
			(layer "B.Fab")
			(effects
				(font
					(size 0.7 0.7)
					(thickness 0.15)
				)
				(justify left bottom mirror)
			)
		)
		(pad "1" smd roundrect
			(at -0.48 0 90)
			(size 0.59 0.64)
			(layers "B.Cu" "B.Mask" "B.Paste")
			(roundrect_rratio 0.25)
			(net 23 "GND")
			(pintype "passive")
		)
		(pad "2" smd roundrect
			(at 0.48 0 90)
			(size 0.59 0.64)
			(layers "B.Cu" "B.Mask" "B.Paste")
			(roundrect_rratio 0.25)
			(net 339 "/X710 DCDC converters/+1V0_OUT")
			(pintype "passive")
		)
	)
	(footprint "antmicro-footprints:C_0402_1005Metric"
		(layer "B.Cu")
		(at 157.081867 89.005117)
		(descr "Capacitor SMD 0402")
		(tags "capacitor SMD 0402")
		(property "Reference" "C186"
			(at 18.968134 9.994883 180)
			(layer "B.SilkS")
			(effects
				(font
					(size 0.7 0.7)
					(thickness 0.15)
				)
				(justify mirror)
			)
		)
		(property "Value" "C_1u_25V_0402"
			(at -1.022927 -2.155213 180)
			(layer "B.Fab")
			(effects
				(font
					(size 0.7 0.7)
					(thickness 0.15)
				)
				(justify left bottom mirror)
			)
		)
		(property "Datasheet" "https://www.murata.com/products/productdetail?partno=GRM155R61E105KE11%23"
			(at 0 0 180)
			(layer "B.Fab")
			(hide yes)
			(effects
				(font
					(size 1.27 1.27)
					(thickness 0.15)
				)
				(justify mirror)
			)
		)
		(property "Description" "SMD Multilayer Ceramic Capacitor, 1 µF, 25 V, 0402 [1005 Metric], ± 10%, X5R, GRM Series"
			(at 0 0 180)
			(layer "B.Fab")
			(hide yes)
			(effects
				(font
					(size 1.27 1.27)
					(thickness 0.15)
				)
				(justify mirror)
			)
		)
		(property "MPN" "GRM155R61E105KE11J"
			(at 0 0 0)
			(unlocked yes)
			(layer "B.Fab")
			(hide yes)
			(effects
				(font
					(size 1 1)
					(thickness 0.15)
				)
				(justify mirror)
			)
		)
		(property "Manufacturer" "Murata"
			(at 0 0 0)
			(unlocked yes)
			(layer "B.Fab")
			(hide yes)
			(effects
				(font
					(size 1 1)
					(thickness 0.15)
				)
				(justify mirror)
			)
		)
		(property "License" "Apache-2.0"
			(at 0 0 0)
			(unlocked yes)
			(layer "B.Fab")
			(hide yes)
			(effects
				(font
					(size 1 1)
					(thickness 0.15)
				)
				(justify mirror)
			)
		)
		(property "Author" "Antmicro"
			(at 0 0 0)
			(unlocked yes)
			(layer "B.Fab")
			(hide yes)
			(effects
				(font
					(size 1 1)
					(thickness 0.15)
				)
				(justify mirror)
			)
		)
		(property "Val" "1u"
			(at 0 0 0)
			(unlocked yes)
			(layer "B.Fab")
			(hide yes)
			(effects
				(font
					(size 1 1)
					(thickness 0.15)
				)
				(justify mirror)
			)
		)
		(property "Voltage" "25V"
			(at 0 0 0)
			(unlocked yes)
			(layer "B.Fab")
			(hide yes)
			(effects
				(font
					(size 1 1)
					(thickness 0.15)
				)
				(justify mirror)
			)
		)
		(property "Dielectric" "X5R"
			(at 0 0 0)
			(unlocked yes)
			(layer "B.Fab")
			(hide yes)
			(effects
				(font
					(size 1 1)
					(thickness 0.15)
				)
				(justify mirror)
			)
		)
		(sheetname "/X710-AT2 power/")
		(sheetfile "x710-at2-power.kicad_sch")
		(attr smd)
		(fp_rect
			(start -0.925 0.47)
			(end 0.925 -0.47)
			(stroke
				(width 0.05)
				(type default)
			)
			(fill no)
			(layer "B.CrtYd")
		)
		(fp_line
			(start -0.494 -0.248)
			(end -0.494 0.25)
			(stroke
				(width 0.15)
				(type solid)
			)
			(layer "B.Fab")
		)
		(fp_line
			(start -0.494 0.25)
			(end 0.504 0.25)
			(stroke
				(width 0.15)
				(type solid)
			)
			(layer "B.Fab")
		)
		(fp_line
			(start 0.504 -0.248)
			(end -0.494 -0.248)
			(stroke
				(width 0.15)
				(type solid)
			)
			(layer "B.Fab")
		)
		(fp_line
			(start 0.504 0.25)
			(end 0.504 -0.248)
			(stroke
				(width 0.15)
				(type solid)
			)
			(layer "B.Fab")
		)
		(fp_text user "License: Apache-2.0"
			(at -0.939 -5.799 180)
			(layer "B.Fab")
			(effects
				(font
					(size 0.7 0.7)
					(thickness 0.15)
				)
				(justify left bottom mirror)
			)
		)
		(fp_text user "Author: Antmicro"
			(at -0.939 -3.399 180)
			(layer "B.Fab")
			(effects
				(font
					(size 0.7 0.7)
					(thickness 0.15)
				)
				(justify left bottom mirror)
			)
		)
		(fp_text user "${REFERENCE}"
			(at -0.939 -4.599 180)
			(layer "B.Fab")
			(effects
				(font
					(size 0.7 0.7)
					(thickness 0.15)
				)
				(justify left bottom mirror)
			)
		)
		(pad "1" smd roundrect
			(at -0.48 0)
			(size 0.59 0.64)
			(layers "B.Cu" "B.Mask" "B.Paste")
			(roundrect_rratio 0.25)
			(net 23 "GND")
			(pintype "passive")
		)
		(pad "2" smd roundrect
			(at 0.48 0)
			(size 0.59 0.64)
			(layers "B.Cu" "B.Mask" "B.Paste")
			(roundrect_rratio 0.25)
			(net 10 "AVDDH")
			(pintype "passive")
		)
	)
	(footprint "antmicro-footprints:C_0402_1005Metric"
		(layer "B.Cu")
		(at 121.7 145.1 -90)
		(descr "Capacitor SMD 0402")
		(tags "capacitor SMD 0402")
		(property "Reference" "C4"
			(at -2.35 -0.3 90)
			(layer "B.SilkS")
			(effects
				(font
					(size 0.7 0.7)
					(thickness 0.15)
				)
				(justify left bottom mirror)
			)
		)
		(property "Value" "C_100n_0402"
			(at -1.022927 -2.155213 90)
			(layer "B.Fab")
			(effects
				(font
					(size 0.7 0.7)
					(thickness 0.15)
				)
				(justify left bottom mirror)
			)
		)
		(property "Datasheet" "https://www.murata.com/products/productdetail?partno=GRM155R61H104KE14%23"
			(at 0 0 90)
			(layer "B.Fab")
			(hide yes)
			(effects
				(font
					(size 1.27 1.27)
					(thickness 0.15)
				)
				(justify mirror)
			)
		)
		(property "Description" "SMD Multilayer Ceramic Capacitor, 0.1 µF, 50 V, 0402 [1005 Metric], ± 10%, X5R, GRM Series"
			(at 0 0 90)
			(layer "B.Fab")
			(hide yes)
			(effects
				(font
					(size 1.27 1.27)
					(thickness 0.15)
				)
				(justify mirror)
			)
		)
		(property "MPN" "GRM155R61H104KE14D"
			(at 0 0 270)
			(unlocked yes)
			(layer "B.Fab")
			(hide yes)
			(effects
				(font
					(size 1 1)
					(thickness 0.15)
				)
				(justify mirror)
			)
		)
		(property "Manufacturer" "Murata"
			(at 0 0 270)
			(unlocked yes)
			(layer "B.Fab")
			(hide yes)
			(effects
				(font
					(size 1 1)
					(thickness 0.15)
				)
				(justify mirror)
			)
		)
		(property "License" "Apache-2.0"
			(at 0 0 270)
			(unlocked yes)
			(layer "B.Fab")
			(hide yes)
			(effects
				(font
					(size 1 1)
					(thickness 0.15)
				)
				(justify mirror)
			)
		)
		(property "Val" "100n"
			(at 0 0 270)
			(unlocked yes)
			(layer "B.Fab")
			(hide yes)
			(effects
				(font
					(size 1 1)
					(thickness 0.15)
				)
				(justify mirror)
			)
		)
		(property "Voltage" "50V"
			(at 0 0 270)
			(unlocked yes)
			(layer "B.Fab")
			(hide yes)
			(effects
				(font
					(size 1 1)
					(thickness 0.15)
				)
				(justify mirror)
			)
		)
		(property "Dielectric" "X5R"
			(at 0 0 270)
			(unlocked yes)
			(layer "B.Fab")
			(hide yes)
			(effects
				(font
					(size 1 1)
					(thickness 0.15)
				)
				(justify mirror)
			)
		)
		(property "Author" "Antmicro"
			(at 0 0 270)
			(unlocked yes)
			(layer "B.Fab")
			(hide yes)
			(effects
				(font
					(size 1 1)
					(thickness 0.15)
				)
				(justify mirror)
			)
		)
		(sheetname "/USB-C connector/")
		(sheetfile "USB-C_connector.kicad_sch")
		(attr smd)
		(fp_rect
			(start -0.925 0.47)
			(end 0.925 -0.47)
			(stroke
				(width 0.05)
				(type default)
			)
			(fill no)
			(layer "B.CrtYd")
		)
		(fp_line
			(start -0.494 0.25)
			(end 0.504 0.25)
			(stroke
				(width 0.15)
				(type solid)
			)
			(layer "B.Fab")
		)
		(fp_line
			(start 0.504 0.25)
			(end 0.504 -0.248)
			(stroke
				(width 0.15)
				(type solid)
			)
			(layer "B.Fab")
		)
		(fp_line
			(start -0.494 -0.248)
			(end -0.494 0.25)
			(stroke
				(width 0.15)
				(type solid)
			)
			(layer "B.Fab")
		)
		(fp_line
			(start 0.504 -0.248)
			(end -0.494 -0.248)
			(stroke
				(width 0.15)
				(type solid)
			)
			(layer "B.Fab")
		)
		(fp_text user "Author: Antmicro"
			(at -0.939 -3.399 90)
			(layer "B.Fab")
			(effects
				(font
					(size 0.7 0.7)
					(thickness 0.15)
				)
				(justify left bottom mirror)
			)
		)
		(fp_text user "License: Apache-2.0"
			(at -0.939 -5.799 90)
			(layer "B.Fab")
			(effects
				(font
					(size 0.7 0.7)
					(thickness 0.15)
				)
				(justify left bottom mirror)
			)
		)
		(fp_text user "${REFERENCE}"
			(at -0.939 -4.599 90)
			(layer "B.Fab")
			(effects
				(font
					(size 0.7 0.7)
					(thickness 0.15)
				)
				(justify left bottom mirror)
			)
		)
		(pad "1" smd roundrect
			(at -0.48 0 270)
			(size 0.59 0.64)
			(layers "B.Cu" "B.Mask" "B.Paste")
			(roundrect_rratio 0.25)
			(net 23 "GND")
			(pintype "passive")
		)
		(pad "2" smd roundrect
			(at 0.48 0 270)
			(size 0.59 0.64)
			(layers "B.Cu" "B.Mask" "B.Paste")
			(roundrect_rratio 0.25)
			(net 215 "/USB-C connector/VBUS")
			(pintype "passive")
		)
	)
	(footprint "antmicro-footprints:R_0402_1005Metric"
		(layer "B.Cu")
		(at 132.875002 131.099998 90)
		(descr "Resistor SMD 0402")
		(tags "resistor SMD 0402")
		(property "Reference" "R4"
			(at 8.35 19.525001 270)
			(layer "B.SilkS")
			(effects
				(font
					(size 0.7 0.7)
					(thickness 0.15)
				)
				(justify mirror)
			)
		)
		(property "Value" "R_100k_0402"
			(at -1.011843 -1.772047 270)
			(layer "B.Fab")
			(effects
				(font
					(size 0.7 0.7)
					(thickness 0.15)
				)
				(justify left bottom mirror)
			)
		)
		(property "Datasheet" "https://www.bourns.com/docs/product-datasheets/cr.pdf"
			(at 0 0 270)
			(layer "B.Fab")
			(hide yes)
			(effects
				(font
					(size 1.27 1.27)
					(thickness 0.15)
				)
				(justify mirror)
			)
		)
		(property "Description" "SMD Chip Resistor, 100 kohm, ± 1%, 62.5 mW, 0402 [1005 Metric], Thick Film, General Purpose"
			(at 0 0 270)
			(layer "B.Fab")
			(hide yes)
			(effects
				(font
					(size 1.27 1.27)
					(thickness 0.15)
				)
				(justify mirror)
			)
		)
		(property "MPN" "CR0402-FX-1003GLF"
			(at 0 0 90)
			(unlocked yes)
			(layer "B.Fab")
			(hide yes)
			(effects
				(font
					(size 1 1)
					(thickness 0.15)
				)
				(justify mirror)
			)
		)
		(property "Manufacturer" "Bourns"
			(at 0 0 90)
			(unlocked yes)
			(layer "B.Fab")
			(hide yes)
			(effects
				(font
					(size 1 1)
					(thickness 0.15)
				)
				(justify mirror)
			)
		)
		(property "License" "Apache-2.0"
			(at 0 0 90)
			(unlocked yes)
			(layer "B.Fab")
			(hide yes)
			(effects
				(font
					(size 1 1)
					(thickness 0.15)
				)
				(justify mirror)
			)
		)
		(property "Val" "100k"
			(at 0 0 90)
			(unlocked yes)
			(layer "B.Fab")
			(hide yes)
			(effects
				(font
					(size 1 1)
					(thickness 0.15)
				)
				(justify mirror)
			)
		)
		(property "Tolerance" "1%"
			(at 0 0 90)
			(unlocked yes)
			(layer "B.Fab")
			(hide yes)
			(effects
				(font
					(size 1 1)
					(thickness 0.15)
				)
				(justify mirror)
			)
		)
		(property "Author" "Antmicro"
			(at 0 0 90)
			(unlocked yes)
			(layer "B.Fab")
			(hide yes)
			(effects
				(font
					(size 1 1)
					(thickness 0.15)
				)
				(justify mirror)
			)
		)
		(sheetname "/PD and TB DC-DC/")
		(sheetfile "PD_and_TB_DC_DC.kicad_sch")
		(attr smd)
		(fp_rect
			(start -0.925 0.47)
			(end 0.925 -0.47)
			(stroke
				(width 0.05)
				(type default)
			)
			(fill no)
			(layer "B.CrtYd")
		)
		(fp_rect
			(start -0.5 0.25)
			(end 0.5 -0.25)
			(stroke
				(width 0.15)
				(type solid)
			)
			(fill no)
			(layer "B.Fab")
		)
		(fp_text user "License: Apache-2.0"
			(at -0.95 -5.169 270)
			(layer "B.Fab")
			(effects
				(font
					(size 0.7 0.7)
					(thickness 0.15)
				)
				(justify left bottom mirror)
			)
		)
		(fp_text user "${REFERENCE}"
			(at -0.95 -3.168 270)
			(layer "B.Fab")
			(effects
				(font
					(size 0.7 0.7)
					(thickness 0.15)
				)
				(justify left bottom mirror)
			)
		)
		(fp_text user "Author: Antmicro"
			(at -0.95 -4.169 270)
			(layer "B.Fab")
			(effects
				(font
					(size 0.7 0.7)
					(thickness 0.15)
				)
				(justify left bottom mirror)
			)
		)
		(pad "1" smd roundrect
			(at -0.48 0 90)
			(size 0.59 0.64)
			(layers "B.Cu" "B.Mask" "B.Paste")
			(roundrect_rratio 0.25)
			(net 79 "/PD and TB DC-DC/AUX.-")
			(pintype "passive")
		)
		(pad "2" smd roundrect
			(at 0.48 0 90)
			(size 0.59 0.64)
			(layers "B.Cu" "B.Mask" "B.Paste")
			(roundrect_rratio 0.25)
			(net 304 "/PD and TB DC-DC/TPS_3V3")
			(pintype "passive")
		)
	)
	(footprint "antmicro-footprints:C_0402_1005Metric"
		(layer "B.Cu")
		(at 157.961866 85.035118 180)
		(descr "Capacitor SMD 0402")
		(tags "capacitor SMD 0402")
		(property "Reference" "C204"
			(at -20.793134 -9.464883 0)
			(layer "B.SilkS")
			(effects
				(font
					(size 0.7 0.7)
					(thickness 0.15)
				)
				(justify mirror)
			)
		)
		(property "Value" "C_1u_25V_0402"
			(at -1.022927 -2.155213 0)
			(layer "B.Fab")
			(effects
				(font
					(size 0.7 0.7)
					(thickness 0.15)
				)
				(justify left bottom mirror)
			)
		)
		(property "Datasheet" "https://www.murata.com/products/productdetail?partno=GRM155R61E105KE11%23"
			(at 0 0 0)
			(layer "B.Fab")
			(hide yes)
			(effects
				(font
					(size 1.27 1.27)
					(thickness 0.15)
				)
				(justify mirror)
			)
		)
		(property "Description" "SMD Multilayer Ceramic Capacitor, 1 µF, 25 V, 0402 [1005 Metric], ± 10%, X5R, GRM Series"
			(at 0 0 0)
			(layer "B.Fab")
			(hide yes)
			(effects
				(font
					(size 1.27 1.27)
					(thickness 0.15)
				)
				(justify mirror)
			)
		)
		(property "MPN" "GRM155R61E105KE11J"
			(at 0 0 180)
			(unlocked yes)
			(layer "B.Fab")
			(hide yes)
			(effects
				(font
					(size 1 1)
					(thickness 0.15)
				)
				(justify mirror)
			)
		)
		(property "Manufacturer" "Murata"
			(at 0 0 180)
			(unlocked yes)
			(layer "B.Fab")
			(hide yes)
			(effects
				(font
					(size 1 1)
					(thickness 0.15)
				)
				(justify mirror)
			)
		)
		(property "License" "Apache-2.0"
			(at 0 0 180)
			(unlocked yes)
			(layer "B.Fab")
			(hide yes)
			(effects
				(font
					(size 1 1)
					(thickness 0.15)
				)
				(justify mirror)
			)
		)
		(property "Author" "Antmicro"
			(at 0 0 180)
			(unlocked yes)
			(layer "B.Fab")
			(hide yes)
			(effects
				(font
					(size 1 1)
					(thickness 0.15)
				)
				(justify mirror)
			)
		)
		(property "Val" "1u"
			(at 0 0 180)
			(unlocked yes)
			(layer "B.Fab")
			(hide yes)
			(effects
				(font
					(size 1 1)
					(thickness 0.15)
				)
				(justify mirror)
			)
		)
		(property "Voltage" "25V"
			(at 0 0 180)
			(unlocked yes)
			(layer "B.Fab")
			(hide yes)
			(effects
				(font
					(size 1 1)
					(thickness 0.15)
				)
				(justify mirror)
			)
		)
		(property "Dielectric" "X5R"
			(at 0 0 180)
			(unlocked yes)
			(layer "B.Fab")
			(hide yes)
			(effects
				(font
					(size 1 1)
					(thickness 0.15)
				)
				(justify mirror)
			)
		)
		(sheetname "/X710-AT2 power/")
		(sheetfile "x710-at2-power.kicad_sch")
		(attr smd)
		(fp_rect
			(start -0.925 0.47)
			(end 0.925 -0.47)
			(stroke
				(width 0.05)
				(type default)
			)
			(fill no)
			(layer "B.CrtYd")
		)
		(fp_line
			(start 0.504 0.25)
			(end 0.504 -0.248)
			(stroke
				(width 0.15)
				(type solid)
			)
			(layer "B.Fab")
		)
		(fp_line
			(start 0.504 -0.248)
			(end -0.494 -0.248)
			(stroke
				(width 0.15)
				(type solid)
			)
			(layer "B.Fab")
		)
		(fp_line
			(start -0.494 0.25)
			(end 0.504 0.25)
			(stroke
				(width 0.15)
				(type solid)
			)
			(layer "B.Fab")
		)
		(fp_line
			(start -0.494 -0.248)
			(end -0.494 0.25)
			(stroke
				(width 0.15)
				(type solid)
			)
			(layer "B.Fab")
		)
		(fp_text user "Author: Antmicro"
			(at -0.939 -3.399 0)
			(layer "B.Fab")
			(effects
				(font
					(size 0.7 0.7)
					(thickness 0.15)
				)
				(justify left bottom mirror)
			)
		)
		(fp_text user "License: Apache-2.0"
			(at -0.939 -5.799 0)
			(layer "B.Fab")
			(effects
				(font
					(size 0.7 0.7)
					(thickness 0.15)
				)
				(justify left bottom mirror)
			)
		)
		(fp_text user "${REFERENCE}"
			(at -0.939 -4.599 0)
			(layer "B.Fab")
			(effects
				(font
					(size 0.7 0.7)
					(thickness 0.15)
				)
				(justify left bottom mirror)
			)
		)
		(pad "1" smd roundrect
			(at -0.48 0 180)
			(size 0.59 0.64)
			(layers "B.Cu" "B.Mask" "B.Paste")
			(roundrect_rratio 0.25)
			(net 23 "GND")
			(pintype "passive")
		)
		(pad "2" smd roundrect
			(at 0.48 0 180)
			(size 0.59 0.64)
			(layers "B.Cu" "B.Mask" "B.Paste")
			(roundrect_rratio 0.25)
			(net 10 "AVDDH")
			(pintype "passive")
		)
	)
	(footprint "antmicro-footprints:R_0402_1005Metric"
		(layer "B.Cu")
		(at 147.531866 69.535117 180)
		(descr "Resistor SMD 0402")
		(tags "resistor SMD 0402")
		(property "Reference" "R160"
			(at -19.068134 -9.464883 0)
			(layer "B.SilkS")
			(effects
				(font
					(size 0.7 0.7)
					(thickness 0.15)
				)
				(justify mirror)
			)
		)
		(property "Value" "R_100R_0402"
			(at -1.011843 -1.772047 0)
			(layer "B.Fab")
			(effects
				(font
					(size 0.7 0.7)
					(thickness 0.15)
				)
				(justify left bottom mirror)
			)
		)
		(property "Datasheet" "https://www.bourns.com/docs/product-datasheets/cr.pdf"
			(at 0 0 0)
			(layer "B.Fab")
			(hide yes)
			(effects
				(font
					(size 1.27 1.27)
					(thickness 0.15)
				)
				(justify mirror)
			)
		)
		(property "Description" "SMD Chip Resistor, 100 ohm, ± 1%, 62.5 mW, 0402 [1005 Metric], Thick Film, General Purpose"
			(at 0 0 0)
			(layer "B.Fab")
			(hide yes)
			(effects
				(font
					(size 1.27 1.27)
					(thickness 0.15)
				)
				(justify mirror)
			)
		)
		(property "MPN" "CR0402-FX-1000GLF"
			(at 0 0 180)
			(unlocked yes)
			(layer "B.Fab")
			(hide yes)
			(effects
				(font
					(size 1 1)
					(thickness 0.15)
				)
				(justify mirror)
			)
		)
		(property "Manufacturer" "Bourns"
			(at 0 0 180)
			(unlocked yes)
			(layer "B.Fab")
			(hide yes)
			(effects
				(font
					(size 1 1)
					(thickness 0.15)
				)
				(justify mirror)
			)
		)
		(property "License" "Apache-2.0"
			(at 0 0 180)
			(unlocked yes)
			(layer "B.Fab")
			(hide yes)
			(effects
				(font
					(size 1 1)
					(thickness 0.15)
				)
				(justify mirror)
			)
		)
		(property "Author" "Antmicro"
			(at 0 0 180)
			(unlocked yes)
			(layer "B.Fab")
			(hide yes)
			(effects
				(font
					(size 1 1)
					(thickness 0.15)
				)
				(justify mirror)
			)
		)
		(property "Val" "100R"
			(at 0 0 180)
			(unlocked yes)
			(layer "B.Fab")
			(hide yes)
			(effects
				(font
					(size 1 1)
					(thickness 0.15)
				)
				(justify mirror)
			)
		)
		(property "Tolerance" "1%"
			(at 0 0 180)
			(unlocked yes)
			(layer "B.Fab")
			(hide yes)
			(effects
				(font
					(size 1 1)
					(thickness 0.15)
				)
				(justify mirror)
			)
		)
		(sheetname "/X710-AT2 Misc/")
		(sheetfile "x710-at2-mics.kicad_sch")
		(attr smd dnp)
		(fp_rect
			(start -0.925 0.47)
			(end 0.925 -0.47)
			(stroke
				(width 0.05)
				(type default)
			)
			(fill no)
			(layer "B.CrtYd")
		)
		(fp_rect
			(start -0.5 0.25)
			(end 0.5 -0.25)
			(stroke
				(width 0.15)
				(type solid)
			)
			(fill no)
			(layer "B.Fab")
		)
		(fp_text user "License: Apache-2.0"
			(at -0.95 -5.169 0)
			(layer "B.Fab")
			(effects
				(font
					(size 0.7 0.7)
					(thickness 0.15)
				)
				(justify left bottom mirror)
			)
		)
		(fp_text user "${REFERENCE}"
			(at -0.95 -3.168 0)
			(layer "B.Fab")
			(effects
				(font
					(size 0.7 0.7)
					(thickness 0.15)
				)
				(justify left bottom mirror)
			)
		)
		(fp_text user "Author: Antmicro"
			(at -0.95 -4.169 0)
			(layer "B.Fab")
			(effects
				(font
					(size 0.7 0.7)
					(thickness 0.15)
				)
				(justify left bottom mirror)
			)
		)
		(pad "1" smd roundrect
			(at -0.48 0 180)
			(size 0.59 0.64)
			(layers "B.Cu" "B.Mask" "B.Paste")
			(roundrect_rratio 0.25)
			(net 23 "GND")
			(pintype "passive")
		)
		(pad "2" smd roundrect
			(at 0.48 0 180)
			(size 0.59 0.64)
			(layers "B.Cu" "B.Mask" "B.Paste")
			(roundrect_rratio 0.25)
			(net 126 "/X710-AT2 Misc/~{PCI_DIS}")
			(pintype "passive")
		)
	)
	(footprint "antmicro-footprints:R_0402_1005Metric"
		(layer "B.Cu")
		(at 140.4 134.6)
		(descr "Resistor SMD 0402")
		(tags "resistor SMD 0402")
		(property "Reference" "R24"
			(at 19.525001 -8.1 180)
			(layer "B.SilkS")
			(effects
				(font
					(size 0.7 0.7)
					(thickness 0.15)
				)
				(justify mirror)
			)
		)
		(property "Value" "R_100k_0402"
			(at -1.011843 -1.772047 180)
			(layer "B.Fab")
			(effects
				(font
					(size 0.7 0.7)
					(thickness 0.15)
				)
				(justify left bottom mirror)
			)
		)
		(property "Datasheet" "https://www.bourns.com/docs/product-datasheets/cr.pdf"
			(at 0 0 180)
			(layer "B.Fab")
			(hide yes)
			(effects
				(font
					(size 1.27 1.27)
					(thickness 0.15)
				)
				(justify mirror)
			)
		)
		(property "Description" "SMD Chip Resistor, 100 kohm, ± 1%, 62.5 mW, 0402 [1005 Metric], Thick Film, General Purpose"
			(at 0 0 180)
			(layer "B.Fab")
			(hide yes)
			(effects
				(font
					(size 1.27 1.27)
					(thickness 0.15)
				)
				(justify mirror)
			)
		)
		(property "MPN" "CR0402-FX-1003GLF"
			(at 0 0 0)
			(unlocked yes)
			(layer "B.Fab")
			(hide yes)
			(effects
				(font
					(size 1 1)
					(thickness 0.15)
				)
				(justify mirror)
			)
		)
		(property "Manufacturer" "Bourns"
			(at 0 0 0)
			(unlocked yes)
			(layer "B.Fab")
			(hide yes)
			(effects
				(font
					(size 1 1)
					(thickness 0.15)
				)
				(justify mirror)
			)
		)
		(property "License" "Apache-2.0"
			(at 0 0 0)
			(unlocked yes)
			(layer "B.Fab")
			(hide yes)
			(effects
				(font
					(size 1 1)
					(thickness 0.15)
				)
				(justify mirror)
			)
		)
		(property "Val" "100k"
			(at 0 0 0)
			(unlocked yes)
			(layer "B.Fab")
			(hide yes)
			(effects
				(font
					(size 1 1)
					(thickness 0.15)
				)
				(justify mirror)
			)
		)
		(property "Tolerance" "1%"
			(at 0 0 0)
			(unlocked yes)
			(layer "B.Fab")
			(hide yes)
			(effects
				(font
					(size 1 1)
					(thickness 0.15)
				)
				(justify mirror)
			)
		)
		(property "Author" "Antmicro"
			(at 0 0 0)
			(unlocked yes)
			(layer "B.Fab")
			(hide yes)
			(effects
				(font
					(size 1 1)
					(thickness 0.15)
				)
				(justify mirror)
			)
		)
		(sheetname "/PD and TB DC-DC/")
		(sheetfile "PD_and_TB_DC_DC.kicad_sch")
		(attr smd)
		(fp_rect
			(start -0.925 0.47)
			(end 0.925 -0.47)
			(stroke
				(width 0.05)
				(type default)
			)
			(fill no)
			(layer "B.CrtYd")
		)
		(fp_rect
			(start -0.5 0.25)
			(end 0.5 -0.25)
			(stroke
				(width 0.15)
				(type solid)
			)
			(fill no)
			(layer "B.Fab")
		)
		(fp_text user "${REFERENCE}"
			(at -0.95 -3.168 180)
			(layer "B.Fab")
			(effects
				(font
					(size 0.7 0.7)
					(thickness 0.15)
				)
				(justify left bottom mirror)
			)
		)
		(fp_text user "Author: Antmicro"
			(at -0.95 -4.169 180)
			(layer "B.Fab")
			(effects
				(font
					(size 0.7 0.7)
					(thickness 0.15)
				)
				(justify left bottom mirror)
			)
		)
		(fp_text user "License: Apache-2.0"
			(at -0.95 -5.169 180)
			(layer "B.Fab")
			(effects
				(font
					(size 0.7 0.7)
					(thickness 0.15)
				)
				(justify left bottom mirror)
			)
		)
		(pad "1" smd roundrect
			(at -0.48 0)
			(size 0.59 0.64)
			(layers "B.Cu" "B.Mask" "B.Paste")
			(roundrect_rratio 0.25)
			(net 207 "Net-(U3-DEBUG_CTL1(GPIO16,_I2CADDR_B4))")
			(pintype "passive")
		)
		(pad "2" smd roundrect
			(at 0.48 0)
			(size 0.59 0.64)
			(layers "B.Cu" "B.Mask" "B.Paste")
			(roundrect_rratio 0.25)
			(net 304 "/PD and TB DC-DC/TPS_3V3")
			(pintype "passive")
		)
	)
	(footprint "antmicro-footprints:C_0402_1005Metric"
		(layer "B.Cu")
		(at 149.58 146.66 -90)
		(descr "Capacitor SMD 0402")
		(tags "capacitor SMD 0402")
		(property "Reference" "C306"
			(at 1.09 -0.42 90)
			(layer "B.SilkS")
			(effects
				(font
					(size 0.7 0.7)
					(thickness 0.15)
				)
				(justify left bottom mirror)
			)
		)
		(property "Value" "C_470p_0402"
			(at -1.022927 -2.155213 90)
			(layer "B.Fab")
			(effects
				(font
					(size 0.7 0.7)
					(thickness 0.15)
				)
				(justify left bottom mirror)
			)
		)
		(property "Datasheet" "https://www.passivecomponent.com/wp-content/uploads/datasheet/WTC_MLCC_General_Purpose.pdf"
			(at 0 0 90)
			(layer "B.Fab")
			(hide yes)
			(effects
				(font
					(size 1.27 1.27)
					(thickness 0.15)
				)
				(justify mirror)
			)
		)
		(property "Description" "SMD Multilayer Ceramic Capacitor, General Purpose, 470 pF, 25 V, 0402 [1005 Metric], ± 10%, X7R"
			(at 0 0 90)
			(layer "B.Fab")
			(hide yes)
			(effects
				(font
					(size 1.27 1.27)
					(thickness 0.15)
				)
				(justify mirror)
			)
		)
		(property "MPN" "0402B471K250CT"
			(at 0 0 270)
			(unlocked yes)
			(layer "B.Fab")
			(hide yes)
			(effects
				(font
					(size 1 1)
					(thickness 0.15)
				)
				(justify mirror)
			)
		)
		(property "Manufacturer" "Walsin"
			(at 0 0 270)
			(unlocked yes)
			(layer "B.Fab")
			(hide yes)
			(effects
				(font
					(size 1 1)
					(thickness 0.15)
				)
				(justify mirror)
			)
		)
		(property "License" "Apache-2.0"
			(at 0 0 270)
			(unlocked yes)
			(layer "B.Fab")
			(hide yes)
			(effects
				(font
					(size 1 1)
					(thickness 0.15)
				)
				(justify mirror)
			)
		)
		(property "Author" "Antmicro"
			(at 0 0 270)
			(unlocked yes)
			(layer "B.Fab")
			(hide yes)
			(effects
				(font
					(size 1 1)
					(thickness 0.15)
				)
				(justify mirror)
			)
		)
		(property "Val" "470p"
			(at 0 0 270)
			(unlocked yes)
			(layer "B.Fab")
			(hide yes)
			(effects
				(font
					(size 1 1)
					(thickness 0.15)
				)
				(justify mirror)
			)
		)
		(property "Voltage" "25V"
			(at 0 0 270)
			(unlocked yes)
			(layer "B.Fab")
			(hide yes)
			(effects
				(font
					(size 1 1)
					(thickness 0.15)
				)
				(justify mirror)
			)
		)
		(property "Dielectric" "X7R"
			(at 0 0 270)
			(unlocked yes)
			(layer "B.Fab")
			(hide yes)
			(effects
				(font
					(size 1 1)
					(thickness 0.15)
				)
				(justify mirror)
			)
		)
		(sheetname "/2xRJ45/")
		(sheetfile "2xrj45.kicad_sch")
		(attr smd)
		(fp_rect
			(start -0.925 0.47)
			(end 0.925 -0.47)
			(stroke
				(width 0.05)
				(type default)
			)
			(fill no)
			(layer "B.CrtYd")
		)
		(fp_line
			(start -0.494 0.25)
			(end 0.504 0.25)
			(stroke
				(width 0.15)
				(type solid)
			)
			(layer "B.Fab")
		)
		(fp_line
			(start 0.504 0.25)
			(end 0.504 -0.248)
			(stroke
				(width 0.15)
				(type solid)
			)
			(layer "B.Fab")
		)
		(fp_line
			(start -0.494 -0.248)
			(end -0.494 0.25)
			(stroke
				(width 0.15)
				(type solid)
			)
			(layer "B.Fab")
		)
		(fp_line
			(start 0.504 -0.248)
			(end -0.494 -0.248)
			(stroke
				(width 0.15)
				(type solid)
			)
			(layer "B.Fab")
		)
		(fp_text user "Author: Antmicro"
			(at -0.939 -3.399 90)
			(layer "B.Fab")
			(effects
				(font
					(size 0.7 0.7)
					(thickness 0.15)
				)
				(justify left bottom mirror)
			)
		)
		(fp_text user "License: Apache-2.0"
			(at -0.939 -5.799 90)
			(layer "B.Fab")
			(effects
				(font
					(size 0.7 0.7)
					(thickness 0.15)
				)
				(justify left bottom mirror)
			)
		)
		(fp_text user "${REFERENCE}"
			(at -0.939 -4.599 90)
			(layer "B.Fab")
			(effects
				(font
					(size 0.7 0.7)
					(thickness 0.15)
				)
				(justify left bottom mirror)
			)
		)
		(pad "1" smd roundrect
			(at -0.48 0 270)
			(size 0.59 0.64)
			(layers "B.Cu" "B.Mask" "B.Paste")
			(roundrect_rratio 0.25)
			(net 23 "GND")
			(pintype "passive")
		)
		(pad "2" smd roundrect
			(at 0.48 0 270)
			(size 0.59 0.64)
			(layers "B.Cu" "B.Mask" "B.Paste")
			(roundrect_rratio 0.25)
			(net 410 "Net-(J3-LED_GRN-)")
			(pintype "passive")
		)
	)
	(footprint "antmicro-footprints:R_0402_1005Metric"
		(layer "B.Cu")
		(at 145.631865 83.260117 180)
		(descr "Resistor SMD 0402")
		(tags "resistor SMD 0402")
		(property "Reference" "R121"
			(at -17.768134 -9.464883 0)
			(layer "B.SilkS")
			(effects
				(font
					(size 0.7 0.7)
					(thickness 0.15)
				)
				(justify mirror)
			)
		)
		(property "Value" "R_100R_0402"
			(at -1.011843 -1.772047 0)
			(layer "B.Fab")
			(effects
				(font
					(size 0.7 0.7)
					(thickness 0.15)
				)
				(justify left bottom mirror)
			)
		)
		(property "Datasheet" "https://www.bourns.com/docs/product-datasheets/cr.pdf"
			(at 0 0 0)
			(layer "B.Fab")
			(hide yes)
			(effects
				(font
					(size 1.27 1.27)
					(thickness 0.15)
				)
				(justify mirror)
			)
		)
		(property "Description" "SMD Chip Resistor, 100 ohm, ± 1%, 62.5 mW, 0402 [1005 Metric], Thick Film, General Purpose"
			(at 0 0 0)
			(layer "B.Fab")
			(hide yes)
			(effects
				(font
					(size 1.27 1.27)
					(thickness 0.15)
				)
				(justify mirror)
			)
		)
		(property "MPN" "CR0402-FX-1000GLF"
			(at 0 0 180)
			(unlocked yes)
			(layer "B.Fab")
			(hide yes)
			(effects
				(font
					(size 1 1)
					(thickness 0.15)
				)
				(justify mirror)
			)
		)
		(property "Manufacturer" "Bourns"
			(at 0 0 180)
			(unlocked yes)
			(layer "B.Fab")
			(hide yes)
			(effects
				(font
					(size 1 1)
					(thickness 0.15)
				)
				(justify mirror)
			)
		)
		(property "License" "Apache-2.0"
			(at 0 0 180)
			(unlocked yes)
			(layer "B.Fab")
			(hide yes)
			(effects
				(font
					(size 1 1)
					(thickness 0.15)
				)
				(justify mirror)
			)
		)
		(property "Author" "Antmicro"
			(at 0 0 180)
			(unlocked yes)
			(layer "B.Fab")
			(hide yes)
			(effects
				(font
					(size 1 1)
					(thickness 0.15)
				)
				(justify mirror)
			)
		)
		(property "Val" "100R"
			(at 0 0 180)
			(unlocked yes)
			(layer "B.Fab")
			(hide yes)
			(effects
				(font
					(size 1 1)
					(thickness 0.15)
				)
				(justify mirror)
			)
		)
		(property "Tolerance" "1%"
			(at 0 0 180)
			(unlocked yes)
			(layer "B.Fab")
			(hide yes)
			(effects
				(font
					(size 1 1)
					(thickness 0.15)
				)
				(justify mirror)
			)
		)
		(sheetname "/X710-AT2 RSVD/")
		(sheetfile "x710-at2-rsvd.kicad_sch")
		(attr smd)
		(fp_rect
			(start -0.925 0.47)
			(end 0.925 -0.47)
			(stroke
				(width 0.05)
				(type default)
			)
			(fill no)
			(layer "B.CrtYd")
		)
		(fp_rect
			(start -0.5 0.25)
			(end 0.5 -0.25)
			(stroke
				(width 0.15)
				(type solid)
			)
			(fill no)
			(layer "B.Fab")
		)
		(fp_text user "License: Apache-2.0"
			(at -0.95 -5.169 0)
			(layer "B.Fab")
			(effects
				(font
					(size 0.7 0.7)
					(thickness 0.15)
				)
				(justify left bottom mirror)
			)
		)
		(fp_text user "${REFERENCE}"
			(at -0.95 -3.168 0)
			(layer "B.Fab")
			(effects
				(font
					(size 0.7 0.7)
					(thickness 0.15)
				)
				(justify left bottom mirror)
			)
		)
		(fp_text user "Author: Antmicro"
			(at -0.95 -4.169 0)
			(layer "B.Fab")
			(effects
				(font
					(size 0.7 0.7)
					(thickness 0.15)
				)
				(justify left bottom mirror)
			)
		)
		(pad "1" smd roundrect
			(at -0.48 0 180)
			(size 0.59 0.64)
			(layers "B.Cu" "B.Mask" "B.Paste")
			(roundrect_rratio 0.25)
			(net 23 "GND")
			(pintype "passive")
		)
		(pad "2" smd roundrect
			(at 0.48 0 180)
			(size 0.59 0.64)
			(layers "B.Cu" "B.Mask" "B.Paste")
			(roundrect_rratio 0.25)
			(net 92 "/X710-AT2 RSVD/RSVDY24_VSS")
			(pintype "passive")
		)
	)
	(footprint "antmicro-footprints:C_0402_1005Metric"
		(layer "B.Cu")
		(at 156.111866 87.085117 180)
		(descr "Capacitor SMD 0402")
		(tags "capacitor SMD 0402")
		(property "Reference" "C184"
			(at -19.873134 -9.464883 0)
			(layer "B.SilkS")
			(effects
				(font
					(size 0.7 0.7)
					(thickness 0.15)
				)
				(justify mirror)
			)
		)
		(property "Value" "C_1u_25V_0402"
			(at -1.022927 -2.155213 0)
			(layer "B.Fab")
			(effects
				(font
					(size 0.7 0.7)
					(thickness 0.15)
				)
				(justify left bottom mirror)
			)
		)
		(property "Datasheet" "https://www.murata.com/products/productdetail?partno=GRM155R61E105KE11%23"
			(at 0 0 0)
			(layer "B.Fab")
			(hide yes)
			(effects
				(font
					(size 1.27 1.27)
					(thickness 0.15)
				)
				(justify mirror)
			)
		)
		(property "Description" "SMD Multilayer Ceramic Capacitor, 1 µF, 25 V, 0402 [1005 Metric], ± 10%, X5R, GRM Series"
			(at 0 0 0)
			(layer "B.Fab")
			(hide yes)
			(effects
				(font
					(size 1.27 1.27)
					(thickness 0.15)
				)
				(justify mirror)
			)
		)
		(property "MPN" "GRM155R61E105KE11J"
			(at 0 0 180)
			(unlocked yes)
			(layer "B.Fab")
			(hide yes)
			(effects
				(font
					(size 1 1)
					(thickness 0.15)
				)
				(justify mirror)
			)
		)
		(property "Manufacturer" "Murata"
			(at 0 0 180)
			(unlocked yes)
			(layer "B.Fab")
			(hide yes)
			(effects
				(font
					(size 1 1)
					(thickness 0.15)
				)
				(justify mirror)
			)
		)
		(property "License" "Apache-2.0"
			(at 0 0 180)
			(unlocked yes)
			(layer "B.Fab")
			(hide yes)
			(effects
				(font
					(size 1 1)
					(thickness 0.15)
				)
				(justify mirror)
			)
		)
		(property "Author" "Antmicro"
			(at 0 0 180)
			(unlocked yes)
			(layer "B.Fab")
			(hide yes)
			(effects
				(font
					(size 1 1)
					(thickness 0.15)
				)
				(justify mirror)
			)
		)
		(property "Val" "1u"
			(at 0 0 180)
			(unlocked yes)
			(layer "B.Fab")
			(hide yes)
			(effects
				(font
					(size 1 1)
					(thickness 0.15)
				)
				(justify mirror)
			)
		)
		(property "Voltage" "25V"
			(at 0 0 180)
			(unlocked yes)
			(layer "B.Fab")
			(hide yes)
			(effects
				(font
					(size 1 1)
					(thickness 0.15)
				)
				(justify mirror)
			)
		)
		(property "Dielectric" "X5R"
			(at 0 0 180)
			(unlocked yes)
			(layer "B.Fab")
			(hide yes)
			(effects
				(font
					(size 1 1)
					(thickness 0.15)
				)
				(justify mirror)
			)
		)
		(sheetname "/X710-AT2 power/")
		(sheetfile "x710-at2-power.kicad_sch")
		(attr smd)
		(fp_rect
			(start -0.925 0.47)
			(end 0.925 -0.47)
			(stroke
				(width 0.05)
				(type default)
			)
			(fill no)
			(layer "B.CrtYd")
		)
		(fp_line
			(start 0.504 0.25)
			(end 0.504 -0.248)
			(stroke
				(width 0.15)
				(type solid)
			)
			(layer "B.Fab")
		)
		(fp_line
			(start 0.504 -0.248)
			(end -0.494 -0.248)
			(stroke
				(width 0.15)
				(type solid)
			)
			(layer "B.Fab")
		)
		(fp_line
			(start -0.494 0.25)
			(end 0.504 0.25)
			(stroke
				(width 0.15)
				(type solid)
			)
			(layer "B.Fab")
		)
		(fp_line
			(start -0.494 -0.248)
			(end -0.494 0.25)
			(stroke
				(width 0.15)
				(type solid)
			)
			(layer "B.Fab")
		)
		(fp_text user "Author: Antmicro"
			(at -0.939 -3.399 0)
			(layer "B.Fab")
			(effects
				(font
					(size 0.7 0.7)
					(thickness 0.15)
				)
				(justify left bottom mirror)
			)
		)
		(fp_text user "License: Apache-2.0"
			(at -0.939 -5.799 0)
			(layer "B.Fab")
			(effects
				(font
					(size 0.7 0.7)
					(thickness 0.15)
				)
				(justify left bottom mirror)
			)
		)
		(fp_text user "${REFERENCE}"
			(at -0.939 -4.599 0)
			(layer "B.Fab")
			(effects
				(font
					(size 0.7 0.7)
					(thickness 0.15)
				)
				(justify left bottom mirror)
			)
		)
		(pad "1" smd roundrect
			(at -0.48 0 180)
			(size 0.59 0.64)
			(layers "B.Cu" "B.Mask" "B.Paste")
			(roundrect_rratio 0.25)
			(net 23 "GND")
			(pintype "passive")
		)
		(pad "2" smd roundrect
			(at 0.48 0 180)
			(size 0.59 0.64)
			(layers "B.Cu" "B.Mask" "B.Paste")
			(roundrect_rratio 0.25)
			(net 6 "DVDD")
			(pintype "passive")
		)
	)
	(footprint "antmicro-footprints:C_0402_1005Metric"
		(layer "B.Cu")
		(at 158.931867 88.815117)
		(descr "Capacitor SMD 0402")
		(tags "capacitor SMD 0402")
		(property "Reference" "C205"
			(at 20.068133 10.984883 180)
			(layer "B.SilkS")
			(effects
				(font
					(size 0.7 0.7)
					(thickness 0.15)
				)
				(justify mirror)
			)
		)
		(property "Value" "C_1u_25V_0402"
			(at -1.022927 -2.155213 180)
			(layer "B.Fab")
			(effects
				(font
					(size 0.7 0.7)
					(thickness 0.15)
				)
				(justify left bottom mirror)
			)
		)
		(property "Datasheet" "https://www.murata.com/products/productdetail?partno=GRM155R61E105KE11%23"
			(at 0 0 180)
			(layer "B.Fab")
			(hide yes)
			(effects
				(font
					(size 1.27 1.27)
					(thickness 0.15)
				)
				(justify mirror)
			)
		)
		(property "Description" "SMD Multilayer Ceramic Capacitor, 1 µF, 25 V, 0402 [1005 Metric], ± 10%, X5R, GRM Series"
			(at 0 0 180)
			(layer "B.Fab")
			(hide yes)
			(effects
				(font
					(size 1.27 1.27)
					(thickness 0.15)
				)
				(justify mirror)
			)
		)
		(property "MPN" "GRM155R61E105KE11J"
			(at 0 0 0)
			(unlocked yes)
			(layer "B.Fab")
			(hide yes)
			(effects
				(font
					(size 1 1)
					(thickness 0.15)
				)
				(justify mirror)
			)
		)
		(property "Manufacturer" "Murata"
			(at 0 0 0)
			(unlocked yes)
			(layer "B.Fab")
			(hide yes)
			(effects
				(font
					(size 1 1)
					(thickness 0.15)
				)
				(justify mirror)
			)
		)
		(property "License" "Apache-2.0"
			(at 0 0 0)
			(unlocked yes)
			(layer "B.Fab")
			(hide yes)
			(effects
				(font
					(size 1 1)
					(thickness 0.15)
				)
				(justify mirror)
			)
		)
		(property "Author" "Antmicro"
			(at 0 0 0)
			(unlocked yes)
			(layer "B.Fab")
			(hide yes)
			(effects
				(font
					(size 1 1)
					(thickness 0.15)
				)
				(justify mirror)
			)
		)
		(property "Val" "1u"
			(at 0 0 0)
			(unlocked yes)
			(layer "B.Fab")
			(hide yes)
			(effects
				(font
					(size 1 1)
					(thickness 0.15)
				)
				(justify mirror)
			)
		)
		(property "Voltage" "25V"
			(at 0 0 0)
			(unlocked yes)
			(layer "B.Fab")
			(hide yes)
			(effects
				(font
					(size 1 1)
					(thickness 0.15)
				)
				(justify mirror)
			)
		)
		(property "Dielectric" "X5R"
			(at 0 0 0)
			(unlocked yes)
			(layer "B.Fab")
			(hide yes)
			(effects
				(font
					(size 1 1)
					(thickness 0.15)
				)
				(justify mirror)
			)
		)
		(sheetname "/X710-AT2 power/")
		(sheetfile "x710-at2-power.kicad_sch")
		(attr smd)
		(fp_rect
			(start -0.925 0.47)
			(end 0.925 -0.47)
			(stroke
				(width 0.05)
				(type default)
			)
			(fill no)
			(layer "B.CrtYd")
		)
		(fp_line
			(start -0.494 -0.248)
			(end -0.494 0.25)
			(stroke
				(width 0.15)
				(type solid)
			)
			(layer "B.Fab")
		)
		(fp_line
			(start -0.494 0.25)
			(end 0.504 0.25)
			(stroke
				(width 0.15)
				(type solid)
			)
			(layer "B.Fab")
		)
		(fp_line
			(start 0.504 -0.248)
			(end -0.494 -0.248)
			(stroke
				(width 0.15)
				(type solid)
			)
			(layer "B.Fab")
		)
		(fp_line
			(start 0.504 0.25)
			(end 0.504 -0.248)
			(stroke
				(width 0.15)
				(type solid)
			)
			(layer "B.Fab")
		)
		(fp_text user "License: Apache-2.0"
			(at -0.939 -5.799 180)
			(layer "B.Fab")
			(effects
				(font
					(size 0.7 0.7)
					(thickness 0.15)
				)
				(justify left bottom mirror)
			)
		)
		(fp_text user "${REFERENCE}"
			(at -0.939 -4.599 180)
			(layer "B.Fab")
			(effects
				(font
					(size 0.7 0.7)
					(thickness 0.15)
				)
				(justify left bottom mirror)
			)
		)
		(fp_text user "Author: Antmicro"
			(at -0.939 -3.399 180)
			(layer "B.Fab")
			(effects
				(font
					(size 0.7 0.7)
					(thickness 0.15)
				)
				(justify left bottom mirror)
			)
		)
		(pad "1" smd roundrect
			(at -0.48 0)
			(size 0.59 0.64)
			(layers "B.Cu" "B.Mask" "B.Paste")
			(roundrect_rratio 0.25)
			(net 23 "GND")
			(pintype "passive")
		)
		(pad "2" smd roundrect
			(at 0.48 0)
			(size 0.59 0.64)
			(layers "B.Cu" "B.Mask" "B.Paste")
			(roundrect_rratio 0.25)
			(net 5 "P0_AVDDL")
			(pintype "passive")
		)
	)
	(footprint "antmicro-footprints:R_0402_1005Metric"
		(layer "B.Cu")
		(at 148.425 84.925 180)
		(descr "Resistor SMD 0402")
		(tags "resistor SMD 0402")
		(property "Reference" "R179"
			(at -17.975 -9.475 0)
			(layer "B.SilkS")
			(effects
				(font
					(size 0.7 0.7)
					(thickness 0.15)
				)
				(justify mirror)
			)
		)
		(property "Value" "R_10k_0402"
			(at -1.011843 -1.772047 0)
			(layer "B.Fab")
			(effects
				(font
					(size 0.7 0.7)
					(thickness 0.15)
				)
				(justify left bottom mirror)
			)
		)
		(property "Datasheet" "https://www.bourns.com/docs/product-datasheets/cr.pdf"
			(at 0 0 0)
			(layer "B.Fab")
			(hide yes)
			(effects
				(font
					(size 1.27 1.27)
					(thickness 0.15)
				)
				(justify mirror)
			)
		)
		(property "Description" "SMD Chip Resistor, 10 kohm, ± 1%, 62.5 mW, 0402 [1005 Metric], Thick Film, General Purpose"
			(at 0 0 0)
			(layer "B.Fab")
			(hide yes)
			(effects
				(font
					(size 1.27 1.27)
					(thickness 0.15)
				)
				(justify mirror)
			)
		)
		(property "MPN" "CR0402-FX-1002GLF"
			(at 0 0 180)
			(unlocked yes)
			(layer "B.Fab")
			(hide yes)
			(effects
				(font
					(size 1 1)
					(thickness 0.15)
				)
				(justify mirror)
			)
		)
		(property "Manufacturer" "Bourns"
			(at 0 0 180)
			(unlocked yes)
			(layer "B.Fab")
			(hide yes)
			(effects
				(font
					(size 1 1)
					(thickness 0.15)
				)
				(justify mirror)
			)
		)
		(property "License" "Apache-2.0"
			(at 0 0 180)
			(unlocked yes)
			(layer "B.Fab")
			(hide yes)
			(effects
				(font
					(size 1 1)
					(thickness 0.15)
				)
				(justify mirror)
			)
		)
		(property "Author" "Antmicro"
			(at 0 0 180)
			(unlocked yes)
			(layer "B.Fab")
			(hide yes)
			(effects
				(font
					(size 1 1)
					(thickness 0.15)
				)
				(justify mirror)
			)
		)
		(property "Val" "10k"
			(at 0 0 180)
			(unlocked yes)
			(layer "B.Fab")
			(hide yes)
			(effects
				(font
					(size 1 1)
					(thickness 0.15)
				)
				(justify mirror)
			)
		)
		(property "Tolerance" "1%"
			(at 0 0 180)
			(unlocked yes)
			(layer "B.Fab")
			(hide yes)
			(effects
				(font
					(size 1 1)
					(thickness 0.15)
				)
				(justify mirror)
			)
		)
		(sheetname "/X710-AT2 Misc/")
		(sheetfile "x710-at2-mics.kicad_sch")
		(attr smd)
		(fp_rect
			(start -0.925 0.47)
			(end 0.925 -0.47)
			(stroke
				(width 0.05)
				(type default)
			)
			(fill no)
			(layer "B.CrtYd")
		)
		(fp_rect
			(start -0.5 0.25)
			(end 0.5 -0.25)
			(stroke
				(width 0.15)
				(type solid)
			)
			(fill no)
			(layer "B.Fab")
		)
		(fp_text user "License: Apache-2.0"
			(at -0.95 -5.169 0)
			(layer "B.Fab")
			(effects
				(font
					(size 0.7 0.7)
					(thickness 0.15)
				)
				(justify left bottom mirror)
			)
		)
		(fp_text user "Author: Antmicro"
			(at -0.95 -4.169 0)
			(layer "B.Fab")
			(effects
				(font
					(size 0.7 0.7)
					(thickness 0.15)
				)
				(justify left bottom mirror)
			)
		)
		(fp_text user "${REFERENCE}"
			(at -0.95 -3.168 0)
			(layer "B.Fab")
			(effects
				(font
					(size 0.7 0.7)
					(thickness 0.15)
				)
				(justify left bottom mirror)
			)
		)
		(pad "1" smd roundrect
			(at -0.48 0 180)
			(size 0.59 0.64)
			(layers "B.Cu" "B.Mask" "B.Paste")
			(roundrect_rratio 0.25)
			(net 444 "Net-(U14D-SMBCLK)")
			(pintype "passive")
		)
		(pad "2" smd roundrect
			(at 0.48 0 180)
			(size 0.59 0.64)
			(layers "B.Cu" "B.Mask" "B.Paste")
			(roundrect_rratio 0.25)
			(net 7 "+3V3")
			(pintype "passive")
		)
	)
	(footprint "antmicro-footprints:TP_SMD_0.75mm"
		(layer "B.Cu")
		(at 140.25 57.75 90)
		(property "Reference" "TP37"
			(at 3.15 0.45 270)
			(layer "B.SilkS")
			(effects
				(font
					(size 0.7 0.7)
					(thickness 0.15)
				)
				(justify left bottom mirror)
			)
		)
		(property "Value" "TP_0.75mm_SMD"
			(at 0 -1.2 270)
			(layer "B.Fab")
			(effects
				(font
					(size 0.7 0.7)
					(thickness 0.15)
				)
				(justify left bottom mirror)
			)
		)
		(property "Description" "SMT test point"
			(at 0 0 270)
			(layer "B.Fab")
			(hide yes)
			(effects
				(font
					(size 1.27 1.27)
					(thickness 0.15)
				)
				(justify mirror)
			)
		)
		(property "MPN" ""
			(at 0 0 90)
			(unlocked yes)
			(layer "B.Fab")
			(hide yes)
			(effects
				(font
					(size 1 1)
					(thickness 0.15)
				)
				(justify mirror)
			)
		)
		(property "Manufacturer" ""
			(at 0 0 90)
			(unlocked yes)
			(layer "B.Fab")
			(hide yes)
			(effects
				(font
					(size 1 1)
					(thickness 0.15)
				)
				(justify mirror)
			)
		)
		(property "Author" "Antmicro"
			(at 0 0 90)
			(unlocked yes)
			(layer "B.Fab")
			(hide yes)
			(effects
				(font
					(size 1 1)
					(thickness 0.15)
				)
				(justify mirror)
			)
		)
		(property "License" "Apache-2.0"
			(at 0 0 90)
			(unlocked yes)
			(layer "B.Fab")
			(hide yes)
			(effects
				(font
					(size 1 1)
					(thickness 0.15)
				)
				(justify mirror)
			)
		)
		(sheetname "/Power input/")
		(sheetfile "power_input.kicad_sch")
		(attr exclude_from_pos_files exclude_from_bom)
		(fp_circle
			(center 0 0)
			(end 0.475 0)
			(stroke
				(width 0.05)
				(type default)
			)
			(fill no)
			(layer "B.CrtYd")
		)
		(fp_text user "Author: Antmicro"
			(at -0.4 -3.901 270)
			(layer "B.Fab")
			(effects
				(font
					(size 0.7 0.7)
					(thickness 0.15)
				)
				(justify left bottom mirror)
			)
		)
		(fp_text user "License: Apache-2.0"
			(at -0.4 -5.101 270)
			(layer "B.Fab")
			(effects
				(font
					(size 0.7 0.7)
					(thickness 0.15)
				)
				(justify left bottom mirror)
			)
		)
		(fp_text user "${REFERENCE}"
			(at -0.4 -2.7 270)
			(layer "B.Fab")
			(effects
				(font
					(size 0.7 0.7)
					(thickness 0.15)
				)
				(justify left bottom mirror)
			)
		)
		(pad "1" smd circle
			(at 0 0 90)
			(size 0.75 0.75)
			(layers "B.Cu" "B.Mask")
			(net 40 "+5V")
			(pinfunction "1")
			(pintype "passive")
		)
	)
	(footprint "antmicro-footprints:TP_SMD_0.75mm"
		(layer "B.Cu")
		(at 151.2 87 180)
		(property "Reference" "TP35"
			(at -17.6 -9.2 270)
			(layer "B.SilkS")
			(effects
				(font
					(size 0.7 0.7)
					(thickness 0.15)
				)
				(justify mirror)
			)
		)
		(property "Value" "TP_0.75mm_SMD"
			(at 0 -1.2 0)
			(layer "B.Fab")
			(effects
				(font
					(size 0.7 0.7)
					(thickness 0.15)
				)
				(justify left bottom mirror)
			)
		)
		(property "Description" "SMT test point"
			(at 0 0 0)
			(layer "B.Fab")
			(hide yes)
			(effects
				(font
					(size 1.27 1.27)
					(thickness 0.15)
				)
				(justify mirror)
			)
		)
		(property "MPN" ""
			(at 0 0 180)
			(unlocked yes)
			(layer "B.Fab")
			(hide yes)
			(effects
				(font
					(size 1 1)
					(thickness 0.15)
				)
				(justify mirror)
			)
		)
		(property "Manufacturer" ""
			(at 0 0 180)
			(unlocked yes)
			(layer "B.Fab")
			(hide yes)
			(effects
				(font
					(size 1 1)
					(thickness 0.15)
				)
				(justify mirror)
			)
		)
		(property "Author" "Antmicro"
			(at 0 0 180)
			(unlocked yes)
			(layer "B.Fab")
			(hide yes)
			(effects
				(font
					(size 1 1)
					(thickness 0.15)
				)
				(justify mirror)
			)
		)
		(property "License" "Apache-2.0"
			(at 0 0 180)
			(unlocked yes)
			(layer "B.Fab")
			(hide yes)
			(effects
				(font
					(size 1 1)
					(thickness 0.15)
				)
				(justify mirror)
			)
		)
		(sheetname "/X710-AT2 Misc/")
		(sheetfile "x710-at2-mics.kicad_sch")
		(attr exclude_from_pos_files exclude_from_bom)
		(fp_circle
			(center 0 0)
			(end 0.475 0)
			(stroke
				(width 0.05)
				(type default)
			)
			(fill no)
			(layer "B.CrtYd")
		)
		(fp_text user "Author: Antmicro"
			(at -0.4 -3.901 0)
			(layer "B.Fab")
			(effects
				(font
					(size 0.7 0.7)
					(thickness 0.15)
				)
				(justify left bottom mirror)
			)
		)
		(fp_text user "License: Apache-2.0"
			(at -0.4 -5.101 0)
			(layer "B.Fab")
			(effects
				(font
					(size 0.7 0.7)
					(thickness 0.15)
				)
				(justify left bottom mirror)
			)
		)
		(fp_text user "${REFERENCE}"
			(at -0.4 -2.7 0)
			(layer "B.Fab")
			(effects
				(font
					(size 0.7 0.7)
					(thickness 0.15)
				)
				(justify left bottom mirror)
			)
		)
		(pad "1" smd circle
			(at 0 0 180)
			(size 0.75 0.75)
			(layers "B.Cu" "B.Mask")
			(net 444 "Net-(U14D-SMBCLK)")
			(pinfunction "1")
			(pintype "passive")
		)
	)
	(footprint "antmicro-footprints:C_0402_1005Metric"
		(layer "B.Cu")
		(at 128.009999 118.61 180)
		(descr "Capacitor SMD 0402")
		(tags "capacitor SMD 0402")
		(property "Reference" "C99"
			(at -21.900002 7.700002 0)
			(layer "B.SilkS")
			(effects
				(font
					(size 0.7 0.7)
					(thickness 0.15)
				)
				(justify mirror)
			)
		)
		(property "Value" "C_100n_0402"
			(at -1.022927 -2.155213 0)
			(layer "B.Fab")
			(effects
				(font
					(size 0.7 0.7)
					(thickness 0.15)
				)
				(justify left bottom mirror)
			)
		)
		(property "Datasheet" "https://www.murata.com/products/productdetail?partno=GRM155R61H104KE14%23"
			(at 0 0 0)
			(layer "B.Fab")
			(hide yes)
			(effects
				(font
					(size 1.27 1.27)
					(thickness 0.15)
				)
				(justify mirror)
			)
		)
		(property "Description" "SMD Multilayer Ceramic Capacitor, 0.1 µF, 50 V, 0402 [1005 Metric], ± 10%, X5R, GRM Series"
			(at 0 0 0)
			(layer "B.Fab")
			(hide yes)
			(effects
				(font
					(size 1.27 1.27)
					(thickness 0.15)
				)
				(justify mirror)
			)
		)
		(property "MPN" "GRM155R61H104KE14D"
			(at 0 0 180)
			(unlocked yes)
			(layer "B.Fab")
			(hide yes)
			(effects
				(font
					(size 1 1)
					(thickness 0.15)
				)
				(justify mirror)
			)
		)
		(property "Manufacturer" "Murata"
			(at 0 0 180)
			(unlocked yes)
			(layer "B.Fab")
			(hide yes)
			(effects
				(font
					(size 1 1)
					(thickness 0.15)
				)
				(justify mirror)
			)
		)
		(property "License" "Apache-2.0"
			(at 0 0 180)
			(unlocked yes)
			(layer "B.Fab")
			(hide yes)
			(effects
				(font
					(size 1 1)
					(thickness 0.15)
				)
				(justify mirror)
			)
		)
		(property "Val" "100n"
			(at 0 0 180)
			(unlocked yes)
			(layer "B.Fab")
			(hide yes)
			(effects
				(font
					(size 1 1)
					(thickness 0.15)
				)
				(justify mirror)
			)
		)
		(property "Voltage" "50V"
			(at 0 0 180)
			(unlocked yes)
			(layer "B.Fab")
			(hide yes)
			(effects
				(font
					(size 1 1)
					(thickness 0.15)
				)
				(justify mirror)
			)
		)
		(property "Dielectric" "X5R"
			(at 0 0 180)
			(unlocked yes)
			(layer "B.Fab")
			(hide yes)
			(effects
				(font
					(size 1 1)
					(thickness 0.15)
				)
				(justify mirror)
			)
		)
		(property "Author" "Antmicro"
			(at 0 0 180)
			(unlocked yes)
			(layer "B.Fab")
			(hide yes)
			(effects
				(font
					(size 1 1)
					(thickness 0.15)
				)
				(justify mirror)
			)
		)
		(sheetname "/TB Controller - Power/")
		(sheetfile "tb-power.kicad_sch")
		(attr smd)
		(fp_rect
			(start -0.925 0.47)
			(end 0.925 -0.47)
			(stroke
				(width 0.05)
				(type default)
			)
			(fill no)
			(layer "B.CrtYd")
		)
		(fp_line
			(start 0.504 0.25)
			(end 0.504 -0.248)
			(stroke
				(width 0.15)
				(type solid)
			)
			(layer "B.Fab")
		)
		(fp_line
			(start 0.504 -0.248)
			(end -0.494 -0.248)
			(stroke
				(width 0.15)
				(type solid)
			)
			(layer "B.Fab")
		)
		(fp_line
			(start -0.494 0.25)
			(end 0.504 0.25)
			(stroke
				(width 0.15)
				(type solid)
			)
			(layer "B.Fab")
		)
		(fp_line
			(start -0.494 -0.248)
			(end -0.494 0.25)
			(stroke
				(width 0.15)
				(type solid)
			)
			(layer "B.Fab")
		)
		(fp_text user "License: Apache-2.0"
			(at -0.939 -5.799 0)
			(layer "B.Fab")
			(effects
				(font
					(size 0.7 0.7)
					(thickness 0.15)
				)
				(justify left bottom mirror)
			)
		)
		(fp_text user "${REFERENCE}"
			(at -0.939 -4.599 0)
			(layer "B.Fab")
			(effects
				(font
					(size 0.7 0.7)
					(thickness 0.15)
				)
				(justify left bottom mirror)
			)
		)
		(fp_text user "Author: Antmicro"
			(at -0.939 -3.399 0)
			(layer "B.Fab")
			(effects
				(font
					(size 0.7 0.7)
					(thickness 0.15)
				)
				(justify left bottom mirror)
			)
		)
		(pad "1" smd roundrect
			(at -0.48 0 180)
			(size 0.59 0.64)
			(layers "B.Cu" "B.Mask" "B.Paste")
			(roundrect_rratio 0.25)
			(net 23 "GND")
			(pintype "passive")
		)
		(pad "2" smd roundrect
			(at 0.48 0 180)
			(size 0.59 0.64)
			(layers "B.Cu" "B.Mask" "B.Paste")
			(roundrect_rratio 0.25)
			(net 57 "+3V3_TB")
			(pintype "passive")
		)
	)
	(footprint "antmicro-footprints:C_0402_1005Metric"
		(layer "B.Cu")
		(at 124.599998 123.950002 -90)
		(descr "Capacitor SMD 0402")
		(tags "capacitor SMD 0402")
		(property "Reference" "C65"
			(at -7.700002 -21.900002 90)
			(layer "B.SilkS")
			(effects
				(font
					(size 0.7 0.7)
					(thickness 0.15)
				)
				(justify mirror)
			)
		)
		(property "Value" "C_1u_0402"
			(at -1.022927 -2.155213 90)
			(layer "B.Fab")
			(effects
				(font
					(size 0.7 0.7)
					(thickness 0.15)
				)
				(justify left bottom mirror)
			)
		)
		(property "Datasheet" "https://product.tdk.com/en/search/capacitor/ceramic/mlcc/info?part_no=C1005X6S1A105K050BC"
			(at 0 0 90)
			(layer "B.Fab")
			(hide yes)
			(effects
				(font
					(size 1.27 1.27)
					(thickness 0.15)
				)
				(justify mirror)
			)
		)
		(property "Description" "SMD Multilayer Ceramic Capacitor, 1 µF, 10 V, 0402 [1005 Metric], ± 10%, X6S, C"
			(at 0 0 90)
			(layer "B.Fab")
			(hide yes)
			(effects
				(font
					(size 1.27 1.27)
					(thickness 0.15)
				)
				(justify mirror)
			)
		)
		(property "MPN" "C1005X6S1A105K050BC"
			(at 0 0 270)
			(unlocked yes)
			(layer "B.Fab")
			(hide yes)
			(effects
				(font
					(size 1 1)
					(thickness 0.15)
				)
				(justify mirror)
			)
		)
		(property "Manufacturer" "TDK"
			(at 0 0 270)
			(unlocked yes)
			(layer "B.Fab")
			(hide yes)
			(effects
				(font
					(size 1 1)
					(thickness 0.15)
				)
				(justify mirror)
			)
		)
		(property "License" "Apache-2.0"
			(at 0 0 270)
			(unlocked yes)
			(layer "B.Fab")
			(hide yes)
			(effects
				(font
					(size 1 1)
					(thickness 0.15)
				)
				(justify mirror)
			)
		)
		(property "Val" "1u"
			(at 0 0 270)
			(unlocked yes)
			(layer "B.Fab")
			(hide yes)
			(effects
				(font
					(size 1 1)
					(thickness 0.15)
				)
				(justify mirror)
			)
		)
		(property "Voltage" ""
			(at 0 0 270)
			(unlocked yes)
			(layer "B.Fab")
			(hide yes)
			(effects
				(font
					(size 1 1)
					(thickness 0.15)
				)
				(justify mirror)
			)
		)
		(property "Dielectric" ""
			(at 0 0 270)
			(unlocked yes)
			(layer "B.Fab")
			(hide yes)
			(effects
				(font
					(size 1 1)
					(thickness 0.15)
				)
				(justify mirror)
			)
		)
		(property "Author" "Antmicro"
			(at 0 0 270)
			(unlocked yes)
			(layer "B.Fab")
			(hide yes)
			(effects
				(font
					(size 1 1)
					(thickness 0.15)
				)
				(justify mirror)
			)
		)
		(sheetname "/TB Controller - Power/")
		(sheetfile "tb-power.kicad_sch")
		(attr smd)
		(fp_rect
			(start -0.925 0.47)
			(end 0.925 -0.47)
			(stroke
				(width 0.05)
				(type default)
			)
			(fill no)
			(layer "B.CrtYd")
		)
		(fp_line
			(start -0.494 0.25)
			(end 0.504 0.25)
			(stroke
				(width 0.15)
				(type solid)
			)
			(layer "B.Fab")
		)
		(fp_line
			(start 0.504 0.25)
			(end 0.504 -0.248)
			(stroke
				(width 0.15)
				(type solid)
			)
			(layer "B.Fab")
		)
		(fp_line
			(start -0.494 -0.248)
			(end -0.494 0.25)
			(stroke
				(width 0.15)
				(type solid)
			)
			(layer "B.Fab")
		)
		(fp_line
			(start 0.504 -0.248)
			(end -0.494 -0.248)
			(stroke
				(width 0.15)
				(type solid)
			)
			(layer "B.Fab")
		)
		(fp_text user "${REFERENCE}"
			(at -0.939 -4.599 90)
			(layer "B.Fab")
			(effects
				(font
					(size 0.7 0.7)
					(thickness 0.15)
				)
				(justify left bottom mirror)
			)
		)
		(fp_text user "Author: Antmicro"
			(at -0.939 -3.399 90)
			(layer "B.Fab")
			(effects
				(font
					(size 0.7 0.7)
					(thickness 0.15)
				)
				(justify left bottom mirror)
			)
		)
		(fp_text user "License: Apache-2.0"
			(at -0.939 -5.799 90)
			(layer "B.Fab")
			(effects
				(font
					(size 0.7 0.7)
					(thickness 0.15)
				)
				(justify left bottom mirror)
			)
		)
		(pad "1" smd roundrect
			(at -0.48 0 270)
			(size 0.59 0.64)
			(layers "B.Cu" "B.Mask" "B.Paste")
			(roundrect_rratio 0.25)
			(net 23 "GND")
			(pintype "passive")
		)
		(pad "2" smd roundrect
			(at 0.48 0 270)
			(size 0.59 0.64)
			(layers "B.Cu" "B.Mask" "B.Paste")
			(roundrect_rratio 0.25)
			(net 403 "Net-(C55-Pad2)")
			(pintype "passive")
		)
	)
	(footprint "antmicro-footprints:C_0402_1005Metric"
		(layer "B.Cu")
		(at 130.45 125.900001 -90)
		(descr "Capacitor SMD 0402")
		(tags "capacitor SMD 0402")
		(property "Reference" "C78"
			(at -7.700002 -21.900002 90)
			(layer "B.SilkS")
			(effects
				(font
					(size 0.7 0.7)
					(thickness 0.15)
				)
				(justify mirror)
			)
		)
		(property "Value" "C_1u_0402"
			(at -1.022927 -2.155213 90)
			(layer "B.Fab")
			(effects
				(font
					(size 0.7 0.7)
					(thickness 0.15)
				)
				(justify left bottom mirror)
			)
		)
		(property "Datasheet" "https://product.tdk.com/en/search/capacitor/ceramic/mlcc/info?part_no=C1005X6S1A105K050BC"
			(at 0 0 90)
			(layer "B.Fab")
			(hide yes)
			(effects
				(font
					(size 1.27 1.27)
					(thickness 0.15)
				)
				(justify mirror)
			)
		)
		(property "Description" "SMD Multilayer Ceramic Capacitor, 1 µF, 10 V, 0402 [1005 Metric], ± 10%, X6S, C"
			(at 0 0 90)
			(layer "B.Fab")
			(hide yes)
			(effects
				(font
					(size 1.27 1.27)
					(thickness 0.15)
				)
				(justify mirror)
			)
		)
		(property "MPN" "C1005X6S1A105K050BC"
			(at 0 0 270)
			(unlocked yes)
			(layer "B.Fab")
			(hide yes)
			(effects
				(font
					(size 1 1)
					(thickness 0.15)
				)
				(justify mirror)
			)
		)
		(property "Manufacturer" "TDK"
			(at 0 0 270)
			(unlocked yes)
			(layer "B.Fab")
			(hide yes)
			(effects
				(font
					(size 1 1)
					(thickness 0.15)
				)
				(justify mirror)
			)
		)
		(property "License" "Apache-2.0"
			(at 0 0 270)
			(unlocked yes)
			(layer "B.Fab")
			(hide yes)
			(effects
				(font
					(size 1 1)
					(thickness 0.15)
				)
				(justify mirror)
			)
		)
		(property "Val" "1u"
			(at 0 0 270)
			(unlocked yes)
			(layer "B.Fab")
			(hide yes)
			(effects
				(font
					(size 1 1)
					(thickness 0.15)
				)
				(justify mirror)
			)
		)
		(property "Voltage" ""
			(at 0 0 270)
			(unlocked yes)
			(layer "B.Fab")
			(hide yes)
			(effects
				(font
					(size 1 1)
					(thickness 0.15)
				)
				(justify mirror)
			)
		)
		(property "Dielectric" ""
			(at 0 0 270)
			(unlocked yes)
			(layer "B.Fab")
			(hide yes)
			(effects
				(font
					(size 1 1)
					(thickness 0.15)
				)
				(justify mirror)
			)
		)
		(property "Author" "Antmicro"
			(at 0 0 270)
			(unlocked yes)
			(layer "B.Fab")
			(hide yes)
			(effects
				(font
					(size 1 1)
					(thickness 0.15)
				)
				(justify mirror)
			)
		)
		(sheetname "/TB Controller - Power/")
		(sheetfile "tb-power.kicad_sch")
		(attr smd)
		(fp_rect
			(start -0.925 0.47)
			(end 0.925 -0.47)
			(stroke
				(width 0.05)
				(type default)
			)
			(fill no)
			(layer "B.CrtYd")
		)
		(fp_line
			(start -0.494 0.25)
			(end 0.504 0.25)
			(stroke
				(width 0.15)
				(type solid)
			)
			(layer "B.Fab")
		)
		(fp_line
			(start 0.504 0.25)
			(end 0.504 -0.248)
			(stroke
				(width 0.15)
				(type solid)
			)
			(layer "B.Fab")
		)
		(fp_line
			(start -0.494 -0.248)
			(end -0.494 0.25)
			(stroke
				(width 0.15)
				(type solid)
			)
			(layer "B.Fab")
		)
		(fp_line
			(start 0.504 -0.248)
			(end -0.494 -0.248)
			(stroke
				(width 0.15)
				(type solid)
			)
			(layer "B.Fab")
		)
		(fp_text user "License: Apache-2.0"
			(at -0.939 -5.799 90)
			(layer "B.Fab")
			(effects
				(font
					(size 0.7 0.7)
					(thickness 0.15)
				)
				(justify left bottom mirror)
			)
		)
		(fp_text user "${REFERENCE}"
			(at -0.939 -4.599 90)
			(layer "B.Fab")
			(effects
				(font
					(size 0.7 0.7)
					(thickness 0.15)
				)
				(justify left bottom mirror)
			)
		)
		(fp_text user "Author: Antmicro"
			(at -0.939 -3.399 90)
			(layer "B.Fab")
			(effects
				(font
					(size 0.7 0.7)
					(thickness 0.15)
				)
				(justify left bottom mirror)
			)
		)
		(pad "1" smd roundrect
			(at -0.48 0 270)
			(size 0.59 0.64)
			(layers "B.Cu" "B.Mask" "B.Paste")
			(roundrect_rratio 0.25)
			(net 23 "GND")
			(pintype "passive")
		)
		(pad "2" smd roundrect
			(at 0.48 0 270)
			(size 0.59 0.64)
			(layers "B.Cu" "B.Mask" "B.Paste")
			(roundrect_rratio 0.25)
			(net 57 "+3V3_TB")
			(pintype "passive")
		)
	)
	(footprint "antmicro-footprints:Tag-Connect_TC2050-IDC-NL_2x5_P1.27mm"
		(layer "B.Cu")
		(at 126.02 89 -90)
		(property "Reference" "J2"
			(at 0.2 -3.38 90)
			(layer "B.SilkS")
			(effects
				(font
					(size 0.7 0.7)
					(thickness 0.15)
				)
				(justify left bottom mirror)
			)
		)
		(property "Value" "Tag-Connect_TC2050-IDC-NL_2x5_P1.27mm"
			(at 0 -4.4 90)
			(layer "B.Fab")
			(effects
				(font
					(size 0.7 0.7)
					(thickness 0.15)
				)
				(justify left bottom mirror)
			)
		)
		(property "Datasheet" "https://www.tag-connect.com/wp-content/uploads/bsk-pdf-manager/TC2050-IDC-NL_Datasheet_8.pdf"
			(at 0 0 90)
			(layer "B.Fab")
			(hide yes)
			(effects
				(font
					(size 1.27 1.27)
					(thickness 0.15)
				)
				(justify mirror)
			)
		)
		(property "Description" "Tag Connect 2x5 1.27mm terminal"
			(at 0 0 90)
			(layer "B.Fab")
			(hide yes)
			(effects
				(font
					(size 1.27 1.27)
					(thickness 0.15)
				)
				(justify mirror)
			)
		)
		(property "MPN" "TC2050-IDC-NL"
			(at 0 0 270)
			(unlocked yes)
			(layer "B.Fab")
			(hide yes)
			(effects
				(font
					(size 1 1)
					(thickness 0.15)
				)
				(justify mirror)
			)
		)
		(property "Manufacturer" "Tag Connect"
			(at 0 0 270)
			(unlocked yes)
			(layer "B.Fab")
			(hide yes)
			(effects
				(font
					(size 1 1)
					(thickness 0.15)
				)
				(justify mirror)
			)
		)
		(property "Author" "Antmicro"
			(at 0 0 270)
			(unlocked yes)
			(layer "B.Fab")
			(hide yes)
			(effects
				(font
					(size 1 1)
					(thickness 0.15)
				)
				(justify mirror)
			)
		)
		(property "License" "Apache-2.0"
			(at 0 0 270)
			(unlocked yes)
			(layer "B.Fab")
			(hide yes)
			(effects
				(font
					(size 1 1)
					(thickness 0.15)
				)
				(justify mirror)
			)
		)
		(sheetname "/X710-AT2 PCIe/")
		(sheetfile "x710-at2-pcie.kicad_sch")
		(attr exclude_from_pos_files exclude_from_bom dnp)
		(fp_line
			(start -2.2 2.05)
			(end 4.7 2.05)
			(stroke
				(width 0.15)
				(type solid)
			)
			(layer "B.SilkS")
		)
		(fp_line
			(start 4.7 2.05)
			(end 5.1 1.7)
			(stroke
				(width 0.15)
				(type solid)
			)
			(layer "B.SilkS")
		)
		(fp_line
			(start 5.1 1.7)
			(end 5.1 -1.7)
			(stroke
				(width 0.15)
				(type solid)
			)
			(layer "B.SilkS")
		)
		(fp_line
			(start -5.08 0.9)
			(end -2.2 2.05)
			(stroke
				(width 0.15)
				(type solid)
			)
			(layer "B.SilkS")
		)
		(fp_line
			(start -5.08 -0.8)
			(end -5.08 0.9)
			(stroke
				(width 0.15)
				(type solid)
			)
			(layer "B.SilkS")
		)
		(fp_line
			(start -3.101 -1.269)
			(end -3.101 -0.4)
			(stroke
				(width 0.15)
				(type solid)
			)
			(layer "B.SilkS")
		)
		(fp_line
			(start -2.3 -2.049)
			(end -5.08 -0.8)
			(stroke
				(width 0.15)
				(type solid)
			)
			(layer "B.SilkS")
		)
		(fp_line
			(start 4.7 -2.049)
			(end 5.1 -1.7)
			(stroke
				(width 0.15)
				(type solid)
			)
			(layer "B.SilkS")
		)
		(fp_line
			(start 4.7 -2.049)
			(end -2.3 -2.049)
			(stroke
				(width 0.15)
				(type solid)
			)
			(layer "B.SilkS")
		)
		(fp_line
			(start -2.3 2.3)
			(end 4.8 2.3)
			(stroke
				(width 0.05)
				(type solid)
			)
			(layer "B.CrtYd")
		)
		(fp_line
			(start 4.8 2.3)
			(end 5.32 1.8)
			(stroke
				(width 0.05)
				(type solid)
			)
			(layer "B.CrtYd")
		)
		(fp_line
			(start 5.32 1.8)
			(end 5.32 -1.8)
			(stroke
				(width 0.05)
				(type solid)
			)
			(layer "B.CrtYd")
		)
		(fp_line
			(start -5.33 1.1)
			(end -2.3 2.3)
			(stroke
				(width 0.05)
				(type solid)
			)
			(layer "B.CrtYd")
		)
		(fp_line
			(start -5.33 -1)
			(end -5.33 1.1)
			(stroke
				(width 0.05)
				(type solid)
			)
			(layer "B.CrtYd")
		)
		(fp_line
			(start -2.4 -2.29)
			(end -5.33 -1)
			(stroke
				(width 0.05)
				(type solid)
			)
			(layer "B.CrtYd")
		)
		(fp_line
			(start 4.8 -2.29)
			(end 5.32 -1.8)
			(stroke
				(width 0.05)
				(type solid)
			)
			(layer "B.CrtYd")
		)
		(fp_line
			(start 4.8 -2.29)
			(end -2.4 -2.29)
			(stroke
				(width 0.05)
				(type solid)
			)
			(layer "B.CrtYd")
		)
		(fp_text user "${REFERENCE}"
			(at -6.223 -6.049 90)
			(layer "B.Fab")
			(effects
				(font
					(size 0.7 0.7)
					(thickness 0.15)
				)
				(justify left bottom mirror)
			)
		)
		(fp_text user "License: Apache-2.0"
			(at -6.223 -8.449 90)
			(layer "B.Fab")
			(effects
				(font
					(size 0.7 0.7)
					(thickness 0.15)
				)
				(justify left bottom mirror)
			)
		)
		(fp_text user "Author: Antmicro"
			(at -6.223 -7.249 90)
			(layer "B.Fab")
			(effects
				(font
					(size 0.7 0.7)
					(thickness 0.15)
				)
				(justify left bottom mirror)
			)
		)
		(pad "" np_thru_hole circle
			(at -3.81 0 270)
			(size 0.9906 0.9906)
			(drill 0.9906)
			(layers "*.Cu" "*.Mask")
		)
		(pad "" np_thru_hole circle
			(at 3.809 -1.015 270)
			(size 0.9906 0.9906)
			(drill 0.9906)
			(layers "*.Cu" "*.Mask")
		)
		(pad "" np_thru_hole circle
			(at 3.809 1.016 270)
			(size 0.9906 0.9906)
			(drill 0.9906)
			(layers "*.Cu" "*.Mask")
		)
		(pad "1" connect circle
			(at -2.54 -0.634 270)
			(size 0.7874 0.7874)
			(layers "B.Cu" "B.Mask")
			(net 423 "unconnected-(J2-Pad1)")
			(pinfunction "3V3")
			(pintype "passive+no_connect")
		)
		(pad "2" connect circle
			(at -1.27 -0.634 270)
			(size 0.7874 0.7874)
			(layers "B.Cu" "B.Mask")
			(net 4 "/X710-AT2 PCIe/PCIe_JTAG.JTMS")
			(pinfunction "JTAG_TMS")
			(pintype "passive")
		)
		(pad "3" connect circle
			(at 0 -0.634 270)
			(size 0.7874 0.7874)
			(layers "B.Cu" "B.Mask")
			(net 23 "GND")
			(pinfunction "GND")
			(pintype "passive")
		)
		(pad "4" connect circle
			(at 1.269 -0.634 270)
			(size 0.7874 0.7874)
			(layers "B.Cu" "B.Mask")
			(net 16 "/X710-AT2 PCIe/PCIe_JTAG.JTCK")
			(pinfunction "JTAG_TCK")
			(pintype "passive")
		)
		(pad "5" connect circle
			(at 2.539 -0.634 270)
			(size 0.7874 0.7874)
			(layers "B.Cu" "B.Mask")
			(net 23 "GND")
			(pinfunction "GND")
			(pintype "passive")
		)
		(pad "6" connect circle
			(at 2.539 0.635 270)
			(size 0.7874 0.7874)
			(layers "B.Cu" "B.Mask")
			(net 8 "/X710-AT2 PCIe/PCIe_JTAG.JTDO")
			(pinfunction "JTAG_TDO")
			(pintype "passive")
		)
		(pad "7" connect circle
			(at 1.269 0.635 270)
			(size 0.7874 0.7874)
			(layers "B.Cu" "B.Mask")
			(net 422 "unconnected-(J2-Pad7)")
			(pinfunction "NC")
			(pintype "no_connect")
		)
		(pad "8" connect circle
			(at 0 0.635 270)
			(size 0.7874 0.7874)
			(layers "B.Cu" "B.Mask")
			(net 11 "/X710-AT2 PCIe/PCIe_JTAG.JTDI")
			(pinfunction "JTAG_TDI")
			(pintype "passive")
		)
		(pad "9" connect circle
			(at -1.27 0.635 270)
			(size 0.7874 0.7874)
			(layers "B.Cu" "B.Mask")
			(net 23 "GND")
			(pinfunction "GND")
			(pintype "passive")
		)
		(pad "10" connect circle
			(at -2.54 0.635 270)
			(size 0.7874 0.7874)
			(layers "B.Cu" "B.Mask")
			(net 15 "/X710-AT2 PCIe/PCIe_JTAG.~{JRST}")
			(pinfunction "JTAG_~{RESET}")
			(pintype "passive")
		)
	)
	(footprint "antmicro-footprints:R_0402_1005Metric"
		(layer "B.Cu")
		(at 153.831866 89.685117 90)
		(descr "Resistor SMD 0402")
		(tags "resistor SMD 0402")
		(property "Reference" "R206"
			(at -9.914883 18.568134 270)
			(layer "B.SilkS")
			(effects
				(font
					(size 0.7 0.7)
					(thickness 0.15)
				)
				(justify mirror)
			)
		)
		(property "Value" "R_4k53_0402"
			(at -1.011843 -1.772047 270)
			(layer "B.Fab")
			(effects
				(font
					(size 0.7 0.7)
					(thickness 0.15)
				)
				(justify left bottom mirror)
			)
		)
		(property "Datasheet" "https://industrial.panasonic.com/cdbs/www-data/pdf/RDM0000/AOA0000C307.pdf"
			(at 0 0 270)
			(layer "B.Fab")
			(hide yes)
			(effects
				(font
					(size 1.27 1.27)
					(thickness 0.15)
				)
				(justify mirror)
			)
		)
		(property "Description" "SMD Chip Resistor, 4.53 kohm, ± 0.1%, 62.5 mW, 0402 [1005 Metric], Automotive AEC-Q200 Thin Film"
			(at 0 0 270)
			(layer "B.Fab")
			(hide yes)
			(effects
				(font
					(size 1.27 1.27)
					(thickness 0.15)
				)
				(justify mirror)
			)
		)
		(property "MPN" "ERA-2AEB4531X"
			(at 0 0 90)
			(unlocked yes)
			(layer "B.Fab")
			(hide yes)
			(effects
				(font
					(size 1 1)
					(thickness 0.15)
				)
				(justify mirror)
			)
		)
		(property "Manufacturer" "Panasonic"
			(at 0 0 90)
			(unlocked yes)
			(layer "B.Fab")
			(hide yes)
			(effects
				(font
					(size 1 1)
					(thickness 0.15)
				)
				(justify mirror)
			)
		)
		(property "License" "Apache-2.0"
			(at 0 0 90)
			(unlocked yes)
			(layer "B.Fab")
			(hide yes)
			(effects
				(font
					(size 1 1)
					(thickness 0.15)
				)
				(justify mirror)
			)
		)
		(property "Author" "Antmicro"
			(at 0 0 90)
			(unlocked yes)
			(layer "B.Fab")
			(hide yes)
			(effects
				(font
					(size 1 1)
					(thickness 0.15)
				)
				(justify mirror)
			)
		)
		(property "Val" "4k53"
			(at 0 0 90)
			(unlocked yes)
			(layer "B.Fab")
			(hide yes)
			(effects
				(font
					(size 1 1)
					(thickness 0.15)
				)
				(justify mirror)
			)
		)
		(property "Tolerance" "0.1%"
			(at 0 0 90)
			(unlocked yes)
			(layer "B.Fab")
			(hide yes)
			(effects
				(font
					(size 1 1)
					(thickness 0.15)
				)
				(justify mirror)
			)
		)
		(sheetname "/X710-AT2 10GbE/")
		(sheetfile "x710-at2-10gbe.kicad_sch")
		(attr smd)
		(fp_rect
			(start -0.925 0.47)
			(end 0.925 -0.47)
			(stroke
				(width 0.05)
				(type default)
			)
			(fill no)
			(layer "B.CrtYd")
		)
		(fp_rect
			(start -0.5 0.25)
			(end 0.5 -0.25)
			(stroke
				(width 0.15)
				(type solid)
			)
			(fill no)
			(layer "B.Fab")
		)
		(fp_text user "License: Apache-2.0"
			(at -0.95 -5.169 270)
			(layer "B.Fab")
			(effects
				(font
					(size 0.7 0.7)
					(thickness 0.15)
				)
				(justify left bottom mirror)
			)
		)
		(fp_text user "${REFERENCE}"
			(at -0.95 -3.168 270)
			(layer "B.Fab")
			(effects
				(font
					(size 0.7 0.7)
					(thickness 0.15)
				)
				(justify left bottom mirror)
			)
		)
		(fp_text user "Author: Antmicro"
			(at -0.95 -4.169 270)
			(layer "B.Fab")
			(effects
				(font
					(size 0.7 0.7)
					(thickness 0.15)
				)
				(justify left bottom mirror)
			)
		)
		(pad "1" smd roundrect
			(at -0.48 0 90)
			(size 0.59 0.64)
			(layers "B.Cu" "B.Mask" "B.Paste")
			(roundrect_rratio 0.25)
			(net 23 "GND")
			(pintype "passive")
		)
		(pad "2" smd roundrect
			(at 0.48 0 90)
			(size 0.59 0.64)
			(layers "B.Cu" "B.Mask" "B.Paste")
			(roundrect_rratio 0.25)
			(net 62 "/X710-AT2 10GbE/RESCAL_RES_P")
			(pintype "passive")
		)
	)
	(footprint "antmicro-footprints:R_0402_1005Metric"
		(layer "B.Cu")
		(at 135.75 140.9 -90)
		(descr "Resistor SMD 0402")
		(tags "resistor SMD 0402")
		(property "Reference" "R31"
			(at -9.557574 -19.525001 90)
			(layer "B.SilkS")
			(effects
				(font
					(size 0.7 0.7)
					(thickness 0.15)
				)
				(justify mirror)
			)
		)
		(property "Value" "R_10k_0402"
			(at -1.011843 -1.772047 90)
			(layer "B.Fab")
			(effects
				(font
					(size 0.7 0.7)
					(thickness 0.15)
				)
				(justify left bottom mirror)
			)
		)
		(property "Datasheet" "https://www.bourns.com/docs/product-datasheets/cr.pdf"
			(at 0 0 90)
			(layer "B.Fab")
			(hide yes)
			(effects
				(font
					(size 1.27 1.27)
					(thickness 0.15)
				)
				(justify mirror)
			)
		)
		(property "Description" "SMD Chip Resistor, 10 kohm, ± 1%, 62.5 mW, 0402 [1005 Metric], Thick Film, General Purpose"
			(at 0 0 90)
			(layer "B.Fab")
			(hide yes)
			(effects
				(font
					(size 1.27 1.27)
					(thickness 0.15)
				)
				(justify mirror)
			)
		)
		(property "MPN" "CR0402-FX-1002GLF"
			(at 0 0 270)
			(unlocked yes)
			(layer "B.Fab")
			(hide yes)
			(effects
				(font
					(size 1 1)
					(thickness 0.15)
				)
				(justify mirror)
			)
		)
		(property "Manufacturer" "Bourns"
			(at 0 0 270)
			(unlocked yes)
			(layer "B.Fab")
			(hide yes)
			(effects
				(font
					(size 1 1)
					(thickness 0.15)
				)
				(justify mirror)
			)
		)
		(property "License" "Apache-2.0"
			(at 0 0 270)
			(unlocked yes)
			(layer "B.Fab")
			(hide yes)
			(effects
				(font
					(size 1 1)
					(thickness 0.15)
				)
				(justify mirror)
			)
		)
		(property "Val" "10k"
			(at 0 0 270)
			(unlocked yes)
			(layer "B.Fab")
			(hide yes)
			(effects
				(font
					(size 1 1)
					(thickness 0.15)
				)
				(justify mirror)
			)
		)
		(property "Tolerance" "1%"
			(at 0 0 270)
			(unlocked yes)
			(layer "B.Fab")
			(hide yes)
			(effects
				(font
					(size 1 1)
					(thickness 0.15)
				)
				(justify mirror)
			)
		)
		(property "Author" "Antmicro"
			(at 0 0 270)
			(unlocked yes)
			(layer "B.Fab")
			(hide yes)
			(effects
				(font
					(size 1 1)
					(thickness 0.15)
				)
				(justify mirror)
			)
		)
		(sheetname "/PD and TB DC-DC/")
		(sheetfile "PD_and_TB_DC_DC.kicad_sch")
		(attr smd)
		(fp_rect
			(start -0.925 0.47)
			(end 0.925 -0.47)
			(stroke
				(width 0.05)
				(type default)
			)
			(fill no)
			(layer "B.CrtYd")
		)
		(fp_rect
			(start -0.5 0.25)
			(end 0.5 -0.25)
			(stroke
				(width 0.15)
				(type solid)
			)
			(fill no)
			(layer "B.Fab")
		)
		(fp_text user "Author: Antmicro"
			(at -0.95 -4.169 90)
			(layer "B.Fab")
			(effects
				(font
					(size 0.7 0.7)
					(thickness 0.15)
				)
				(justify left bottom mirror)
			)
		)
		(fp_text user "License: Apache-2.0"
			(at -0.95 -5.169 90)
			(layer "B.Fab")
			(effects
				(font
					(size 0.7 0.7)
					(thickness 0.15)
				)
				(justify left bottom mirror)
			)
		)
		(fp_text user "${REFERENCE}"
			(at -0.95 -3.168 90)
			(layer "B.Fab")
			(effects
				(font
					(size 0.7 0.7)
					(thickness 0.15)
				)
				(justify left bottom mirror)
			)
		)
		(pad "1" smd roundrect
			(at -0.48 0 270)
			(size 0.59 0.64)
			(layers "B.Cu" "B.Mask" "B.Paste")
			(roundrect_rratio 0.25)
			(net 377 "/PD and TB DC-DC/RESET_N")
			(pintype "passive")
		)
		(pad "2" smd roundrect
			(at 0.48 0 270)
			(size 0.59 0.64)
			(layers "B.Cu" "B.Mask" "B.Paste")
			(roundrect_rratio 0.25)
			(net 304 "/PD and TB DC-DC/TPS_3V3")
			(pintype "passive")
		)
	)
	(footprint "antmicro-footprints:R_0402_1005Metric"
		(layer "B.Cu")
		(at 142.500001 117.15 180)
		(descr "Resistor SMD 0402")
		(tags "resistor SMD 0402")
		(property "Reference" "R64"
			(at -19.75 7.450001 0)
			(layer "B.SilkS")
			(effects
				(font
					(size 0.7 0.7)
					(thickness 0.15)
				)
				(justify mirror)
			)
		)
		(property "Value" "R_10k_0402"
			(at -1.011843 -1.772047 0)
			(layer "B.Fab")
			(effects
				(font
					(size 0.7 0.7)
					(thickness 0.15)
				)
				(justify left bottom mirror)
			)
		)
		(property "Datasheet" "https://www.bourns.com/docs/product-datasheets/cr.pdf"
			(at 0 0 0)
			(layer "B.Fab")
			(hide yes)
			(effects
				(font
					(size 1.27 1.27)
					(thickness 0.15)
				)
				(justify mirror)
			)
		)
		(property "Description" "SMD Chip Resistor, 10 kohm, ± 1%, 62.5 mW, 0402 [1005 Metric], Thick Film, General Purpose"
			(at 0 0 0)
			(layer "B.Fab")
			(hide yes)
			(effects
				(font
					(size 1.27 1.27)
					(thickness 0.15)
				)
				(justify mirror)
			)
		)
		(property "MPN" "CR0402-FX-1002GLF"
			(at 0 0 180)
			(unlocked yes)
			(layer "B.Fab")
			(hide yes)
			(effects
				(font
					(size 1 1)
					(thickness 0.15)
				)
				(justify mirror)
			)
		)
		(property "Manufacturer" "Bourns"
			(at 0 0 180)
			(unlocked yes)
			(layer "B.Fab")
			(hide yes)
			(effects
				(font
					(size 1 1)
					(thickness 0.15)
				)
				(justify mirror)
			)
		)
		(property "License" "Apache-2.0"
			(at 0 0 180)
			(unlocked yes)
			(layer "B.Fab")
			(hide yes)
			(effects
				(font
					(size 1 1)
					(thickness 0.15)
				)
				(justify mirror)
			)
		)
		(property "Val" "10k"
			(at 0 0 180)
			(unlocked yes)
			(layer "B.Fab")
			(hide yes)
			(effects
				(font
					(size 1 1)
					(thickness 0.15)
				)
				(justify mirror)
			)
		)
		(property "Tolerance" "1%"
			(at 0 0 180)
			(unlocked yes)
			(layer "B.Fab")
			(hide yes)
			(effects
				(font
					(size 1 1)
					(thickness 0.15)
				)
				(justify mirror)
			)
		)
		(property "Author" "Antmicro"
			(at 0 0 180)
			(unlocked yes)
			(layer "B.Fab")
			(hide yes)
			(effects
				(font
					(size 1 1)
					(thickness 0.15)
				)
				(justify mirror)
			)
		)
		(sheetname "/TB Controller/")
		(sheetfile "tb.kicad_sch")
		(attr smd)
		(fp_rect
			(start -0.925 0.47)
			(end 0.925 -0.47)
			(stroke
				(width 0.05)
				(type default)
			)
			(fill no)
			(layer "B.CrtYd")
		)
		(fp_rect
			(start -0.5 0.25)
			(end 0.5 -0.25)
			(stroke
				(width 0.15)
				(type solid)
			)
			(fill no)
			(layer "B.Fab")
		)
		(fp_text user "License: Apache-2.0"
			(at -0.95 -5.169 0)
			(layer "B.Fab")
			(effects
				(font
					(size 0.7 0.7)
					(thickness 0.15)
				)
				(justify left bottom mirror)
			)
		)
		(fp_text user "${REFERENCE}"
			(at -0.95 -3.168 0)
			(layer "B.Fab")
			(effects
				(font
					(size 0.7 0.7)
					(thickness 0.15)
				)
				(justify left bottom mirror)
			)
		)
		(fp_text user "Author: Antmicro"
			(at -0.95 -4.169 0)
			(layer "B.Fab")
			(effects
				(font
					(size 0.7 0.7)
					(thickness 0.15)
				)
				(justify left bottom mirror)
			)
		)
		(pad "1" smd roundrect
			(at -0.48 0 180)
			(size 0.59 0.64)
			(layers "B.Cu" "B.Mask" "B.Paste")
			(roundrect_rratio 0.25)
			(net 57 "+3V3_TB")
			(pintype "passive")
		)
		(pad "2" smd roundrect
			(at 0.48 0 180)
			(size 0.59 0.64)
			(layers "B.Cu" "B.Mask" "B.Paste")
			(roundrect_rratio 0.25)
			(net 226 "Net-(U4D-TCK)")
			(pintype "passive")
		)
	)
	(footprint "antmicro-footprints:C_0402_1005Metric"
		(layer "B.Cu")
		(at 144 133.25)
		(descr "Capacitor SMD 0402")
		(tags "capacitor SMD 0402")
		(property "Reference" "C294"
			(at 2 -0.75 180)
			(layer "B.SilkS")
			(effects
				(font
					(size 0.7 0.7)
					(thickness 0.15)
				)
				(justify left bottom mirror)
			)
		)
		(property "Value" "C_1u_25V_0402"
			(at -1.022927 -2.155213 180)
			(layer "B.Fab")
			(effects
				(font
					(size 0.7 0.7)
					(thickness 0.15)
				)
				(justify left bottom mirror)
			)
		)
		(property "Datasheet" "https://www.murata.com/products/productdetail?partno=GRM155R61E105KE11%23"
			(at 0 0 180)
			(layer "B.Fab")
			(hide yes)
			(effects
				(font
					(size 1.27 1.27)
					(thickness 0.15)
				)
				(justify mirror)
			)
		)
		(property "Description" "SMD Multilayer Ceramic Capacitor, 1 µF, 25 V, 0402 [1005 Metric], ± 10%, X5R, GRM Series"
			(at 0 0 180)
			(layer "B.Fab")
			(hide yes)
			(effects
				(font
					(size 1.27 1.27)
					(thickness 0.15)
				)
				(justify mirror)
			)
		)
		(property "MPN" "GRM155R61E105KE11J"
			(at 0 0 0)
			(unlocked yes)
			(layer "B.Fab")
			(hide yes)
			(effects
				(font
					(size 1 1)
					(thickness 0.15)
				)
				(justify mirror)
			)
		)
		(property "Manufacturer" "Murata"
			(at 0 0 0)
			(unlocked yes)
			(layer "B.Fab")
			(hide yes)
			(effects
				(font
					(size 1 1)
					(thickness 0.15)
				)
				(justify mirror)
			)
		)
		(property "License" "Apache-2.0"
			(at 0 0 0)
			(unlocked yes)
			(layer "B.Fab")
			(hide yes)
			(effects
				(font
					(size 1 1)
					(thickness 0.15)
				)
				(justify mirror)
			)
		)
		(property "Author" "Antmicro"
			(at 0 0 0)
			(unlocked yes)
			(layer "B.Fab")
			(hide yes)
			(effects
				(font
					(size 1 1)
					(thickness 0.15)
				)
				(justify mirror)
			)
		)
		(property "Val" "1u"
			(at 0 0 0)
			(unlocked yes)
			(layer "B.Fab")
			(hide yes)
			(effects
				(font
					(size 1 1)
					(thickness 0.15)
				)
				(justify mirror)
			)
		)
		(property "Voltage" "25V"
			(at 0 0 0)
			(unlocked yes)
			(layer "B.Fab")
			(hide yes)
			(effects
				(font
					(size 1 1)
					(thickness 0.15)
				)
				(justify mirror)
			)
		)
		(property "Dielectric" "X5R"
			(at 0 0 0)
			(unlocked yes)
			(layer "B.Fab")
			(hide yes)
			(effects
				(font
					(size 1 1)
					(thickness 0.15)
				)
				(justify mirror)
			)
		)
		(sheetname "/2xRJ45/")
		(sheetfile "2xrj45.kicad_sch")
		(attr smd)
		(fp_rect
			(start -0.925 0.47)
			(end 0.925 -0.47)
			(stroke
				(width 0.05)
				(type default)
			)
			(fill no)
			(layer "B.CrtYd")
		)
		(fp_line
			(start -0.494 -0.248)
			(end -0.494 0.25)
			(stroke
				(width 0.15)
				(type solid)
			)
			(layer "B.Fab")
		)
		(fp_line
			(start -0.494 0.25)
			(end 0.504 0.25)
			(stroke
				(width 0.15)
				(type solid)
			)
			(layer "B.Fab")
		)
		(fp_line
			(start 0.504 -0.248)
			(end -0.494 -0.248)
			(stroke
				(width 0.15)
				(type solid)
			)
			(layer "B.Fab")
		)
		(fp_line
			(start 0.504 0.25)
			(end 0.504 -0.248)
			(stroke
				(width 0.15)
				(type solid)
			)
			(layer "B.Fab")
		)
		(fp_text user "License: Apache-2.0"
			(at -0.939 -5.799 180)
			(layer "B.Fab")
			(effects
				(font
					(size 0.7 0.7)
					(thickness 0.15)
				)
				(justify left bottom mirror)
			)
		)
		(fp_text user "${REFERENCE}"
			(at -0.939 -4.599 180)
			(layer "B.Fab")
			(effects
				(font
					(size 0.7 0.7)
					(thickness 0.15)
				)
				(justify left bottom mirror)
			)
		)
		(fp_text user "Author: Antmicro"
			(at -0.939 -3.399 180)
			(layer "B.Fab")
			(effects
				(font
					(size 0.7 0.7)
					(thickness 0.15)
				)
				(justify left bottom mirror)
			)
		)
		(pad "1" smd roundrect
			(at -0.48 0)
			(size 0.59 0.64)
			(layers "B.Cu" "B.Mask" "B.Paste")
			(roundrect_rratio 0.25)
			(net 23 "GND")
			(pintype "passive")
		)
		(pad "2" smd roundrect
			(at 0.48 0)
			(size 0.59 0.64)
			(layers "B.Cu" "B.Mask" "B.Paste")
			(roundrect_rratio 0.25)
			(net 133 "/2xRJ45/P0_CT")
			(pintype "passive")
		)
	)
	(footprint "antmicro-footprints:R_0402_1005Metric"
		(layer "B.Cu")
		(at 180.8 73)
		(descr "Resistor SMD 0402")
		(tags "resistor SMD 0402")
		(property "Reference" "R85"
			(at 3 0.4 180)
			(layer "B.SilkS")
			(effects
				(font
					(size 0.7 0.7)
					(thickness 0.15)
				)
				(justify left bottom mirror)
			)
		)
		(property "Value" "R_330R_0402"
			(at -1.011843 -1.772047 180)
			(layer "B.Fab")
			(effects
				(font
					(size 0.7 0.7)
					(thickness 0.15)
				)
				(justify left bottom mirror)
			)
		)
		(property "Datasheet" "https://www.bourns.com/docs/product-datasheets/cr.pdf"
			(at 0 0 180)
			(layer "B.Fab")
			(hide yes)
			(effects
				(font
					(size 1.27 1.27)
					(thickness 0.15)
				)
				(justify mirror)
			)
		)
		(property "Description" "SMD Chip Resistor, 330 ohm, ± 1%, 62.5 mW, 0402 [1005 Metric], Thick Film, General Purpose"
			(at 0 0 180)
			(layer "B.Fab")
			(hide yes)
			(effects
				(font
					(size 1.27 1.27)
					(thickness 0.15)
				)
				(justify mirror)
			)
		)
		(property "MPN" "CR0402-FX-3300GLF"
			(at 0 0 0)
			(unlocked yes)
			(layer "B.Fab")
			(hide yes)
			(effects
				(font
					(size 1 1)
					(thickness 0.15)
				)
				(justify mirror)
			)
		)
		(property "Manufacturer" "Bourns"
			(at 0 0 0)
			(unlocked yes)
			(layer "B.Fab")
			(hide yes)
			(effects
				(font
					(size 1 1)
					(thickness 0.15)
				)
				(justify mirror)
			)
		)
		(property "License" "Apache-2.0"
			(at 0 0 0)
			(unlocked yes)
			(layer "B.Fab")
			(hide yes)
			(effects
				(font
					(size 1 1)
					(thickness 0.15)
				)
				(justify mirror)
			)
		)
		(property "Author" "Antmicro"
			(at 0 0 0)
			(unlocked yes)
			(layer "B.Fab")
			(hide yes)
			(effects
				(font
					(size 1 1)
					(thickness 0.15)
				)
				(justify mirror)
			)
		)
		(property "Val" "330R"
			(at 0 0 0)
			(unlocked yes)
			(layer "B.Fab")
			(hide yes)
			(effects
				(font
					(size 1 1)
					(thickness 0.15)
				)
				(justify mirror)
			)
		)
		(property "Tolerance" "1%"
			(at 0 0 0)
			(unlocked yes)
			(layer "B.Fab")
			(hide yes)
			(effects
				(font
					(size 1 1)
					(thickness 0.15)
				)
				(justify mirror)
			)
		)
		(sheetname "/X710 DCDC converters/")
		(sheetfile "DCDC_converters_X710.kicad_sch")
		(attr smd)
		(fp_rect
			(start -0.925 0.47)
			(end 0.925 -0.47)
			(stroke
				(width 0.05)
				(type default)
			)
			(fill no)
			(layer "B.CrtYd")
		)
		(fp_rect
			(start -0.5 0.25)
			(end 0.5 -0.25)
			(stroke
				(width 0.15)
				(type solid)
			)
			(fill no)
			(layer "B.Fab")
		)
		(fp_text user "Author: Antmicro"
			(at -0.95 -4.169 180)
			(layer "B.Fab")
			(effects
				(font
					(size 0.7 0.7)
					(thickness 0.15)
				)
				(justify left bottom mirror)
			)
		)
		(fp_text user "${REFERENCE}"
			(at -0.95 -3.168 180)
			(layer "B.Fab")
			(effects
				(font
					(size 0.7 0.7)
					(thickness 0.15)
				)
				(justify left bottom mirror)
			)
		)
		(fp_text user "License: Apache-2.0"
			(at -0.95 -5.169 180)
			(layer "B.Fab")
			(effects
				(font
					(size 0.7 0.7)
					(thickness 0.15)
				)
				(justify left bottom mirror)
			)
		)
		(pad "1" smd roundrect
			(at -0.48 0)
			(size 0.59 0.64)
			(layers "B.Cu" "B.Mask" "B.Paste")
			(roundrect_rratio 0.25)
			(net 429 "Net-(Q3-C)")
			(pintype "passive")
		)
		(pad "2" smd roundrect
			(at 0.48 0)
			(size 0.59 0.64)
			(layers "B.Cu" "B.Mask" "B.Paste")
			(roundrect_rratio 0.25)
			(net 54 "Net-(D8-C)")
			(pintype "passive")
		)
	)
	(footprint "antmicro-footprints:R_0402_1005Metric"
		(layer "B.Cu")
		(at 140.600002 118.174998)
		(descr "Resistor SMD 0402")
		(tags "resistor SMD 0402")
		(property "Reference" "R38"
			(at 19.525001 -7.450001 180)
			(layer "B.SilkS")
			(effects
				(font
					(size 0.7 0.7)
					(thickness 0.15)
				)
				(justify mirror)
			)
		)
		(property "Value" "R_2k2_0402"
			(at -1.011843 -1.772047 180)
			(layer "B.Fab")
			(effects
				(font
					(size 0.7 0.7)
					(thickness 0.15)
				)
				(justify left bottom mirror)
			)
		)
		(property "Datasheet" "https://www.bourns.com/docs/product-datasheets/cr.pdf"
			(at 0 0 180)
			(layer "B.Fab")
			(hide yes)
			(effects
				(font
					(size 1.27 1.27)
					(thickness 0.15)
				)
				(justify mirror)
			)
		)
		(property "Description" "SMD Chip Resistor, 2.2 kohm, ± 1%, 62.5 mW, 0402 [1005 Metric], Thick Film, General Purpose"
			(at 0 0 180)
			(layer "B.Fab")
			(hide yes)
			(effects
				(font
					(size 1.27 1.27)
					(thickness 0.15)
				)
				(justify mirror)
			)
		)
		(property "MPN" "CR0402-FX-2201GLF"
			(at 0 0 0)
			(unlocked yes)
			(layer "B.Fab")
			(hide yes)
			(effects
				(font
					(size 1 1)
					(thickness 0.15)
				)
				(justify mirror)
			)
		)
		(property "Manufacturer" "Bourns"
			(at 0 0 0)
			(unlocked yes)
			(layer "B.Fab")
			(hide yes)
			(effects
				(font
					(size 1 1)
					(thickness 0.15)
				)
				(justify mirror)
			)
		)
		(property "License" "Apache-2.0"
			(at 0 0 0)
			(unlocked yes)
			(layer "B.Fab")
			(hide yes)
			(effects
				(font
					(size 1 1)
					(thickness 0.15)
				)
				(justify mirror)
			)
		)
		(property "Val" "2k2"
			(at 0 0 0)
			(unlocked yes)
			(layer "B.Fab")
			(hide yes)
			(effects
				(font
					(size 1 1)
					(thickness 0.15)
				)
				(justify mirror)
			)
		)
		(property "Tolerance" "1%"
			(at 0 0 0)
			(unlocked yes)
			(layer "B.Fab")
			(hide yes)
			(effects
				(font
					(size 1 1)
					(thickness 0.15)
				)
				(justify mirror)
			)
		)
		(property "Author" "Antmicro"
			(at 0 0 0)
			(unlocked yes)
			(layer "B.Fab")
			(hide yes)
			(effects
				(font
					(size 1 1)
					(thickness 0.15)
				)
				(justify mirror)
			)
		)
		(sheetname "/TB Controller/")
		(sheetfile "tb.kicad_sch")
		(attr smd)
		(fp_rect
			(start -0.925 0.47)
			(end 0.925 -0.47)
			(stroke
				(width 0.05)
				(type default)
			)
			(fill no)
			(layer "B.CrtYd")
		)
		(fp_rect
			(start -0.5 0.25)
			(end 0.5 -0.25)
			(stroke
				(width 0.15)
				(type solid)
			)
			(fill no)
			(layer "B.Fab")
		)
		(fp_text user "Author: Antmicro"
			(at -0.95 -4.169 180)
			(layer "B.Fab")
			(effects
				(font
					(size 0.7 0.7)
					(thickness 0.15)
				)
				(justify left bottom mirror)
			)
		)
		(fp_text user "License: Apache-2.0"
			(at -0.95 -5.169 180)
			(layer "B.Fab")
			(effects
				(font
					(size 0.7 0.7)
					(thickness 0.15)
				)
				(justify left bottom mirror)
			)
		)
		(fp_text user "${REFERENCE}"
			(at -0.95 -3.168 180)
			(layer "B.Fab")
			(effects
				(font
					(size 0.7 0.7)
					(thickness 0.15)
				)
				(justify left bottom mirror)
			)
		)
		(pad "1" smd roundrect
			(at -0.48 0)
			(size 0.59 0.64)
			(layers "B.Cu" "B.Mask" "B.Paste")
			(roundrect_rratio 0.25)
			(net 23 "GND")
			(pintype "passive")
		)
		(pad "2" smd roundrect
			(at 0.48 0)
			(size 0.59 0.64)
			(layers "B.Cu" "B.Mask" "B.Paste")
			(roundrect_rratio 0.25)
			(net 221 "Net-(U4C-DPSNK1_DDC_CLK)")
			(pintype "passive")
		)
	)
	(footprint "antmicro-footprints:C_0402_1005Metric"
		(layer "B.Cu")
		(at 134.850002 133.1 90)
		(descr "Capacitor SMD 0402")
		(tags "capacitor SMD 0402")
		(property "Reference" "C25"
			(at 8.339997 19.525001 270)
			(layer "B.SilkS")
			(effects
				(font
					(size 0.7 0.7)
					(thickness 0.15)
				)
				(justify mirror)
			)
		)
		(property "Value" "C_10u_0402"
			(at -1.022927 -2.155213 270)
			(layer "B.Fab")
			(effects
				(font
					(size 0.7 0.7)
					(thickness 0.15)
				)
				(justify left bottom mirror)
			)
		)
		(property "Datasheet" "https://www.yageo.com/en/Chart/Download/pdf/CC0402MRX5R5BB106"
			(at 0 0 270)
			(layer "B.Fab")
			(hide yes)
			(effects
				(font
					(size 1.27 1.27)
					(thickness 0.15)
				)
				(justify mirror)
			)
		)
		(property "Description" "SMD Multilayer Ceramic Capacitor, 10 µF, 6.3 V, 0402 [1005 Metric], ± 20%, X5R, CC Series"
			(at 0 0 270)
			(layer "B.Fab")
			(hide yes)
			(effects
				(font
					(size 1.27 1.27)
					(thickness 0.15)
				)
				(justify mirror)
			)
		)
		(property "MPN" "CC0402MRX5R5BB106"
			(at 0 0 90)
			(unlocked yes)
			(layer "B.Fab")
			(hide yes)
			(effects
				(font
					(size 1 1)
					(thickness 0.15)
				)
				(justify mirror)
			)
		)
		(property "Manufacturer" "YAGEO"
			(at 0 0 90)
			(unlocked yes)
			(layer "B.Fab")
			(hide yes)
			(effects
				(font
					(size 1 1)
					(thickness 0.15)
				)
				(justify mirror)
			)
		)
		(property "License" "Apache-2.0"
			(at 0 0 90)
			(unlocked yes)
			(layer "B.Fab")
			(hide yes)
			(effects
				(font
					(size 1 1)
					(thickness 0.15)
				)
				(justify mirror)
			)
		)
		(property "Val" "10u"
			(at 0 0 90)
			(unlocked yes)
			(layer "B.Fab")
			(hide yes)
			(effects
				(font
					(size 1 1)
					(thickness 0.15)
				)
				(justify mirror)
			)
		)
		(property "Voltage" ""
			(at 0 0 90)
			(unlocked yes)
			(layer "B.Fab")
			(hide yes)
			(effects
				(font
					(size 1 1)
					(thickness 0.15)
				)
				(justify mirror)
			)
		)
		(property "Dielectric" ""
			(at 0 0 90)
			(unlocked yes)
			(layer "B.Fab")
			(hide yes)
			(effects
				(font
					(size 1 1)
					(thickness 0.15)
				)
				(justify mirror)
			)
		)
		(property "Author" "Antmicro"
			(at 0 0 90)
			(unlocked yes)
			(layer "B.Fab")
			(hide yes)
			(effects
				(font
					(size 1 1)
					(thickness 0.15)
				)
				(justify mirror)
			)
		)
		(sheetname "/PD and TB DC-DC/")
		(sheetfile "PD_and_TB_DC_DC.kicad_sch")
		(attr smd)
		(fp_rect
			(start -0.925 0.47)
			(end 0.925 -0.47)
			(stroke
				(width 0.05)
				(type default)
			)
			(fill no)
			(layer "B.CrtYd")
		)
		(fp_line
			(start 0.504 -0.248)
			(end -0.494 -0.248)
			(stroke
				(width 0.15)
				(type solid)
			)
			(layer "B.Fab")
		)
		(fp_line
			(start -0.494 -0.248)
			(end -0.494 0.25)
			(stroke
				(width 0.15)
				(type solid)
			)
			(layer "B.Fab")
		)
		(fp_line
			(start 0.504 0.25)
			(end 0.504 -0.248)
			(stroke
				(width 0.15)
				(type solid)
			)
			(layer "B.Fab")
		)
		(fp_line
			(start -0.494 0.25)
			(end 0.504 0.25)
			(stroke
				(width 0.15)
				(type solid)
			)
			(layer "B.Fab")
		)
		(fp_text user "License: Apache-2.0"
			(at -0.939 -5.799 270)
			(layer "B.Fab")
			(effects
				(font
					(size 0.7 0.7)
					(thickness 0.15)
				)
				(justify left bottom mirror)
			)
		)
		(fp_text user "${REFERENCE}"
			(at -0.939 -4.599 270)
			(layer "B.Fab")
			(effects
				(font
					(size 0.7 0.7)
					(thickness 0.15)
				)
				(justify left bottom mirror)
			)
		)
		(fp_text user "Author: Antmicro"
			(at -0.939 -3.399 270)
			(layer "B.Fab")
			(effects
				(font
					(size 0.7 0.7)
					(thickness 0.15)
				)
				(justify left bottom mirror)
			)
		)
		(pad "1" smd roundrect
			(at -0.48 0 90)
			(size 0.59 0.64)
			(layers "B.Cu" "B.Mask" "B.Paste")
			(roundrect_rratio 0.25)
			(net 304 "/PD and TB DC-DC/TPS_3V3")
			(pintype "passive")
		)
		(pad "2" smd roundrect
			(at 0.48 0 90)
			(size 0.59 0.64)
			(layers "B.Cu" "B.Mask" "B.Paste")
			(roundrect_rratio 0.25)
			(net 23 "GND")
			(pintype "passive")
		)
	)
	(footprint "antmicro-footprints:C_0402_1005Metric"
		(layer "B.Cu")
		(at 130.45 123.95 -90)
		(descr "Capacitor SMD 0402")
		(tags "capacitor SMD 0402")
		(property "Reference" "C64"
			(at -7.700002 -21.900002 90)
			(layer "B.SilkS")
			(effects
				(font
					(size 0.7 0.7)
					(thickness 0.15)
				)
				(justify mirror)
			)
		)
		(property "Value" "C_1u_0402"
			(at -1.022927 -2.155213 90)
			(layer "B.Fab")
			(effects
				(font
					(size 0.7 0.7)
					(thickness 0.15)
				)
				(justify left bottom mirror)
			)
		)
		(property "Datasheet" "https://product.tdk.com/en/search/capacitor/ceramic/mlcc/info?part_no=C1005X6S1A105K050BC"
			(at 0 0 90)
			(layer "B.Fab")
			(hide yes)
			(effects
				(font
					(size 1.27 1.27)
					(thickness 0.15)
				)
				(justify mirror)
			)
		)
		(property "Description" "SMD Multilayer Ceramic Capacitor, 1 µF, 10 V, 0402 [1005 Metric], ± 10%, X6S, C"
			(at 0 0 90)
			(layer "B.Fab")
			(hide yes)
			(effects
				(font
					(size 1.27 1.27)
					(thickness 0.15)
				)
				(justify mirror)
			)
		)
		(property "MPN" "C1005X6S1A105K050BC"
			(at 0 0 270)
			(unlocked yes)
			(layer "B.Fab")
			(hide yes)
			(effects
				(font
					(size 1 1)
					(thickness 0.15)
				)
				(justify mirror)
			)
		)
		(property "Manufacturer" "TDK"
			(at 0 0 270)
			(unlocked yes)
			(layer "B.Fab")
			(hide yes)
			(effects
				(font
					(size 1 1)
					(thickness 0.15)
				)
				(justify mirror)
			)
		)
		(property "License" "Apache-2.0"
			(at 0 0 270)
			(unlocked yes)
			(layer "B.Fab")
			(hide yes)
			(effects
				(font
					(size 1 1)
					(thickness 0.15)
				)
				(justify mirror)
			)
		)
		(property "Val" "1u"
			(at 0 0 270)
			(unlocked yes)
			(layer "B.Fab")
			(hide yes)
			(effects
				(font
					(size 1 1)
					(thickness 0.15)
				)
				(justify mirror)
			)
		)
		(property "Voltage" ""
			(at 0 0 270)
			(unlocked yes)
			(layer "B.Fab")
			(hide yes)
			(effects
				(font
					(size 1 1)
					(thickness 0.15)
				)
				(justify mirror)
			)
		)
		(property "Dielectric" ""
			(at 0 0 270)
			(unlocked yes)
			(layer "B.Fab")
			(hide yes)
			(effects
				(font
					(size 1 1)
					(thickness 0.15)
				)
				(justify mirror)
			)
		)
		(property "Author" "Antmicro"
			(at 0 0 270)
			(unlocked yes)
			(layer "B.Fab")
			(hide yes)
			(effects
				(font
					(size 1 1)
					(thickness 0.15)
				)
				(justify mirror)
			)
		)
		(sheetname "/TB Controller - Power/")
		(sheetfile "tb-power.kicad_sch")
		(attr smd)
		(fp_rect
			(start -0.925 0.47)
			(end 0.925 -0.47)
			(stroke
				(width 0.05)
				(type default)
			)
			(fill no)
			(layer "B.CrtYd")
		)
		(fp_line
			(start -0.494 0.25)
			(end 0.504 0.25)
			(stroke
				(width 0.15)
				(type solid)
			)
			(layer "B.Fab")
		)
		(fp_line
			(start 0.504 0.25)
			(end 0.504 -0.248)
			(stroke
				(width 0.15)
				(type solid)
			)
			(layer "B.Fab")
		)
		(fp_line
			(start -0.494 -0.248)
			(end -0.494 0.25)
			(stroke
				(width 0.15)
				(type solid)
			)
			(layer "B.Fab")
		)
		(fp_line
			(start 0.504 -0.248)
			(end -0.494 -0.248)
			(stroke
				(width 0.15)
				(type solid)
			)
			(layer "B.Fab")
		)
		(fp_text user "${REFERENCE}"
			(at -0.939 -4.599 90)
			(layer "B.Fab")
			(effects
				(font
					(size 0.7 0.7)
					(thickness 0.15)
				)
				(justify left bottom mirror)
			)
		)
		(fp_text user "Author: Antmicro"
			(at -0.939 -3.399 90)
			(layer "B.Fab")
			(effects
				(font
					(size 0.7 0.7)
					(thickness 0.15)
				)
				(justify left bottom mirror)
			)
		)
		(fp_text user "License: Apache-2.0"
			(at -0.939 -5.799 90)
			(layer "B.Fab")
			(effects
				(font
					(size 0.7 0.7)
					(thickness 0.15)
				)
				(justify left bottom mirror)
			)
		)
		(pad "1" smd roundrect
			(at -0.48 0 270)
			(size 0.59 0.64)
			(layers "B.Cu" "B.Mask" "B.Paste")
			(roundrect_rratio 0.25)
			(net 23 "GND")
			(pintype "passive")
		)
		(pad "2" smd roundrect
			(at 0.48 0 270)
			(size 0.59 0.64)
			(layers "B.Cu" "B.Mask" "B.Paste")
			(roundrect_rratio 0.25)
			(net 402 "Net-(C52-Pad2)")
			(pintype "passive")
		)
	)
	(footprint "antmicro-footprints:R_0402_1005Metric"
		(layer "B.Cu")
		(at 136.5 119.15)
		(descr "Resistor SMD 0402")
		(tags "resistor SMD 0402")
		(property "Reference" "R60"
			(at 19.525001 -7.450001 180)
			(layer "B.SilkS")
			(effects
				(font
					(size 0.7 0.7)
					(thickness 0.15)
				)
				(justify mirror)
			)
		)
		(property "Value" "R_100k_0402"
			(at -1.011843 -1.772047 180)
			(layer "B.Fab")
			(effects
				(font
					(size 0.7 0.7)
					(thickness 0.15)
				)
				(justify left bottom mirror)
			)
		)
		(property "Datasheet" "https://www.bourns.com/docs/product-datasheets/cr.pdf"
			(at 0 0 180)
			(layer "B.Fab")
			(hide yes)
			(effects
				(font
					(size 1.27 1.27)
					(thickness 0.15)
				)
				(justify mirror)
			)
		)
		(property "Description" "SMD Chip Resistor, 100 kohm, ± 1%, 62.5 mW, 0402 [1005 Metric], Thick Film, General Purpose"
			(at 0 0 180)
			(layer "B.Fab")
			(hide yes)
			(effects
				(font
					(size 1.27 1.27)
					(thickness 0.15)
				)
				(justify mirror)
			)
		)
		(property "MPN" "CR0402-FX-1003GLF"
			(at 0 0 0)
			(unlocked yes)
			(layer "B.Fab")
			(hide yes)
			(effects
				(font
					(size 1 1)
					(thickness 0.15)
				)
				(justify mirror)
			)
		)
		(property "Manufacturer" "Bourns"
			(at 0 0 0)
			(unlocked yes)
			(layer "B.Fab")
			(hide yes)
			(effects
				(font
					(size 1 1)
					(thickness 0.15)
				)
				(justify mirror)
			)
		)
		(property "License" "Apache-2.0"
			(at 0 0 0)
			(unlocked yes)
			(layer "B.Fab")
			(hide yes)
			(effects
				(font
					(size 1 1)
					(thickness 0.15)
				)
				(justify mirror)
			)
		)
		(property "Val" "100k"
			(at 0 0 0)
			(unlocked yes)
			(layer "B.Fab")
			(hide yes)
			(effects
				(font
					(size 1 1)
					(thickness 0.15)
				)
				(justify mirror)
			)
		)
		(property "Tolerance" "1%"
			(at 0 0 0)
			(unlocked yes)
			(layer "B.Fab")
			(hide yes)
			(effects
				(font
					(size 1 1)
					(thickness 0.15)
				)
				(justify mirror)
			)
		)
		(property "Author" "Antmicro"
			(at 0 0 0)
			(unlocked yes)
			(layer "B.Fab")
			(hide yes)
			(effects
				(font
					(size 1 1)
					(thickness 0.15)
				)
				(justify mirror)
			)
		)
		(sheetname "/TB Controller/")
		(sheetfile "tb.kicad_sch")
		(attr smd)
		(fp_rect
			(start -0.925 0.47)
			(end 0.925 -0.47)
			(stroke
				(width 0.05)
				(type default)
			)
			(fill no)
			(layer "B.CrtYd")
		)
		(fp_rect
			(start -0.5 0.25)
			(end 0.5 -0.25)
			(stroke
				(width 0.15)
				(type solid)
			)
			(fill no)
			(layer "B.Fab")
		)
		(fp_text user "License: Apache-2.0"
			(at -0.95 -5.169 180)
			(layer "B.Fab")
			(effects
				(font
					(size 0.7 0.7)
					(thickness 0.15)
				)
				(justify left bottom mirror)
			)
		)
		(fp_text user "${REFERENCE}"
			(at -0.95 -3.168 180)
			(layer "B.Fab")
			(effects
				(font
					(size 0.7 0.7)
					(thickness 0.15)
				)
				(justify left bottom mirror)
			)
		)
		(fp_text user "Author: Antmicro"
			(at -0.95 -4.169 180)
			(layer "B.Fab")
			(effects
				(font
					(size 0.7 0.7)
					(thickness 0.15)
				)
				(justify left bottom mirror)
			)
		)
		(pad "1" smd roundrect
			(at -0.48 0)
			(size 0.59 0.64)
			(layers "B.Cu" "B.Mask" "B.Paste")
			(roundrect_rratio 0.25)
			(net 233 "Net-(U4E-PB_DPSRC_HPD)")
			(pintype "passive")
		)
		(pad "2" smd roundrect
			(at 0.48 0)
			(size 0.59 0.64)
			(layers "B.Cu" "B.Mask" "B.Paste")
			(roundrect_rratio 0.25)
			(net 23 "GND")
			(pintype "passive")
		)
	)
	(footprint "antmicro-footprints:TP_SMD_0.75mm"
		(layer "B.Cu")
		(at 155.881865 78.760117 180)
		(property "Reference" "TP34"
			(at -20.978136 -8.839883 0)
			(layer "B.SilkS")
			(effects
				(font
					(size 0.7 0.7)
					(thickness 0.15)
				)
				(justify mirror)
			)
		)
		(property "Value" "TP_0.75mm_SMD"
			(at 0 -1.2 0)
			(layer "B.Fab")
			(effects
				(font
					(size 0.7 0.7)
					(thickness 0.15)
				)
				(justify left bottom mirror)
			)
		)
		(property "Description" "SMT test point"
			(at 0 0 0)
			(layer "B.Fab")
			(hide yes)
			(effects
				(font
					(size 1.27 1.27)
					(thickness 0.15)
				)
				(justify mirror)
			)
		)
		(property "MPN" ""
			(at 0 0 180)
			(unlocked yes)
			(layer "B.Fab")
			(hide yes)
			(effects
				(font
					(size 1 1)
					(thickness 0.15)
				)
				(justify mirror)
			)
		)
		(property "Manufacturer" ""
			(at 0 0 180)
			(unlocked yes)
			(layer "B.Fab")
			(hide yes)
			(effects
				(font
					(size 1 1)
					(thickness 0.15)
				)
				(justify mirror)
			)
		)
		(property "Author" "Antmicro"
			(at 0 0 180)
			(unlocked yes)
			(layer "B.Fab")
			(hide yes)
			(effects
				(font
					(size 1 1)
					(thickness 0.15)
				)
				(justify mirror)
			)
		)
		(property "License" "Apache-2.0"
			(at 0 0 180)
			(unlocked yes)
			(layer "B.Fab")
			(hide yes)
			(effects
				(font
					(size 1 1)
					(thickness 0.15)
				)
				(justify mirror)
			)
		)
		(sheetname "/X710-AT2 Misc/")
		(sheetfile "x710-at2-mics.kicad_sch")
		(attr exclude_from_pos_files exclude_from_bom)
		(fp_circle
			(center 0 0)
			(end 0.475 0)
			(stroke
				(width 0.05)
				(type default)
			)
			(fill no)
			(layer "B.CrtYd")
		)
		(fp_text user "License: Apache-2.0"
			(at -0.4 -5.101 0)
			(layer "B.Fab")
			(effects
				(font
					(size 0.7 0.7)
					(thickness 0.15)
				)
				(justify left bottom mirror)
			)
		)
		(fp_text user "Author: Antmicro"
			(at -0.4 -3.901 0)
			(layer "B.Fab")
			(effects
				(font
					(size 0.7 0.7)
					(thickness 0.15)
				)
				(justify left bottom mirror)
			)
		)
		(fp_text user "${REFERENCE}"
			(at -0.4 -2.7 0)
			(layer "B.Fab")
			(effects
				(font
					(size 0.7 0.7)
					(thickness 0.15)
				)
				(justify left bottom mirror)
			)
		)
		(pad "1" smd circle
			(at 0 0 180)
			(size 0.75 0.75)
			(layers "B.Cu" "B.Mask")
			(net 107 "/X710-AT2 Misc/PHY_TDO")
			(pinfunction "1")
			(pintype "passive")
		)
	)
	(footprint "antmicro-footprints:C_0402_1005Metric"
		(layer "B.Cu")
		(at 133.840001 135.089997 -90)
		(descr "Capacitor SMD 0402")
		(tags "capacitor SMD 0402")
		(property "Reference" "C19"
			(at -8.339997 -19.525001 90)
			(layer "B.SilkS")
			(effects
				(font
					(size 0.7 0.7)
					(thickness 0.15)
				)
				(justify mirror)
			)
		)
		(property "Value" "C_1u_0402"
			(at -1.022927 -2.155213 90)
			(layer "B.Fab")
			(effects
				(font
					(size 0.7 0.7)
					(thickness 0.15)
				)
				(justify left bottom mirror)
			)
		)
		(property "Datasheet" "https://product.tdk.com/en/search/capacitor/ceramic/mlcc/info?part_no=C1005X6S1A105K050BC"
			(at 0 0 90)
			(layer "B.Fab")
			(hide yes)
			(effects
				(font
					(size 1.27 1.27)
					(thickness 0.15)
				)
				(justify mirror)
			)
		)
		(property "Description" "SMD Multilayer Ceramic Capacitor, 1 µF, 10 V, 0402 [1005 Metric], ± 10%, X6S, C"
			(at 0 0 90)
			(layer "B.Fab")
			(hide yes)
			(effects
				(font
					(size 1.27 1.27)
					(thickness 0.15)
				)
				(justify mirror)
			)
		)
		(property "MPN" "C1005X6S1A105K050BC"
			(at 0 0 270)
			(unlocked yes)
			(layer "B.Fab")
			(hide yes)
			(effects
				(font
					(size 1 1)
					(thickness 0.15)
				)
				(justify mirror)
			)
		)
		(property "Manufacturer" "TDK"
			(at 0 0 270)
			(unlocked yes)
			(layer "B.Fab")
			(hide yes)
			(effects
				(font
					(size 1 1)
					(thickness 0.15)
				)
				(justify mirror)
			)
		)
		(property "License" "Apache-2.0"
			(at 0 0 270)
			(unlocked yes)
			(layer "B.Fab")
			(hide yes)
			(effects
				(font
					(size 1 1)
					(thickness 0.15)
				)
				(justify mirror)
			)
		)
		(property "Val" "1u"
			(at 0 0 270)
			(unlocked yes)
			(layer "B.Fab")
			(hide yes)
			(effects
				(font
					(size 1 1)
					(thickness 0.15)
				)
				(justify mirror)
			)
		)
		(property "Voltage" ""
			(at 0 0 270)
			(unlocked yes)
			(layer "B.Fab")
			(hide yes)
			(effects
				(font
					(size 1 1)
					(thickness 0.15)
				)
				(justify mirror)
			)
		)
		(property "Dielectric" ""
			(at 0 0 270)
			(unlocked yes)
			(layer "B.Fab")
			(hide yes)
			(effects
				(font
					(size 1 1)
					(thickness 0.15)
				)
				(justify mirror)
			)
		)
		(property "Author" "Antmicro"
			(at 0 0 270)
			(unlocked yes)
			(layer "B.Fab")
			(hide yes)
			(effects
				(font
					(size 1 1)
					(thickness 0.15)
				)
				(justify mirror)
			)
		)
		(sheetname "/PD and TB DC-DC/")
		(sheetfile "PD_and_TB_DC_DC.kicad_sch")
		(attr smd)
		(fp_rect
			(start -0.925 0.47)
			(end 0.925 -0.47)
			(stroke
				(width 0.05)
				(type default)
			)
			(fill no)
			(layer "B.CrtYd")
		)
		(fp_line
			(start -0.494 0.25)
			(end 0.504 0.25)
			(stroke
				(width 0.15)
				(type solid)
			)
			(layer "B.Fab")
		)
		(fp_line
			(start 0.504 0.25)
			(end 0.504 -0.248)
			(stroke
				(width 0.15)
				(type solid)
			)
			(layer "B.Fab")
		)
		(fp_line
			(start -0.494 -0.248)
			(end -0.494 0.25)
			(stroke
				(width 0.15)
				(type solid)
			)
			(layer "B.Fab")
		)
		(fp_line
			(start 0.504 -0.248)
			(end -0.494 -0.248)
			(stroke
				(width 0.15)
				(type solid)
			)
			(layer "B.Fab")
		)
		(fp_text user "Author: Antmicro"
			(at -0.939 -3.399 90)
			(layer "B.Fab")
			(effects
				(font
					(size 0.7 0.7)
					(thickness 0.15)
				)
				(justify left bottom mirror)
			)
		)
		(fp_text user "License: Apache-2.0"
			(at -0.939 -5.799 90)
			(layer "B.Fab")
			(effects
				(font
					(size 0.7 0.7)
					(thickness 0.15)
				)
				(justify left bottom mirror)
			)
		)
		(fp_text user "${REFERENCE}"
			(at -0.939 -4.599 90)
			(layer "B.Fab")
			(effects
				(font
					(size 0.7 0.7)
					(thickness 0.15)
				)
				(justify left bottom mirror)
			)
		)
		(pad "1" smd roundrect
			(at -0.48 0 270)
			(size 0.59 0.64)
			(layers "B.Cu" "B.Mask" "B.Paste")
			(roundrect_rratio 0.25)
			(net 171 "Net-(U3-VOUT_3V3)")
			(pintype "passive")
		)
		(pad "2" smd roundrect
			(at 0.48 0 270)
			(size 0.59 0.64)
			(layers "B.Cu" "B.Mask" "B.Paste")
			(roundrect_rratio 0.25)
			(net 23 "GND")
			(pintype "passive")
		)
	)
	(footprint "antmicro-footprints:R_0402_1005Metric"
		(layer "B.Cu")
		(at 136.500002 117.150001)
		(descr "Resistor SMD 0402")
		(tags "resistor SMD 0402")
		(property "Reference" "R45"
			(at 19.525001 -7.450001 180)
			(layer "B.SilkS")
			(effects
				(font
					(size 0.7 0.7)
					(thickness 0.15)
				)
				(justify mirror)
			)
		)
		(property "Value" "R_10k_0402"
			(at -1.011843 -1.772047 180)
			(layer "B.Fab")
			(effects
				(font
					(size 0.7 0.7)
					(thickness 0.15)
				)
				(justify left bottom mirror)
			)
		)
		(property "Datasheet" "https://www.bourns.com/docs/product-datasheets/cr.pdf"
			(at 0 0 180)
			(layer "B.Fab")
			(hide yes)
			(effects
				(font
					(size 1.27 1.27)
					(thickness 0.15)
				)
				(justify mirror)
			)
		)
		(property "Description" "SMD Chip Resistor, 10 kohm, ± 1%, 62.5 mW, 0402 [1005 Metric], Thick Film, General Purpose"
			(at 0 0 180)
			(layer "B.Fab")
			(hide yes)
			(effects
				(font
					(size 1.27 1.27)
					(thickness 0.15)
				)
				(justify mirror)
			)
		)
		(property "MPN" "CR0402-FX-1002GLF"
			(at 0 0 0)
			(unlocked yes)
			(layer "B.Fab")
			(hide yes)
			(effects
				(font
					(size 1 1)
					(thickness 0.15)
				)
				(justify mirror)
			)
		)
		(property "Manufacturer" "Bourns"
			(at 0 0 0)
			(unlocked yes)
			(layer "B.Fab")
			(hide yes)
			(effects
				(font
					(size 1 1)
					(thickness 0.15)
				)
				(justify mirror)
			)
		)
		(property "License" "Apache-2.0"
			(at 0 0 0)
			(unlocked yes)
			(layer "B.Fab")
			(hide yes)
			(effects
				(font
					(size 1 1)
					(thickness 0.15)
				)
				(justify mirror)
			)
		)
		(property "Val" "10k"
			(at 0 0 0)
			(unlocked yes)
			(layer "B.Fab")
			(hide yes)
			(effects
				(font
					(size 1 1)
					(thickness 0.15)
				)
				(justify mirror)
			)
		)
		(property "Tolerance" "1%"
			(at 0 0 0)
			(unlocked yes)
			(layer "B.Fab")
			(hide yes)
			(effects
				(font
					(size 1 1)
					(thickness 0.15)
				)
				(justify mirror)
			)
		)
		(property "Author" "Antmicro"
			(at 0 0 0)
			(unlocked yes)
			(layer "B.Fab")
			(hide yes)
			(effects
				(font
					(size 1 1)
					(thickness 0.15)
				)
				(justify mirror)
			)
		)
		(sheetname "/TB Controller/")
		(sheetfile "tb.kicad_sch")
		(attr smd)
		(fp_rect
			(start -0.925 0.47)
			(end 0.925 -0.47)
			(stroke
				(width 0.05)
				(type default)
			)
			(fill no)
			(layer "B.CrtYd")
		)
		(fp_rect
			(start -0.5 0.25)
			(end 0.5 -0.25)
			(stroke
				(width 0.15)
				(type solid)
			)
			(fill no)
			(layer "B.Fab")
		)
		(fp_text user "${REFERENCE}"
			(at -0.95 -3.168 180)
			(layer "B.Fab")
			(effects
				(font
					(size 0.7 0.7)
					(thickness 0.15)
				)
				(justify left bottom mirror)
			)
		)
		(fp_text user "Author: Antmicro"
			(at -0.95 -4.169 180)
			(layer "B.Fab")
			(effects
				(font
					(size 0.7 0.7)
					(thickness 0.15)
				)
				(justify left bottom mirror)
			)
		)
		(fp_text user "License: Apache-2.0"
			(at -0.95 -5.169 180)
			(layer "B.Fab")
			(effects
				(font
					(size 0.7 0.7)
					(thickness 0.15)
				)
				(justify left bottom mirror)
			)
		)
		(pad "1" smd roundrect
			(at -0.48 0)
			(size 0.59 0.64)
			(layers "B.Cu" "B.Mask" "B.Paste")
			(roundrect_rratio 0.25)
			(net 188 "Net-(U4C-GPIO_5)")
			(pintype "passive")
		)
		(pad "2" smd roundrect
			(at 0.48 0)
			(size 0.59 0.64)
			(layers "B.Cu" "B.Mask" "B.Paste")
			(roundrect_rratio 0.25)
			(net 23 "GND")
			(pintype "passive")
		)
	)
	(footprint "antmicro-footprints:C_0402_1005Metric"
		(layer "B.Cu")
		(at 146 105 90)
		(descr "Capacitor SMD 0402")
		(tags "capacitor SMD 0402")
		(property "Reference" "C153"
			(at 1 1.5 270)
			(layer "B.SilkS")
			(effects
				(font
					(size 0.7 0.7)
					(thickness 0.15)
				)
				(justify left bottom mirror)
			)
		)
		(property "Value" "C_100n_0402"
			(at -1.022927 -2.155213 270)
			(layer "B.Fab")
			(effects
				(font
					(size 0.7 0.7)
					(thickness 0.15)
				)
				(justify left bottom mirror)
			)
		)
		(property "Datasheet" "https://www.murata.com/products/productdetail?partno=GRM155R61H104KE14%23"
			(at 0 0 270)
			(layer "B.Fab")
			(hide yes)
			(effects
				(font
					(size 1.27 1.27)
					(thickness 0.15)
				)
				(justify mirror)
			)
		)
		(property "Description" "SMD Multilayer Ceramic Capacitor, 0.1 µF, 50 V, 0402 [1005 Metric], ± 10%, X5R, GRM Series"
			(at 0 0 270)
			(layer "B.Fab")
			(hide yes)
			(effects
				(font
					(size 1.27 1.27)
					(thickness 0.15)
				)
				(justify mirror)
			)
		)
		(property "MPN" "GRM155R61H104KE14D"
			(at 0 0 90)
			(unlocked yes)
			(layer "B.Fab")
			(hide yes)
			(effects
				(font
					(size 1 1)
					(thickness 0.15)
				)
				(justify mirror)
			)
		)
		(property "Manufacturer" "Murata"
			(at 0 0 90)
			(unlocked yes)
			(layer "B.Fab")
			(hide yes)
			(effects
				(font
					(size 1 1)
					(thickness 0.15)
				)
				(justify mirror)
			)
		)
		(property "License" "Apache-2.0"
			(at 0 0 90)
			(unlocked yes)
			(layer "B.Fab")
			(hide yes)
			(effects
				(font
					(size 1 1)
					(thickness 0.15)
				)
				(justify mirror)
			)
		)
		(property "Author" "Antmicro"
			(at 0 0 90)
			(unlocked yes)
			(layer "B.Fab")
			(hide yes)
			(effects
				(font
					(size 1 1)
					(thickness 0.15)
				)
				(justify mirror)
			)
		)
		(property "Val" "100n"
			(at 0 0 90)
			(unlocked yes)
			(layer "B.Fab")
			(hide yes)
			(effects
				(font
					(size 1 1)
					(thickness 0.15)
				)
				(justify mirror)
			)
		)
		(property "Voltage" "50V"
			(at 0 0 90)
			(unlocked yes)
			(layer "B.Fab")
			(hide yes)
			(effects
				(font
					(size 1 1)
					(thickness 0.15)
				)
				(justify mirror)
			)
		)
		(property "Dielectric" "X5R"
			(at 0 0 90)
			(unlocked yes)
			(layer "B.Fab")
			(hide yes)
			(effects
				(font
					(size 1 1)
					(thickness 0.15)
				)
				(justify mirror)
			)
		)
		(sheetname "/X710 DCDC converters/")
		(sheetfile "DCDC_converters_X710.kicad_sch")
		(attr smd)
		(fp_rect
			(start -0.925 0.47)
			(end 0.925 -0.47)
			(stroke
				(width 0.05)
				(type default)
			)
			(fill no)
			(layer "B.CrtYd")
		)
		(fp_line
			(start 0.504 -0.248)
			(end -0.494 -0.248)
			(stroke
				(width 0.15)
				(type solid)
			)
			(layer "B.Fab")
		)
		(fp_line
			(start -0.494 -0.248)
			(end -0.494 0.25)
			(stroke
				(width 0.15)
				(type solid)
			)
			(layer "B.Fab")
		)
		(fp_line
			(start 0.504 0.25)
			(end 0.504 -0.248)
			(stroke
				(width 0.15)
				(type solid)
			)
			(layer "B.Fab")
		)
		(fp_line
			(start -0.494 0.25)
			(end 0.504 0.25)
			(stroke
				(width 0.15)
				(type solid)
			)
			(layer "B.Fab")
		)
		(fp_text user "License: Apache-2.0"
			(at -0.939 -5.799 270)
			(layer "B.Fab")
			(effects
				(font
					(size 0.7 0.7)
					(thickness 0.15)
				)
				(justify left bottom mirror)
			)
		)
		(fp_text user "Author: Antmicro"
			(at -0.939 -3.399 270)
			(layer "B.Fab")
			(effects
				(font
					(size 0.7 0.7)
					(thickness 0.15)
				)
				(justify left bottom mirror)
			)
		)
		(fp_text user "${REFERENCE}"
			(at -0.939 -4.599 270)
			(layer "B.Fab")
			(effects
				(font
					(size 0.7 0.7)
					(thickness 0.15)
				)
				(justify left bottom mirror)
			)
		)
		(pad "1" smd roundrect
			(at -0.48 0 90)
			(size 0.59 0.64)
			(layers "B.Cu" "B.Mask" "B.Paste")
			(roundrect_rratio 0.25)
			(net 23 "GND")
			(pintype "passive")
		)
		(pad "2" smd roundrect
			(at 0.48 0 90)
			(size 0.59 0.64)
			(layers "B.Cu" "B.Mask" "B.Paste")
			(roundrect_rratio 0.25)
			(net 341 "/X710 DCDC converters/+DVDD_OUT")
			(pintype "passive")
		)
	)
	(footprint "antmicro-footprints:R_0402_1005Metric"
		(layer "B.Cu")
		(at 180.8 71.5)
		(descr "Resistor SMD 0402")
		(tags "resistor SMD 0402")
		(property "Reference" "R84"
			(at 3 0.4 180)
			(layer "B.SilkS")
			(effects
				(font
					(size 0.7 0.7)
					(thickness 0.15)
				)
				(justify left bottom mirror)
			)
		)
		(property "Value" "R_330R_0402"
			(at -1.011843 -1.772047 180)
			(layer "B.Fab")
			(effects
				(font
					(size 0.7 0.7)
					(thickness 0.15)
				)
				(justify left bottom mirror)
			)
		)
		(property "Datasheet" "https://www.bourns.com/docs/product-datasheets/cr.pdf"
			(at 0 0 180)
			(layer "B.Fab")
			(hide yes)
			(effects
				(font
					(size 1.27 1.27)
					(thickness 0.15)
				)
				(justify mirror)
			)
		)
		(property "Description" "SMD Chip Resistor, 330 ohm, ± 1%, 62.5 mW, 0402 [1005 Metric], Thick Film, General Purpose"
			(at 0 0 180)
			(layer "B.Fab")
			(hide yes)
			(effects
				(font
					(size 1.27 1.27)
					(thickness 0.15)
				)
				(justify mirror)
			)
		)
		(property "MPN" "CR0402-FX-3300GLF"
			(at 0 0 0)
			(unlocked yes)
			(layer "B.Fab")
			(hide yes)
			(effects
				(font
					(size 1 1)
					(thickness 0.15)
				)
				(justify mirror)
			)
		)
		(property "Manufacturer" "Bourns"
			(at 0 0 0)
			(unlocked yes)
			(layer "B.Fab")
			(hide yes)
			(effects
				(font
					(size 1 1)
					(thickness 0.15)
				)
				(justify mirror)
			)
		)
		(property "License" "Apache-2.0"
			(at 0 0 0)
			(unlocked yes)
			(layer "B.Fab")
			(hide yes)
			(effects
				(font
					(size 1 1)
					(thickness 0.15)
				)
				(justify mirror)
			)
		)
		(property "Author" "Antmicro"
			(at 0 0 0)
			(unlocked yes)
			(layer "B.Fab")
			(hide yes)
			(effects
				(font
					(size 1 1)
					(thickness 0.15)
				)
				(justify mirror)
			)
		)
		(property "Val" "330R"
			(at 0 0 0)
			(unlocked yes)
			(layer "B.Fab")
			(hide yes)
			(effects
				(font
					(size 1 1)
					(thickness 0.15)
				)
				(justify mirror)
			)
		)
		(property "Tolerance" "1%"
			(at 0 0 0)
			(unlocked yes)
			(layer "B.Fab")
			(hide yes)
			(effects
				(font
					(size 1 1)
					(thickness 0.15)
				)
				(justify mirror)
			)
		)
		(sheetname "/X710 DCDC converters/")
		(sheetfile "DCDC_converters_X710.kicad_sch")
		(attr smd)
		(fp_rect
			(start -0.925 0.47)
			(end 0.925 -0.47)
			(stroke
				(width 0.05)
				(type default)
			)
			(fill no)
			(layer "B.CrtYd")
		)
		(fp_rect
			(start -0.5 0.25)
			(end 0.5 -0.25)
			(stroke
				(width 0.15)
				(type solid)
			)
			(fill no)
			(layer "B.Fab")
		)
		(fp_text user "Author: Antmicro"
			(at -0.95 -4.169 180)
			(layer "B.Fab")
			(effects
				(font
					(size 0.7 0.7)
					(thickness 0.15)
				)
				(justify left bottom mirror)
			)
		)
		(fp_text user "${REFERENCE}"
			(at -0.95 -3.168 180)
			(layer "B.Fab")
			(effects
				(font
					(size 0.7 0.7)
					(thickness 0.15)
				)
				(justify left bottom mirror)
			)
		)
		(fp_text user "License: Apache-2.0"
			(at -0.95 -5.169 180)
			(layer "B.Fab")
			(effects
				(font
					(size 0.7 0.7)
					(thickness 0.15)
				)
				(justify left bottom mirror)
			)
		)
		(pad "1" smd roundrect
			(at -0.48 0)
			(size 0.59 0.64)
			(layers "B.Cu" "B.Mask" "B.Paste")
			(roundrect_rratio 0.25)
			(net 428 "Net-(Q2-C)")
			(pintype "passive")
		)
		(pad "2" smd roundrect
			(at 0.48 0)
			(size 0.59 0.64)
			(layers "B.Cu" "B.Mask" "B.Paste")
			(roundrect_rratio 0.25)
			(net 415 "Net-(D7-C)")
			(pintype "passive")
		)
	)
	(footprint "antmicro-footprints:SOT-416"
		(layer "B.Cu")
		(at 178.5 68 -90)
		(descr "SOT-416")
		(tags "SOT-416")
		(property "Reference" "Q2"
			(at -0.75 1.3 90)
			(layer "B.SilkS")
			(effects
				(font
					(size 0.7 0.7)
					(thickness 0.15)
				)
				(justify left bottom mirror)
			)
		)
		(property "Value" "DTC014T_SOT-416"
			(at 0 -2 90)
			(layer "B.Fab")
			(effects
				(font
					(size 0.7 0.7)
					(thickness 0.15)
				)
				(justify left bottom mirror)
			)
		)
		(property "Datasheet" "https://www.rohm.com/datasheet?p=DTC014TEB&dist=Mouser&media=referral&source=mouser.com&campaign=Mouser"
			(at 0 0 90)
			(layer "B.Fab")
			(hide yes)
			(effects
				(font
					(size 1.27 1.27)
					(thickness 0.15)
				)
				(justify mirror)
			)
		)
		(property "Description" "Bipolar (BJT) Single Transistor with built-in base resistor, NPN, 50V, 100mA, 150mW, SOT-416FL, Surface Mount"
			(at 0 0 90)
			(layer "B.Fab")
			(hide yes)
			(effects
				(font
					(size 1.27 1.27)
					(thickness 0.15)
				)
				(justify mirror)
			)
		)
		(property "Manufacturer" "ROHM Semiconductor"
			(at 0 0 270)
			(unlocked yes)
			(layer "B.Fab")
			(hide yes)
			(effects
				(font
					(size 1 1)
					(thickness 0.15)
				)
				(justify mirror)
			)
		)
		(property "MPN" "DTC014TEBTL"
			(at 0 0 270)
			(unlocked yes)
			(layer "B.Fab")
			(hide yes)
			(effects
				(font
					(size 1 1)
					(thickness 0.15)
				)
				(justify mirror)
			)
		)
		(property "Author" "Antmicro"
			(at 0 0 270)
			(unlocked yes)
			(layer "B.Fab")
			(hide yes)
			(effects
				(font
					(size 1 1)
					(thickness 0.15)
				)
				(justify mirror)
			)
		)
		(property "License" "Apache-2.0"
			(at 0 0 270)
			(unlocked yes)
			(layer "B.Fab")
			(hide yes)
			(effects
				(font
					(size 1 1)
					(thickness 0.15)
				)
				(justify mirror)
			)
		)
		(sheetname "/X710 DCDC converters/")
		(sheetfile "DCDC_converters_X710.kicad_sch")
		(attr smd)
		(fp_line
			(start 0.508 0.9)
			(end -0.5 0.9)
			(stroke
				(width 0.15)
				(type solid)
			)
			(layer "B.SilkS")
		)
		(fp_line
			(start 0.508 0.9)
			(end 0.508 0.592)
			(stroke
				(width 0.15)
				(type solid)
			)
			(layer "B.SilkS")
		)
		(fp_line
			(start -0.5 0.15)
			(end -0.5 -0.15)
			(stroke
				(width 0.15)
				(type solid)
			)
			(layer "B.SilkS")
		)
		(fp_line
			(start 0.5 -0.9)
			(end 0.5 -0.7)
			(stroke
				(width 0.15)
				(type solid)
			)
			(layer "B.SilkS")
		)
		(fp_line
			(start 0.5 -0.9)
			(end -0.5 -0.9)
			(stroke
				(width 0.15)
				(type solid)
			)
			(layer "B.SilkS")
		)
		(fp_rect
			(start -1 1.05)
			(end 1 -1.05)
			(stroke
				(width 0.05)
				(type solid)
			)
			(fill no)
			(layer "B.CrtYd")
		)
		(fp_line
			(start -0.05 0.9)
			(end -0.45 0.5)
			(stroke
				(width 0.15)
				(type solid)
			)
			(layer "B.Fab")
		)
		(fp_rect
			(start 0.45 -0.9)
			(end -0.45 0.9)
			(stroke
				(width 0.15)
				(type solid)
			)
			(fill no)
			(layer "B.Fab")
		)
		(fp_text user "Author: Antmicro"
			(at -1 -4.602 90)
			(layer "B.Fab")
			(effects
				(font
					(size 0.7 0.7)
					(thickness 0.15)
				)
				(justify left bottom mirror)
			)
		)
		(fp_text user "${REFERENCE}"
			(at -1 -3.4 90)
			(layer "B.Fab")
			(effects
				(font
					(size 0.7 0.7)
					(thickness 0.15)
				)
				(justify left bottom mirror)
			)
		)
		(fp_text user "License: Apache-2.0"
			(at -1 -5.802 90)
			(layer "B.Fab")
			(effects
				(font
					(size 0.7 0.7)
					(thickness 0.15)
				)
				(justify left bottom mirror)
			)
		)
		(pad "1" smd rect
			(at -0.652 0.5 270)
			(size 0.6 0.5)
			(layers "B.Cu" "B.Mask" "B.Paste")
			(net 335 "/X710 DCDC converters/+VCCD_OUT")
			(pinfunction "B")
			(pintype "input")
		)
		(pad "2" smd rect
			(at -0.652 -0.498 270)
			(size 0.6 0.5)
			(layers "B.Cu" "B.Mask" "B.Paste")
			(net 23 "GND")
			(pinfunction "E")
			(pintype "passive")
		)
		(pad "3" smd rect
			(at 0.65 0 270)
			(size 0.6 0.5)
			(layers "B.Cu" "B.Mask" "B.Paste")
			(net 428 "Net-(Q2-C)")
			(pinfunction "C")
			(pintype "passive")
		)
	)
	(footprint "antmicro-footprints:R_0402_1005Metric"
		(layer "B.Cu")
		(at 119.5 89.75 90)
		(descr "Resistor SMD 0402")
		(tags "resistor SMD 0402")
		(property "Reference" "R77"
			(at -5.85 0.3 270)
			(layer "B.SilkS")
			(effects
				(font
					(size 0.7 0.7)
					(thickness 0.15)
				)
				(justify left bottom mirror)
			)
		)
		(property "Value" "R_1k_0402"
			(at -1.011843 -1.772047 270)
			(layer "B.Fab")
			(effects
				(font
					(size 0.7 0.7)
					(thickness 0.15)
				)
				(justify left bottom mirror)
			)
		)
		(property "Datasheet" "https://www.bourns.com/docs/product-datasheets/cr.pdf"
			(at 0 0 270)
			(layer "B.Fab")
			(hide yes)
			(effects
				(font
					(size 1.27 1.27)
					(thickness 0.15)
				)
				(justify mirror)
			)
		)
		(property "Description" "SMD Chip Resistor, 1 kohm, ± 1%, 63 mW, 0402 [1005 Metric], Thick Film, General Purpose"
			(at 0 0 270)
			(layer "B.Fab")
			(hide yes)
			(effects
				(font
					(size 1.27 1.27)
					(thickness 0.15)
				)
				(justify mirror)
			)
		)
		(property "MPN" "CR0402-FX-1001GLF"
			(at 0 0 90)
			(unlocked yes)
			(layer "B.Fab")
			(hide yes)
			(effects
				(font
					(size 1 1)
					(thickness 0.15)
				)
				(justify mirror)
			)
		)
		(property "Manufacturer" "Bourns"
			(at 0 0 90)
			(unlocked yes)
			(layer "B.Fab")
			(hide yes)
			(effects
				(font
					(size 1 1)
					(thickness 0.15)
				)
				(justify mirror)
			)
		)
		(property "License" "Apache-2.0"
			(at 0 0 90)
			(unlocked yes)
			(layer "B.Fab")
			(hide yes)
			(effects
				(font
					(size 1 1)
					(thickness 0.15)
				)
				(justify mirror)
			)
		)
		(property "Author" "Antmicro"
			(at 0 0 90)
			(unlocked yes)
			(layer "B.Fab")
			(hide yes)
			(effects
				(font
					(size 1 1)
					(thickness 0.15)
				)
				(justify mirror)
			)
		)
		(property "Val" "1k"
			(at 0 0 90)
			(unlocked yes)
			(layer "B.Fab")
			(hide yes)
			(effects
				(font
					(size 1 1)
					(thickness 0.15)
				)
				(justify mirror)
			)
		)
		(property "Tolerance" "1%"
			(at 0 0 90)
			(unlocked yes)
			(layer "B.Fab")
			(hide yes)
			(effects
				(font
					(size 1 1)
					(thickness 0.15)
				)
				(justify mirror)
			)
		)
		(sheetname "/TB Controller - Power/")
		(sheetfile "tb-power.kicad_sch")
		(attr smd)
		(fp_rect
			(start -0.925 0.47)
			(end 0.925 -0.47)
			(stroke
				(width 0.05)
				(type default)
			)
			(fill no)
			(layer "B.CrtYd")
		)
		(fp_rect
			(start -0.5 0.25)
			(end 0.5 -0.25)
			(stroke
				(width 0.15)
				(type solid)
			)
			(fill no)
			(layer "B.Fab")
		)
		(fp_text user "Author: Antmicro"
			(at -0.95 -4.169 270)
			(layer "B.Fab")
			(effects
				(font
					(size 0.7 0.7)
					(thickness 0.15)
				)
				(justify left bottom mirror)
			)
		)
		(fp_text user "${REFERENCE}"
			(at -0.95 -3.168 270)
			(layer "B.Fab")
			(effects
				(font
					(size 0.7 0.7)
					(thickness 0.15)
				)
				(justify left bottom mirror)
			)
		)
		(fp_text user "License: Apache-2.0"
			(at -0.95 -5.169 270)
			(layer "B.Fab")
			(effects
				(font
					(size 0.7 0.7)
					(thickness 0.15)
				)
				(justify left bottom mirror)
			)
		)
		(pad "1" smd roundrect
			(at -0.48 0 90)
			(size 0.59 0.64)
			(layers "B.Cu" "B.Mask" "B.Paste")
			(roundrect_rratio 0.25)
			(net 436 "Net-(R77-Pad1)")
			(pintype "passive")
		)
		(pad "2" smd roundrect
			(at 0.48 0 90)
			(size 0.59 0.64)
			(layers "B.Cu" "B.Mask" "B.Paste")
			(roundrect_rratio 0.25)
			(net 68 "/TB Controller - Power/VCC_0P9")
			(pintype "passive")
		)
	)
	(footprint "antmicro-footprints:C_0402_1005Metric"
		(layer "B.Cu")
		(at 154.9 105 90)
		(descr "Capacitor SMD 0402")
		(tags "capacitor SMD 0402")
		(property "Reference" "C151"
			(at 1.4 -0.6 270)
			(layer "B.SilkS")
			(effects
				(font
					(size 0.7 0.7)
					(thickness 0.15)
				)
				(justify left bottom mirror)
			)
		)
		(property "Value" "C_100n_0402"
			(at -1.022927 -2.155213 270)
			(layer "B.Fab")
			(effects
				(font
					(size 0.7 0.7)
					(thickness 0.15)
				)
				(justify left bottom mirror)
			)
		)
		(property "Datasheet" "https://www.murata.com/products/productdetail?partno=GRM155R61H104KE14%23"
			(at 0 0 270)
			(layer "B.Fab")
			(hide yes)
			(effects
				(font
					(size 1.27 1.27)
					(thickness 0.15)
				)
				(justify mirror)
			)
		)
		(property "Description" "SMD Multilayer Ceramic Capacitor, 0.1 µF, 50 V, 0402 [1005 Metric], ± 10%, X5R, GRM Series"
			(at 0 0 270)
			(layer "B.Fab")
			(hide yes)
			(effects
				(font
					(size 1.27 1.27)
					(thickness 0.15)
				)
				(justify mirror)
			)
		)
		(property "MPN" "GRM155R61H104KE14D"
			(at 0 0 90)
			(unlocked yes)
			(layer "B.Fab")
			(hide yes)
			(effects
				(font
					(size 1 1)
					(thickness 0.15)
				)
				(justify mirror)
			)
		)
		(property "Manufacturer" "Murata"
			(at 0 0 90)
			(unlocked yes)
			(layer "B.Fab")
			(hide yes)
			(effects
				(font
					(size 1 1)
					(thickness 0.15)
				)
				(justify mirror)
			)
		)
		(property "License" "Apache-2.0"
			(at 0 0 90)
			(unlocked yes)
			(layer "B.Fab")
			(hide yes)
			(effects
				(font
					(size 1 1)
					(thickness 0.15)
				)
				(justify mirror)
			)
		)
		(property "Author" "Antmicro"
			(at 0 0 90)
			(unlocked yes)
			(layer "B.Fab")
			(hide yes)
			(effects
				(font
					(size 1 1)
					(thickness 0.15)
				)
				(justify mirror)
			)
		)
		(property "Val" "100n"
			(at 0 0 90)
			(unlocked yes)
			(layer "B.Fab")
			(hide yes)
			(effects
				(font
					(size 1 1)
					(thickness 0.15)
				)
				(justify mirror)
			)
		)
		(property "Voltage" "50V"
			(at 0 0 90)
			(unlocked yes)
			(layer "B.Fab")
			(hide yes)
			(effects
				(font
					(size 1 1)
					(thickness 0.15)
				)
				(justify mirror)
			)
		)
		(property "Dielectric" "X5R"
			(at 0 0 90)
			(unlocked yes)
			(layer "B.Fab")
			(hide yes)
			(effects
				(font
					(size 1 1)
					(thickness 0.15)
				)
				(justify mirror)
			)
		)
		(sheetname "/X710 DCDC converters/")
		(sheetfile "DCDC_converters_X710.kicad_sch")
		(attr smd)
		(fp_rect
			(start -0.925 0.47)
			(end 0.925 -0.47)
			(stroke
				(width 0.05)
				(type default)
			)
			(fill no)
			(layer "B.CrtYd")
		)
		(fp_line
			(start 0.504 -0.248)
			(end -0.494 -0.248)
			(stroke
				(width 0.15)
				(type solid)
			)
			(layer "B.Fab")
		)
		(fp_line
			(start -0.494 -0.248)
			(end -0.494 0.25)
			(stroke
				(width 0.15)
				(type solid)
			)
			(layer "B.Fab")
		)
		(fp_line
			(start 0.504 0.25)
			(end 0.504 -0.248)
			(stroke
				(width 0.15)
				(type solid)
			)
			(layer "B.Fab")
		)
		(fp_line
			(start -0.494 0.25)
			(end 0.504 0.25)
			(stroke
				(width 0.15)
				(type solid)
			)
			(layer "B.Fab")
		)
		(fp_text user "License: Apache-2.0"
			(at -0.939 -5.799 270)
			(layer "B.Fab")
			(effects
				(font
					(size 0.7 0.7)
					(thickness 0.15)
				)
				(justify left bottom mirror)
			)
		)
		(fp_text user "Author: Antmicro"
			(at -0.939 -3.399 270)
			(layer "B.Fab")
			(effects
				(font
					(size 0.7 0.7)
					(thickness 0.15)
				)
				(justify left bottom mirror)
			)
		)
		(fp_text user "${REFERENCE}"
			(at -0.939 -4.599 270)
			(layer "B.Fab")
			(effects
				(font
					(size 0.7 0.7)
					(thickness 0.15)
				)
				(justify left bottom mirror)
			)
		)
		(pad "1" smd roundrect
			(at -0.48 0 90)
			(size 0.59 0.64)
			(layers "B.Cu" "B.Mask" "B.Paste")
			(roundrect_rratio 0.25)
			(net 23 "GND")
			(pintype "passive")
		)
		(pad "2" smd roundrect
			(at 0.48 0 90)
			(size 0.59 0.64)
			(layers "B.Cu" "B.Mask" "B.Paste")
			(roundrect_rratio 0.25)
			(net 338 "/X710 DCDC converters/+1V88_OUT")
			(pintype "passive")
		)
	)
	(footprint "antmicro-footprints:C_0402_1005Metric"
		(layer "B.Cu")
		(at 160.05 133.25 180)
		(descr "Capacitor SMD 0402")
		(tags "capacitor SMD 0402")
		(property "Reference" "C300"
			(at -1.45 -1.35 0)
			(layer "B.SilkS")
			(effects
				(font
					(size 0.7 0.7)
					(thickness 0.15)
				)
				(justify left bottom mirror)
			)
		)
		(property "Value" "C_1u_25V_0402"
			(at -1.022927 -2.155213 0)
			(layer "B.Fab")
			(effects
				(font
					(size 0.7 0.7)
					(thickness 0.15)
				)
				(justify left bottom mirror)
			)
		)
		(property "Datasheet" "https://www.murata.com/products/productdetail?partno=GRM155R61E105KE11%23"
			(at 0 0 0)
			(layer "B.Fab")
			(hide yes)
			(effects
				(font
					(size 1.27 1.27)
					(thickness 0.15)
				)
				(justify mirror)
			)
		)
		(property "Description" "SMD Multilayer Ceramic Capacitor, 1 µF, 25 V, 0402 [1005 Metric], ± 10%, X5R, GRM Series"
			(at 0 0 0)
			(layer "B.Fab")
			(hide yes)
			(effects
				(font
					(size 1.27 1.27)
					(thickness 0.15)
				)
				(justify mirror)
			)
		)
		(property "MPN" "GRM155R61E105KE11J"
			(at 0 0 180)
			(unlocked yes)
			(layer "B.Fab")
			(hide yes)
			(effects
				(font
					(size 1 1)
					(thickness 0.15)
				)
				(justify mirror)
			)
		)
		(property "Manufacturer" "Murata"
			(at 0 0 180)
			(unlocked yes)
			(layer "B.Fab")
			(hide yes)
			(effects
				(font
					(size 1 1)
					(thickness 0.15)
				)
				(justify mirror)
			)
		)
		(property "License" "Apache-2.0"
			(at 0 0 180)
			(unlocked yes)
			(layer "B.Fab")
			(hide yes)
			(effects
				(font
					(size 1 1)
					(thickness 0.15)
				)
				(justify mirror)
			)
		)
		(property "Author" "Antmicro"
			(at 0 0 180)
			(unlocked yes)
			(layer "B.Fab")
			(hide yes)
			(effects
				(font
					(size 1 1)
					(thickness 0.15)
				)
				(justify mirror)
			)
		)
		(property "Val" "1u"
			(at 0 0 180)
			(unlocked yes)
			(layer "B.Fab")
			(hide yes)
			(effects
				(font
					(size 1 1)
					(thickness 0.15)
				)
				(justify mirror)
			)
		)
		(property "Voltage" "25V"
			(at 0 0 180)
			(unlocked yes)
			(layer "B.Fab")
			(hide yes)
			(effects
				(font
					(size 1 1)
					(thickness 0.15)
				)
				(justify mirror)
			)
		)
		(property "Dielectric" "X5R"
			(at 0 0 180)
			(unlocked yes)
			(layer "B.Fab")
			(hide yes)
			(effects
				(font
					(size 1 1)
					(thickness 0.15)
				)
				(justify mirror)
			)
		)
		(sheetname "/2xRJ45/")
		(sheetfile "2xrj45.kicad_sch")
		(attr smd)
		(fp_rect
			(start -0.925 0.47)
			(end 0.925 -0.47)
			(stroke
				(width 0.05)
				(type default)
			)
			(fill no)
			(layer "B.CrtYd")
		)
		(fp_line
			(start 0.504 0.25)
			(end 0.504 -0.248)
			(stroke
				(width 0.15)
				(type solid)
			)
			(layer "B.Fab")
		)
		(fp_line
			(start 0.504 -0.248)
			(end -0.494 -0.248)
			(stroke
				(width 0.15)
				(type solid)
			)
			(layer "B.Fab")
		)
		(fp_line
			(start -0.494 0.25)
			(end 0.504 0.25)
			(stroke
				(width 0.15)
				(type solid)
			)
			(layer "B.Fab")
		)
		(fp_line
			(start -0.494 -0.248)
			(end -0.494 0.25)
			(stroke
				(width 0.15)
				(type solid)
			)
			(layer "B.Fab")
		)
		(fp_text user "Author: Antmicro"
			(at -0.939 -3.399 0)
			(layer "B.Fab")
			(effects
				(font
					(size 0.7 0.7)
					(thickness 0.15)
				)
				(justify left bottom mirror)
			)
		)
		(fp_text user "${REFERENCE}"
			(at -0.939 -4.599 0)
			(layer "B.Fab")
			(effects
				(font
					(size 0.7 0.7)
					(thickness 0.15)
				)
				(justify left bottom mirror)
			)
		)
		(fp_text user "License: Apache-2.0"
			(at -0.939 -5.799 0)
			(layer "B.Fab")
			(effects
				(font
					(size 0.7 0.7)
					(thickness 0.15)
				)
				(justify left bottom mirror)
			)
		)
		(pad "1" smd roundrect
			(at -0.48 0 180)
			(size 0.59 0.64)
			(layers "B.Cu" "B.Mask" "B.Paste")
			(roundrect_rratio 0.25)
			(net 23 "GND")
			(pintype "passive")
		)
		(pad "2" smd roundrect
			(at 0.48 0 180)
			(size 0.59 0.64)
			(layers "B.Cu" "B.Mask" "B.Paste")
			(roundrect_rratio 0.25)
			(net 133 "/2xRJ45/P0_CT")
			(pintype "passive")
		)
	)
	(footprint "antmicro-footprints:Tag-Connect_TC2050-IDC-NL_2x5_P1.27mm"
		(layer "B.Cu")
		(at 126.02 77 -90)
		(property "Reference" "J8"
			(at 0.2 -3.38 90)
			(layer "B.SilkS")
			(effects
				(font
					(size 0.7 0.7)
					(thickness 0.15)
				)
				(justify left bottom mirror)
			)
		)
		(property "Value" "Tag-Connect_TC2050-IDC-NL_2x5_P1.27mm"
			(at 0 -4.4 90)
			(layer "B.Fab")
			(effects
				(font
					(size 0.7 0.7)
					(thickness 0.15)
				)
				(justify left bottom mirror)
			)
		)
		(property "Datasheet" "https://www.tag-connect.com/wp-content/uploads/bsk-pdf-manager/TC2050-IDC-NL_Datasheet_8.pdf"
			(at 0 0 90)
			(layer "B.Fab")
			(hide yes)
			(effects
				(font
					(size 1.27 1.27)
					(thickness 0.15)
				)
				(justify mirror)
			)
		)
		(property "Description" "Tag Connect 2x5 1.27mm terminal"
			(at 0 0 90)
			(layer "B.Fab")
			(hide yes)
			(effects
				(font
					(size 1.27 1.27)
					(thickness 0.15)
				)
				(justify mirror)
			)
		)
		(property "MPN" "TC2050-IDC-NL"
			(at 0 0 270)
			(unlocked yes)
			(layer "B.Fab")
			(hide yes)
			(effects
				(font
					(size 1 1)
					(thickness 0.15)
				)
				(justify mirror)
			)
		)
		(property "Manufacturer" "Tag Connect"
			(at 0 0 270)
			(unlocked yes)
			(layer "B.Fab")
			(hide yes)
			(effects
				(font
					(size 1 1)
					(thickness 0.15)
				)
				(justify mirror)
			)
		)
		(property "Author" "Antmicro"
			(at 0 0 270)
			(unlocked yes)
			(layer "B.Fab")
			(hide yes)
			(effects
				(font
					(size 1 1)
					(thickness 0.15)
				)
				(justify mirror)
			)
		)
		(property "License" "Apache-2.0"
			(at 0 0 270)
			(unlocked yes)
			(layer "B.Fab")
			(hide yes)
			(effects
				(font
					(size 1 1)
					(thickness 0.15)
				)
				(justify mirror)
			)
		)
		(sheetname "/X710 flash memory/")
		(sheetfile "flash_x710.kicad_sch")
		(attr exclude_from_pos_files exclude_from_bom dnp)
		(fp_line
			(start -2.2 2.05)
			(end 4.7 2.05)
			(stroke
				(width 0.15)
				(type solid)
			)
			(layer "B.SilkS")
		)
		(fp_line
			(start 4.7 2.05)
			(end 5.1 1.7)
			(stroke
				(width 0.15)
				(type solid)
			)
			(layer "B.SilkS")
		)
		(fp_line
			(start 5.1 1.7)
			(end 5.1 -1.7)
			(stroke
				(width 0.15)
				(type solid)
			)
			(layer "B.SilkS")
		)
		(fp_line
			(start -5.08 0.9)
			(end -2.2 2.05)
			(stroke
				(width 0.15)
				(type solid)
			)
			(layer "B.SilkS")
		)
		(fp_line
			(start -5.08 -0.8)
			(end -5.08 0.9)
			(stroke
				(width 0.15)
				(type solid)
			)
			(layer "B.SilkS")
		)
		(fp_line
			(start -3.101 -1.269)
			(end -3.101 -0.4)
			(stroke
				(width 0.15)
				(type solid)
			)
			(layer "B.SilkS")
		)
		(fp_line
			(start -2.3 -2.049)
			(end -5.08 -0.8)
			(stroke
				(width 0.15)
				(type solid)
			)
			(layer "B.SilkS")
		)
		(fp_line
			(start 4.7 -2.049)
			(end 5.1 -1.7)
			(stroke
				(width 0.15)
				(type solid)
			)
			(layer "B.SilkS")
		)
		(fp_line
			(start 4.7 -2.049)
			(end -2.3 -2.049)
			(stroke
				(width 0.15)
				(type solid)
			)
			(layer "B.SilkS")
		)
		(fp_line
			(start -2.3 2.3)
			(end 4.8 2.3)
			(stroke
				(width 0.05)
				(type solid)
			)
			(layer "B.CrtYd")
		)
		(fp_line
			(start 4.8 2.3)
			(end 5.32 1.8)
			(stroke
				(width 0.05)
				(type solid)
			)
			(layer "B.CrtYd")
		)
		(fp_line
			(start 5.32 1.8)
			(end 5.32 -1.8)
			(stroke
				(width 0.05)
				(type solid)
			)
			(layer "B.CrtYd")
		)
		(fp_line
			(start -5.33 1.1)
			(end -2.3 2.3)
			(stroke
				(width 0.05)
				(type solid)
			)
			(layer "B.CrtYd")
		)
		(fp_line
			(start -5.33 -1)
			(end -5.33 1.1)
			(stroke
				(width 0.05)
				(type solid)
			)
			(layer "B.CrtYd")
		)
		(fp_line
			(start -2.4 -2.29)
			(end -5.33 -1)
			(stroke
				(width 0.05)
				(type solid)
			)
			(layer "B.CrtYd")
		)
		(fp_line
			(start 4.8 -2.29)
			(end 5.32 -1.8)
			(stroke
				(width 0.05)
				(type solid)
			)
			(layer "B.CrtYd")
		)
		(fp_line
			(start 4.8 -2.29)
			(end -2.4 -2.29)
			(stroke
				(width 0.05)
				(type solid)
			)
			(layer "B.CrtYd")
		)
		(fp_text user "License: Apache-2.0"
			(at -6.223 -8.449 90)
			(layer "B.Fab")
			(effects
				(font
					(size 0.7 0.7)
					(thickness 0.15)
				)
				(justify left bottom mirror)
			)
		)
		(fp_text user "${REFERENCE}"
			(at -6.223 -6.049 90)
			(layer "B.Fab")
			(effects
				(font
					(size 0.7 0.7)
					(thickness 0.15)
				)
				(justify left bottom mirror)
			)
		)
		(fp_text user "Author: Antmicro"
			(at -6.223 -7.249 90)
			(layer "B.Fab")
			(effects
				(font
					(size 0.7 0.7)
					(thickness 0.15)
				)
				(justify left bottom mirror)
			)
		)
		(pad "" np_thru_hole circle
			(at -3.81 0 270)
			(size 0.9906 0.9906)
			(drill 0.9906)
			(layers "*.Cu" "*.Mask")
		)
		(pad "" np_thru_hole circle
			(at 3.809 -1.015 270)
			(size 0.9906 0.9906)
			(drill 0.9906)
			(layers "*.Cu" "*.Mask")
		)
		(pad "" np_thru_hole circle
			(at 3.809 1.016 270)
			(size 0.9906 0.9906)
			(drill 0.9906)
			(layers "*.Cu" "*.Mask")
		)
		(pad "1" connect circle
			(at -2.54 -0.634 270)
			(size 0.7874 0.7874)
			(layers "B.Cu" "B.Mask")
			(net 343 "/X710 flash memory/+3V3_FLASH")
			(pinfunction "3V3")
			(pintype "passive")
		)
		(pad "2" connect circle
			(at -1.27 -0.634 270)
			(size 0.7874 0.7874)
			(layers "B.Cu" "B.Mask")
			(net 350 "/X710 flash memory/FLASH.~{CE}")
			(pinfunction "SPI_CS")
			(pintype "passive")
		)
		(pad "3" connect circle
			(at 0 -0.634 270)
			(size 0.7874 0.7874)
			(layers "B.Cu" "B.Mask")
			(net 23 "GND")
			(pinfunction "GND")
			(pintype "passive")
		)
		(pad "4" connect circle
			(at 1.269 -0.634 270)
			(size 0.7874 0.7874)
			(layers "B.Cu" "B.Mask")
			(net 353 "/X710 flash memory/FLASH.CLK")
			(pinfunction "SPI_SCK")
			(pintype "passive")
		)
		(pad "5" connect circle
			(at 2.539 -0.634 270)
			(size 0.7874 0.7874)
			(layers "B.Cu" "B.Mask")
			(net 23 "GND")
			(pinfunction "GND")
			(pintype "passive")
		)
		(pad "6" connect circle
			(at 2.539 0.635 270)
			(size 0.7874 0.7874)
			(layers "B.Cu" "B.Mask")
			(net 351 "/X710 flash memory/FLASH.MISO")
			(pinfunction "SPI_MISO")
			(pintype "passive")
		)
		(pad "7" connect circle
			(at 1.269 0.635 270)
			(size 0.7874 0.7874)
			(layers "B.Cu" "B.Mask")
			(net 425 "unconnected-(J8-Pad7)")
			(pinfunction "NC")
			(pintype "no_connect")
		)
		(pad "8" connect circle
			(at 0 0.635 270)
			(size 0.7874 0.7874)
			(layers "B.Cu" "B.Mask")
			(net 352 "/X710 flash memory/FLASH.MOSI")
			(pinfunction "SPI_MOSI")
			(pintype "passive")
		)
		(pad "9" connect circle
			(at -1.27 0.635 270)
			(size 0.7874 0.7874)
			(layers "B.Cu" "B.Mask")
			(net 23 "GND")
			(pinfunction "GND")
			(pintype "passive")
		)
		(pad "10" connect circle
			(at -2.54 0.635 270)
			(size 0.7874 0.7874)
			(layers "B.Cu" "B.Mask")
			(net 424 "unconnected-(J8-Pad10)")
			(pinfunction "SPI_NC")
			(pintype "passive+no_connect")
		)
	)
	(footprint "antmicro-footprints:R_0402_1005Metric"
		(layer "B.Cu")
		(at 136.500001 116.125001)
		(descr "Resistor SMD 0402")
		(tags "resistor SMD 0402")
		(property "Reference" "R47"
			(at 19.525001 -7.450001 180)
			(layer "B.SilkS")
			(effects
				(font
					(size 0.7 0.7)
					(thickness 0.15)
				)
				(justify mirror)
			)
		)
		(property "Value" "R_100k_0402"
			(at -1.011843 -1.772047 180)
			(layer "B.Fab")
			(effects
				(font
					(size 0.7 0.7)
					(thickness 0.15)
				)
				(justify left bottom mirror)
			)
		)
		(property "Datasheet" "https://www.bourns.com/docs/product-datasheets/cr.pdf"
			(at 0 0 180)
			(layer "B.Fab")
			(hide yes)
			(effects
				(font
					(size 1.27 1.27)
					(thickness 0.15)
				)
				(justify mirror)
			)
		)
		(property "Description" "SMD Chip Resistor, 100 kohm, ± 1%, 62.5 mW, 0402 [1005 Metric], Thick Film, General Purpose"
			(at 0 0 180)
			(layer "B.Fab")
			(hide yes)
			(effects
				(font
					(size 1.27 1.27)
					(thickness 0.15)
				)
				(justify mirror)
			)
		)
		(property "MPN" "CR0402-FX-1003GLF"
			(at 0 0 0)
			(unlocked yes)
			(layer "B.Fab")
			(hide yes)
			(effects
				(font
					(size 1 1)
					(thickness 0.15)
				)
				(justify mirror)
			)
		)
		(property "Manufacturer" "Bourns"
			(at 0 0 0)
			(unlocked yes)
			(layer "B.Fab")
			(hide yes)
			(effects
				(font
					(size 1 1)
					(thickness 0.15)
				)
				(justify mirror)
			)
		)
		(property "License" "Apache-2.0"
			(at 0 0 0)
			(unlocked yes)
			(layer "B.Fab")
			(hide yes)
			(effects
				(font
					(size 1 1)
					(thickness 0.15)
				)
				(justify mirror)
			)
		)
		(property "Val" "100k"
			(at 0 0 0)
			(unlocked yes)
			(layer "B.Fab")
			(hide yes)
			(effects
				(font
					(size 1 1)
					(thickness 0.15)
				)
				(justify mirror)
			)
		)
		(property "Tolerance" "1%"
			(at 0 0 0)
			(unlocked yes)
			(layer "B.Fab")
			(hide yes)
			(effects
				(font
					(size 1 1)
					(thickness 0.15)
				)
				(justify mirror)
			)
		)
		(property "Author" "Antmicro"
			(at 0 0 0)
			(unlocked yes)
			(layer "B.Fab")
			(hide yes)
			(effects
				(font
					(size 1 1)
					(thickness 0.15)
				)
				(justify mirror)
			)
		)
		(sheetname "/TB Controller/")
		(sheetfile "tb.kicad_sch")
		(attr smd)
		(fp_rect
			(start -0.925 0.47)
			(end 0.925 -0.47)
			(stroke
				(width 0.05)
				(type default)
			)
			(fill no)
			(layer "B.CrtYd")
		)
		(fp_rect
			(start -0.5 0.25)
			(end 0.5 -0.25)
			(stroke
				(width 0.15)
				(type solid)
			)
			(fill no)
			(layer "B.Fab")
		)
		(fp_text user "${REFERENCE}"
			(at -0.95 -3.168 180)
			(layer "B.Fab")
			(effects
				(font
					(size 0.7 0.7)
					(thickness 0.15)
				)
				(justify left bottom mirror)
			)
		)
		(fp_text user "License: Apache-2.0"
			(at -0.95 -5.169 180)
			(layer "B.Fab")
			(effects
				(font
					(size 0.7 0.7)
					(thickness 0.15)
				)
				(justify left bottom mirror)
			)
		)
		(fp_text user "Author: Antmicro"
			(at -0.95 -4.169 180)
			(layer "B.Fab")
			(effects
				(font
					(size 0.7 0.7)
					(thickness 0.15)
				)
				(justify left bottom mirror)
			)
		)
		(pad "1" smd roundrect
			(at -0.48 0)
			(size 0.59 0.64)
			(layers "B.Cu" "B.Mask" "B.Paste")
			(roundrect_rratio 0.25)
			(net 190 "Net-(U4C-GPIO_7)")
			(pintype "passive")
		)
		(pad "2" smd roundrect
			(at 0.48 0)
			(size 0.59 0.64)
			(layers "B.Cu" "B.Mask" "B.Paste")
			(roundrect_rratio 0.25)
			(net 23 "GND")
			(pintype "passive")
		)
	)
	(footprint "antmicro-footprints:C_0402_1005Metric"
		(layer "B.Cu")
		(at 156.081866 90.485117 180)
		(descr "Capacitor SMD 0402")
		(tags "capacitor SMD 0402")
		(property "Reference" "C174"
			(at -18.868134 -10.514883 0)
			(layer "B.SilkS")
			(effects
				(font
					(size 0.7 0.7)
					(thickness 0.15)
				)
				(justify mirror)
			)
		)
		(property "Value" "C_1u_25V_0402"
			(at -1.022927 -2.155213 0)
			(layer "B.Fab")
			(effects
				(font
					(size 0.7 0.7)
					(thickness 0.15)
				)
				(justify left bottom mirror)
			)
		)
		(property "Datasheet" "https://www.murata.com/products/productdetail?partno=GRM155R61E105KE11%23"
			(at 0 0 0)
			(layer "B.Fab")
			(hide yes)
			(effects
				(font
					(size 1.27 1.27)
					(thickness 0.15)
				)
				(justify mirror)
			)
		)
		(property "Description" "SMD Multilayer Ceramic Capacitor, 1 µF, 25 V, 0402 [1005 Metric], ± 10%, X5R, GRM Series"
			(at 0 0 0)
			(layer "B.Fab")
			(hide yes)
			(effects
				(font
					(size 1.27 1.27)
					(thickness 0.15)
				)
				(justify mirror)
			)
		)
		(property "MPN" "GRM155R61E105KE11J"
			(at 0 0 180)
			(unlocked yes)
			(layer "B.Fab")
			(hide yes)
			(effects
				(font
					(size 1 1)
					(thickness 0.15)
				)
				(justify mirror)
			)
		)
		(property "Manufacturer" "Murata"
			(at 0 0 180)
			(unlocked yes)
			(layer "B.Fab")
			(hide yes)
			(effects
				(font
					(size 1 1)
					(thickness 0.15)
				)
				(justify mirror)
			)
		)
		(property "License" "Apache-2.0"
			(at 0 0 180)
			(unlocked yes)
			(layer "B.Fab")
			(hide yes)
			(effects
				(font
					(size 1 1)
					(thickness 0.15)
				)
				(justify mirror)
			)
		)
		(property "Author" "Antmicro"
			(at 0 0 180)
			(unlocked yes)
			(layer "B.Fab")
			(hide yes)
			(effects
				(font
					(size 1 1)
					(thickness 0.15)
				)
				(justify mirror)
			)
		)
		(property "Val" "1u"
			(at 0 0 180)
			(unlocked yes)
			(layer "B.Fab")
			(hide yes)
			(effects
				(font
					(size 1 1)
					(thickness 0.15)
				)
				(justify mirror)
			)
		)
		(property "Voltage" "25V"
			(at 0 0 180)
			(unlocked yes)
			(layer "B.Fab")
			(hide yes)
			(effects
				(font
					(size 1 1)
					(thickness 0.15)
				)
				(justify mirror)
			)
		)
		(property "Dielectric" "X5R"
			(at 0 0 180)
			(unlocked yes)
			(layer "B.Fab")
			(hide yes)
			(effects
				(font
					(size 1 1)
					(thickness 0.15)
				)
				(justify mirror)
			)
		)
		(sheetname "/X710-AT2 power/")
		(sheetfile "x710-at2-power.kicad_sch")
		(attr smd)
		(fp_rect
			(start -0.925 0.47)
			(end 0.925 -0.47)
			(stroke
				(width 0.05)
				(type default)
			)
			(fill no)
			(layer "B.CrtYd")
		)
		(fp_line
			(start 0.504 0.25)
			(end 0.504 -0.248)
			(stroke
				(width 0.15)
				(type solid)
			)
			(layer "B.Fab")
		)
		(fp_line
			(start 0.504 -0.248)
			(end -0.494 -0.248)
			(stroke
				(width 0.15)
				(type solid)
			)
			(layer "B.Fab")
		)
		(fp_line
			(start -0.494 0.25)
			(end 0.504 0.25)
			(stroke
				(width 0.15)
				(type solid)
			)
			(layer "B.Fab")
		)
		(fp_line
			(start -0.494 -0.248)
			(end -0.494 0.25)
			(stroke
				(width 0.15)
				(type solid)
			)
			(layer "B.Fab")
		)
		(fp_text user "License: Apache-2.0"
			(at -0.939 -5.799 0)
			(layer "B.Fab")
			(effects
				(font
					(size 0.7 0.7)
					(thickness 0.15)
				)
				(justify left bottom mirror)
			)
		)
		(fp_text user "${REFERENCE}"
			(at -0.939 -4.599 0)
			(layer "B.Fab")
			(effects
				(font
					(size 0.7 0.7)
					(thickness 0.15)
				)
				(justify left bottom mirror)
			)
		)
		(fp_text user "Author: Antmicro"
			(at -0.939 -3.399 0)
			(layer "B.Fab")
			(effects
				(font
					(size 0.7 0.7)
					(thickness 0.15)
				)
				(justify left bottom mirror)
			)
		)
		(pad "1" smd roundrect
			(at -0.48 0 180)
			(size 0.59 0.64)
			(layers "B.Cu" "B.Mask" "B.Paste")
			(roundrect_rratio 0.25)
			(net 23 "GND")
			(pintype "passive")
		)
		(pad "2" smd roundrect
			(at 0.48 0 180)
			(size 0.59 0.64)
			(layers "B.Cu" "B.Mask" "B.Paste")
			(roundrect_rratio 0.25)
			(net 22 "PLL_VDD")
			(pintype "passive")
		)
	)
	(footprint "antmicro-footprints:R_0402_1005Metric"
		(layer "B.Cu")
		(at 133.75 114.9426)
		(descr "Resistor SMD 0402")
		(tags "resistor SMD 0402")
		(property "Reference" "R42"
			(at 19.525001 -7.450001 180)
			(layer "B.SilkS")
			(effects
				(font
					(size 0.7 0.7)
					(thickness 0.15)
				)
				(justify mirror)
			)
		)
		(property "Value" "R_14k_0402"
			(at -1.011843 -1.772047 180)
			(layer "B.Fab")
			(effects
				(font
					(size 0.7 0.7)
					(thickness 0.15)
				)
				(justify left bottom mirror)
			)
		)
		(property "Datasheet" "https://www.bourns.com/docs/product-datasheets/cr.pdf"
			(at 0 0 180)
			(layer "B.Fab")
			(hide yes)
			(effects
				(font
					(size 1.27 1.27)
					(thickness 0.15)
				)
				(justify mirror)
			)
		)
		(property "Description" "SMD Chip Resistor, 14 kohm, ± 1%, 100 mW, 0402 [1005 Metric], Thick Film, Precision"
			(at 0 0 180)
			(layer "B.Fab")
			(hide yes)
			(effects
				(font
					(size 1.27 1.27)
					(thickness 0.15)
				)
				(justify mirror)
			)
		)
		(property "MPN" "CR0402-FX-1402GLF"
			(at 0 0 0)
			(unlocked yes)
			(layer "B.Fab")
			(hide yes)
			(effects
				(font
					(size 1 1)
					(thickness 0.15)
				)
				(justify mirror)
			)
		)
		(property "Manufacturer" "Bourns"
			(at 0 0 0)
			(unlocked yes)
			(layer "B.Fab")
			(hide yes)
			(effects
				(font
					(size 1 1)
					(thickness 0.15)
				)
				(justify mirror)
			)
		)
		(property "License" "Apache-2.0"
			(at 0 0 0)
			(unlocked yes)
			(layer "B.Fab")
			(hide yes)
			(effects
				(font
					(size 1 1)
					(thickness 0.15)
				)
				(justify mirror)
			)
		)
		(property "Val" "14k"
			(at 0 0 0)
			(unlocked yes)
			(layer "B.Fab")
			(hide yes)
			(effects
				(font
					(size 1 1)
					(thickness 0.15)
				)
				(justify mirror)
			)
		)
		(property "Tolerance" "1%"
			(at 0 0 0)
			(unlocked yes)
			(layer "B.Fab")
			(hide yes)
			(effects
				(font
					(size 1 1)
					(thickness 0.15)
				)
				(justify mirror)
			)
		)
		(property "Author" "Antmicro"
			(at 0 0 0)
			(unlocked yes)
			(layer "B.Fab")
			(hide yes)
			(effects
				(font
					(size 1 1)
					(thickness 0.15)
				)
				(justify mirror)
			)
		)
		(sheetname "/TB Controller/")
		(sheetfile "tb.kicad_sch")
		(attr smd dnp)
		(fp_rect
			(start -0.925 0.47)
			(end 0.925 -0.47)
			(stroke
				(width 0.05)
				(type default)
			)
			(fill no)
			(layer "B.CrtYd")
		)
		(fp_rect
			(start -0.5 0.25)
			(end 0.5 -0.25)
			(stroke
				(width 0.15)
				(type solid)
			)
			(fill no)
			(layer "B.Fab")
		)
		(fp_text user "Author: Antmicro"
			(at -0.95 -4.169 180)
			(layer "B.Fab")
			(effects
				(font
					(size 0.7 0.7)
					(thickness 0.15)
				)
				(justify left bottom mirror)
			)
		)
		(fp_text user "${REFERENCE}"
			(at -0.95 -3.168 180)
			(layer "B.Fab")
			(effects
				(font
					(size 0.7 0.7)
					(thickness 0.15)
				)
				(justify left bottom mirror)
			)
		)
		(fp_text user "License: Apache-2.0"
			(at -0.95 -5.169 180)
			(layer "B.Fab")
			(effects
				(font
					(size 0.7 0.7)
					(thickness 0.15)
				)
				(justify left bottom mirror)
			)
		)
		(pad "1" smd roundrect
			(at -0.48 0)
			(size 0.59 0.64)
			(layers "B.Cu" "B.Mask" "B.Paste")
			(roundrect_rratio 0.25)
			(net 185 "Net-(U4C-DPSRC_RBIAS)")
			(pintype "passive")
		)
		(pad "2" smd roundrect
			(at 0.48 0)
			(size 0.59 0.64)
			(layers "B.Cu" "B.Mask" "B.Paste")
			(roundrect_rratio 0.25)
			(net 23 "GND")
			(pintype "passive")
		)
	)
	(footprint "antmicro-footprints:C_0402_1005Metric"
		(layer "B.Cu")
		(at 149.325897 77.260117 180)
		(descr "Capacitor SMD 0402")
		(tags "capacitor SMD 0402")
		(property "Reference" "C237"
			(at -19.468135 -9.464883 0)
			(layer "B.SilkS")
			(effects
				(font
					(size 0.7 0.7)
					(thickness 0.15)
				)
				(justify mirror)
			)
		)
		(property "Value" "C_1u_25V_0402"
			(at -1.022927 -2.155213 0)
			(layer "B.Fab")
			(effects
				(font
					(size 0.7 0.7)
					(thickness 0.15)
				)
				(justify left bottom mirror)
			)
		)
		(property "Datasheet" "https://www.murata.com/products/productdetail?partno=GRM155R61E105KE11%23"
			(at 0 0 0)
			(layer "B.Fab")
			(hide yes)
			(effects
				(font
					(size 1.27 1.27)
					(thickness 0.15)
				)
				(justify mirror)
			)
		)
		(property "Description" "SMD Multilayer Ceramic Capacitor, 1 µF, 25 V, 0402 [1005 Metric], ± 10%, X5R, GRM Series"
			(at 0 0 0)
			(layer "B.Fab")
			(hide yes)
			(effects
				(font
					(size 1.27 1.27)
					(thickness 0.15)
				)
				(justify mirror)
			)
		)
		(property "MPN" "GRM155R61E105KE11J"
			(at 0 0 180)
			(unlocked yes)
			(layer "B.Fab")
			(hide yes)
			(effects
				(font
					(size 1 1)
					(thickness 0.15)
				)
				(justify mirror)
			)
		)
		(property "Manufacturer" "Murata"
			(at 0 0 180)
			(unlocked yes)
			(layer "B.Fab")
			(hide yes)
			(effects
				(font
					(size 1 1)
					(thickness 0.15)
				)
				(justify mirror)
			)
		)
		(property "License" "Apache-2.0"
			(at 0 0 180)
			(unlocked yes)
			(layer "B.Fab")
			(hide yes)
			(effects
				(font
					(size 1 1)
					(thickness 0.15)
				)
				(justify mirror)
			)
		)
		(property "Author" "Antmicro"
			(at 0 0 180)
			(unlocked yes)
			(layer "B.Fab")
			(hide yes)
			(effects
				(font
					(size 1 1)
					(thickness 0.15)
				)
				(justify mirror)
			)
		)
		(property "Val" "1u"
			(at 0 0 180)
			(unlocked yes)
			(layer "B.Fab")
			(hide yes)
			(effects
				(font
					(size 1 1)
					(thickness 0.15)
				)
				(justify mirror)
			)
		)
		(property "Voltage" "25V"
			(at 0 0 180)
			(unlocked yes)
			(layer "B.Fab")
			(hide yes)
			(effects
				(font
					(size 1 1)
					(thickness 0.15)
				)
				(justify mirror)
			)
		)
		(property "Dielectric" "X5R"
			(at 0 0 180)
			(unlocked yes)
			(layer "B.Fab")
			(hide yes)
			(effects
				(font
					(size 1 1)
					(thickness 0.15)
				)
				(justify mirror)
			)
		)
		(sheetname "/X710-AT2 power/")
		(sheetfile "x710-at2-power.kicad_sch")
		(attr smd)
		(fp_rect
			(start -0.925 0.47)
			(end 0.925 -0.47)
			(stroke
				(width 0.05)
				(type default)
			)
			(fill no)
			(layer "B.CrtYd")
		)
		(fp_line
			(start 0.504 0.25)
			(end 0.504 -0.248)
			(stroke
				(width 0.15)
				(type solid)
			)
			(layer "B.Fab")
		)
		(fp_line
			(start 0.504 -0.248)
			(end -0.494 -0.248)
			(stroke
				(width 0.15)
				(type solid)
			)
			(layer "B.Fab")
		)
		(fp_line
			(start -0.494 0.25)
			(end 0.504 0.25)
			(stroke
				(width 0.15)
				(type solid)
			)
			(layer "B.Fab")
		)
		(fp_line
			(start -0.494 -0.248)
			(end -0.494 0.25)
			(stroke
				(width 0.15)
				(type solid)
			)
			(layer "B.Fab")
		)
		(fp_text user "License: Apache-2.0"
			(at -0.939 -5.799 0)
			(layer "B.Fab")
			(effects
				(font
					(size 0.7 0.7)
					(thickness 0.15)
				)
				(justify left bottom mirror)
			)
		)
		(fp_text user "${REFERENCE}"
			(at -0.939 -4.599 0)
			(layer "B.Fab")
			(effects
				(font
					(size 0.7 0.7)
					(thickness 0.15)
				)
				(justify left bottom mirror)
			)
		)
		(fp_text user "Author: Antmicro"
			(at -0.939 -3.399 0)
			(layer "B.Fab")
			(effects
				(font
					(size 0.7 0.7)
					(thickness 0.15)
				)
				(justify left bottom mirror)
			)
		)
		(pad "1" smd roundrect
			(at -0.48 0 180)
			(size 0.59 0.64)
			(layers "B.Cu" "B.Mask" "B.Paste")
			(roundrect_rratio 0.25)
			(net 23 "GND")
			(pintype "passive")
		)
		(pad "2" smd roundrect
			(at 0.48 0 180)
			(size 0.59 0.64)
			(layers "B.Cu" "B.Mask" "B.Paste")
			(roundrect_rratio 0.25)
			(net 9 "VCCD")
			(pintype "passive")
		)
	)
	(footprint "antmicro-footprints:C_0402_1005Metric"
		(layer "B.Cu")
		(at 137.35 133.599998 180)
		(descr "Capacitor SMD 0402")
		(tags "capacitor SMD 0402")
		(property "Reference" "C14"
			(at -19.525001 8.1 0)
			(layer "B.SilkS")
			(effects
				(font
					(size 0.7 0.7)
					(thickness 0.15)
				)
				(justify mirror)
			)
		)
		(property "Value" "C_1u_0402"
			(at -1.022927 -2.155213 0)
			(layer "B.Fab")
			(effects
				(font
					(size 0.7 0.7)
					(thickness 0.15)
				)
				(justify left bottom mirror)
			)
		)
		(property "Datasheet" "https://product.tdk.com/en/search/capacitor/ceramic/mlcc/info?part_no=C1005X6S1A105K050BC"
			(at 0 0 0)
			(layer "B.Fab")
			(hide yes)
			(effects
				(font
					(size 1.27 1.27)
					(thickness 0.15)
				)
				(justify mirror)
			)
		)
		(property "Description" "SMD Multilayer Ceramic Capacitor, 1 µF, 10 V, 0402 [1005 Metric], ± 10%, X6S, C"
			(at 0 0 0)
			(layer "B.Fab")
			(hide yes)
			(effects
				(font
					(size 1.27 1.27)
					(thickness 0.15)
				)
				(justify mirror)
			)
		)
		(property "MPN" "C1005X6S1A105K050BC"
			(at 0 0 180)
			(unlocked yes)
			(layer "B.Fab")
			(hide yes)
			(effects
				(font
					(size 1 1)
					(thickness 0.15)
				)
				(justify mirror)
			)
		)
		(property "Manufacturer" "TDK"
			(at 0 0 180)
			(unlocked yes)
			(layer "B.Fab")
			(hide yes)
			(effects
				(font
					(size 1 1)
					(thickness 0.15)
				)
				(justify mirror)
			)
		)
		(property "License" "Apache-2.0"
			(at 0 0 180)
			(unlocked yes)
			(layer "B.Fab")
			(hide yes)
			(effects
				(font
					(size 1 1)
					(thickness 0.15)
				)
				(justify mirror)
			)
		)
		(property "Val" "1u"
			(at 0 0 180)
			(unlocked yes)
			(layer "B.Fab")
			(hide yes)
			(effects
				(font
					(size 1 1)
					(thickness 0.15)
				)
				(justify mirror)
			)
		)
		(property "Voltage" ""
			(at 0 0 180)
			(unlocked yes)
			(layer "B.Fab")
			(hide yes)
			(effects
				(font
					(size 1 1)
					(thickness 0.15)
				)
				(justify mirror)
			)
		)
		(property "Dielectric" ""
			(at 0 0 180)
			(unlocked yes)
			(layer "B.Fab")
			(hide yes)
			(effects
				(font
					(size 1 1)
					(thickness 0.15)
				)
				(justify mirror)
			)
		)
		(property "Author" "Antmicro"
			(at 0 0 180)
			(unlocked yes)
			(layer "B.Fab")
			(hide yes)
			(effects
				(font
					(size 1 1)
					(thickness 0.15)
				)
				(justify mirror)
			)
		)
		(sheetname "/PD and TB DC-DC/")
		(sheetfile "PD_and_TB_DC_DC.kicad_sch")
		(attr smd)
		(fp_rect
			(start -0.925 0.47)
			(end 0.925 -0.47)
			(stroke
				(width 0.05)
				(type default)
			)
			(fill no)
			(layer "B.CrtYd")
		)
		(fp_line
			(start 0.504 0.25)
			(end 0.504 -0.248)
			(stroke
				(width 0.15)
				(type solid)
			)
			(layer "B.Fab")
		)
		(fp_line
			(start 0.504 -0.248)
			(end -0.494 -0.248)
			(stroke
				(width 0.15)
				(type solid)
			)
			(layer "B.Fab")
		)
		(fp_line
			(start -0.494 0.25)
			(end 0.504 0.25)
			(stroke
				(width 0.15)
				(type solid)
			)
			(layer "B.Fab")
		)
		(fp_line
			(start -0.494 -0.248)
			(end -0.494 0.25)
			(stroke
				(width 0.15)
				(type solid)
			)
			(layer "B.Fab")
		)
		(fp_text user "${REFERENCE}"
			(at -0.939 -4.599 0)
			(layer "B.Fab")
			(effects
				(font
					(size 0.7 0.7)
					(thickness 0.15)
				)
				(justify left bottom mirror)
			)
		)
		(fp_text user "Author: Antmicro"
			(at -0.939 -3.399 0)
			(layer "B.Fab")
			(effects
				(font
					(size 0.7 0.7)
					(thickness 0.15)
				)
				(justify left bottom mirror)
			)
		)
		(fp_text user "License: Apache-2.0"
			(at -0.939 -5.799 0)
			(layer "B.Fab")
			(effects
				(font
					(size 0.7 0.7)
					(thickness 0.15)
				)
				(justify left bottom mirror)
			)
		)
		(pad "1" smd roundrect
			(at -0.48 0 180)
			(size 0.59 0.64)
			(layers "B.Cu" "B.Mask" "B.Paste")
			(roundrect_rratio 0.25)
			(net 23 "GND")
			(pintype "passive")
		)
		(pad "2" smd roundrect
			(at 0.48 0 180)
			(size 0.59 0.64)
			(layers "B.Cu" "B.Mask" "B.Paste")
			(roundrect_rratio 0.25)
			(net 57 "+3V3_TB")
			(pintype "passive")
		)
	)
	(footprint "antmicro-footprints:C_0402_1005Metric"
		(layer "B.Cu")
		(at 173.58 146.66 -90)
		(descr "Capacitor SMD 0402")
		(tags "capacitor SMD 0402")
		(property "Reference" "C305"
			(at 1.09 -0.42 90)
			(layer "B.SilkS")
			(effects
				(font
					(size 0.7 0.7)
					(thickness 0.15)
				)
				(justify left bottom mirror)
			)
		)
		(property "Value" "C_470p_0402"
			(at -1.022927 -2.155213 90)
			(layer "B.Fab")
			(effects
				(font
					(size 0.7 0.7)
					(thickness 0.15)
				)
				(justify left bottom mirror)
			)
		)
		(property "Datasheet" "https://www.passivecomponent.com/wp-content/uploads/datasheet/WTC_MLCC_General_Purpose.pdf"
			(at 0 0 90)
			(layer "B.Fab")
			(hide yes)
			(effects
				(font
					(size 1.27 1.27)
					(thickness 0.15)
				)
				(justify mirror)
			)
		)
		(property "Description" "SMD Multilayer Ceramic Capacitor, General Purpose, 470 pF, 25 V, 0402 [1005 Metric], ± 10%, X7R"
			(at 0 0 90)
			(layer "B.Fab")
			(hide yes)
			(effects
				(font
					(size 1.27 1.27)
					(thickness 0.15)
				)
				(justify mirror)
			)
		)
		(property "MPN" "0402B471K250CT"
			(at 0 0 270)
			(unlocked yes)
			(layer "B.Fab")
			(hide yes)
			(effects
				(font
					(size 1 1)
					(thickness 0.15)
				)
				(justify mirror)
			)
		)
		(property "Manufacturer" "Walsin"
			(at 0 0 270)
			(unlocked yes)
			(layer "B.Fab")
			(hide yes)
			(effects
				(font
					(size 1 1)
					(thickness 0.15)
				)
				(justify mirror)
			)
		)
		(property "License" "Apache-2.0"
			(at 0 0 270)
			(unlocked yes)
			(layer "B.Fab")
			(hide yes)
			(effects
				(font
					(size 1 1)
					(thickness 0.15)
				)
				(justify mirror)
			)
		)
		(property "Author" "Antmicro"
			(at 0 0 270)
			(unlocked yes)
			(layer "B.Fab")
			(hide yes)
			(effects
				(font
					(size 1 1)
					(thickness 0.15)
				)
				(justify mirror)
			)
		)
		(property "Val" "470p"
			(at 0 0 270)
			(unlocked yes)
			(layer "B.Fab")
			(hide yes)
			(effects
				(font
					(size 1 1)
					(thickness 0.15)
				)
				(justify mirror)
			)
		)
		(property "Voltage" "25V"
			(at 0 0 270)
			(unlocked yes)
			(layer "B.Fab")
			(hide yes)
			(effects
				(font
					(size 1 1)
					(thickness 0.15)
				)
				(justify mirror)
			)
		)
		(property "Dielectric" "X7R"
			(at 0 0 270)
			(unlocked yes)
			(layer "B.Fab")
			(hide yes)
			(effects
				(font
					(size 1 1)
					(thickness 0.15)
				)
				(justify mirror)
			)
		)
		(sheetname "/2xRJ45/")
		(sheetfile "2xrj45.kicad_sch")
		(attr smd)
		(fp_rect
			(start -0.925 0.47)
			(end 0.925 -0.47)
			(stroke
				(width 0.05)
				(type default)
			)
			(fill no)
			(layer "B.CrtYd")
		)
		(fp_line
			(start -0.494 0.25)
			(end 0.504 0.25)
			(stroke
				(width 0.15)
				(type solid)
			)
			(layer "B.Fab")
		)
		(fp_line
			(start 0.504 0.25)
			(end 0.504 -0.248)
			(stroke
				(width 0.15)
				(type solid)
			)
			(layer "B.Fab")
		)
		(fp_line
			(start -0.494 -0.248)
			(end -0.494 0.25)
			(stroke
				(width 0.15)
				(type solid)
			)
			(layer "B.Fab")
		)
		(fp_line
			(start 0.504 -0.248)
			(end -0.494 -0.248)
			(stroke
				(width 0.15)
				(type solid)
			)
			(layer "B.Fab")
		)
		(fp_text user "License: Apache-2.0"
			(at -0.939 -5.799 90)
			(layer "B.Fab")
			(effects
				(font
					(size 0.7 0.7)
					(thickness 0.15)
				)
				(justify left bottom mirror)
			)
		)
		(fp_text user "${REFERENCE}"
			(at -0.939 -4.599 90)
			(layer "B.Fab")
			(effects
				(font
					(size 0.7 0.7)
					(thickness 0.15)
				)
				(justify left bottom mirror)
			)
		)
		(fp_text user "Author: Antmicro"
			(at -0.939 -3.399 90)
			(layer "B.Fab")
			(effects
				(font
					(size 0.7 0.7)
					(thickness 0.15)
				)
				(justify left bottom mirror)
			)
		)
		(pad "1" smd roundrect
			(at -0.48 0 270)
			(size 0.59 0.64)
			(layers "B.Cu" "B.Mask" "B.Paste")
			(roundrect_rratio 0.25)
			(net 23 "GND")
			(pintype "passive")
		)
		(pad "2" smd roundrect
			(at 0.48 0 270)
			(size 0.59 0.64)
			(layers "B.Cu" "B.Mask" "B.Paste")
			(roundrect_rratio 0.25)
			(net 409 "Net-(J4-LED_YG_G-)")
			(pintype "passive")
		)
	)
	(footprint "antmicro-footprints:Fiducial_1mm_Mask2mm"
		(layer "B.Cu")
		(at 125 47.5 180)
		(descr "Circular Fiducial, 1mm bare copper, 3mm soldermask opening")
		(tags "fiducial")
		(property "Reference" "FD2"
			(at -1 -2.7 0)
			(layer "B.SilkS")
			(effects
				(font
					(size 0.7 0.7)
					(thickness 0.15)
				)
				(justify left bottom mirror)
			)
		)
		(property "Value" "Fiducial_1mm_Mask2mm"
			(at 0 -2.2 0)
			(layer "B.Fab")
			(effects
				(font
					(size 0.7 0.7)
					(thickness 0.15)
				)
				(justify left bottom mirror)
			)
		)
		(property "Description" "Fiducial mask"
			(at 0 0 0)
			(layer "B.Fab")
			(hide yes)
			(effects
				(font
					(size 1.27 1.27)
					(thickness 0.15)
				)
				(justify mirror)
			)
		)
		(property "Author" "Antmicro"
			(at 0 0 180)
			(unlocked yes)
			(layer "B.Fab")
			(hide yes)
			(effects
				(font
					(size 1 1)
					(thickness 0.15)
				)
				(justify mirror)
			)
		)
		(property "License" "Apache-2.0"
			(at 0 0 180)
			(unlocked yes)
			(layer "B.Fab")
			(hide yes)
			(effects
				(font
					(size 1 1)
					(thickness 0.15)
				)
				(justify mirror)
			)
		)
		(sheetname "/")
		(sheetfile "thunderbolt-to-10gbe-adapter.kicad_sch")
		(attr exclude_from_pos_files exclude_from_bom)
		(fp_circle
			(center 0 0)
			(end 1.24 0)
			(stroke
				(width 0.05)
				(type solid)
			)
			(fill no)
			(layer "B.CrtYd")
		)
		(fp_circle
			(center 0 0)
			(end 0.999 0)
			(stroke
				(width 0.15)
				(type solid)
			)
			(fill no)
			(layer "B.Fab")
		)
		(fp_text user "License: Apache-2.0"
			(at -1.25 -7.003 0)
			(layer "B.Fab")
			(effects
				(font
					(size 0.7 0.7)
					(thickness 0.15)
				)
				(justify left bottom mirror)
			)
		)
		(fp_text user "Author: Antmicro"
			(at -1.25 -5.803 0)
			(layer "B.Fab")
			(effects
				(font
					(size 0.7 0.7)
					(thickness 0.15)
				)
				(justify left bottom mirror)
			)
		)
		(fp_text user "${REFERENCE}"
			(at -1.25 -4.603 0)
			(layer "B.Fab")
			(effects
				(font
					(size 0.7 0.7)
					(thickness 0.15)
				)
				(justify left bottom mirror)
			)
		)
		(pad "" smd circle
			(at 0 0 180)
			(size 1 1)
			(layers "B.Cu" "B.Mask")
			(solder_mask_margin 0.5)
			(clearance 0.5)
		)
	)
	(footprint "antmicro-footprints:R_0402_1005Metric"
		(layer "B.Cu")
		(at 139.2 131.6 180)
		(descr "Resistor SMD 0402")
		(tags "resistor SMD 0402")
		(property "Reference" "R10"
			(at -19.525001 8.1 0)
			(layer "B.SilkS")
			(effects
				(font
					(size 0.7 0.7)
					(thickness 0.15)
				)
				(justify mirror)
			)
		)
		(property "Value" "R_2k2_0402"
			(at -1.011843 -1.772047 0)
			(layer "B.Fab")
			(effects
				(font
					(size 0.7 0.7)
					(thickness 0.15)
				)
				(justify left bottom mirror)
			)
		)
		(property "Datasheet" "https://www.bourns.com/docs/product-datasheets/cr.pdf"
			(at 0 0 0)
			(layer "B.Fab")
			(hide yes)
			(effects
				(font
					(size 1.27 1.27)
					(thickness 0.15)
				)
				(justify mirror)
			)
		)
		(property "Description" "SMD Chip Resistor, 2.2 kohm, ± 1%, 62.5 mW, 0402 [1005 Metric], Thick Film, General Purpose"
			(at 0 0 0)
			(layer "B.Fab")
			(hide yes)
			(effects
				(font
					(size 1.27 1.27)
					(thickness 0.15)
				)
				(justify mirror)
			)
		)
		(property "MPN" "CR0402-FX-2201GLF"
			(at 0 0 180)
			(unlocked yes)
			(layer "B.Fab")
			(hide yes)
			(effects
				(font
					(size 1 1)
					(thickness 0.15)
				)
				(justify mirror)
			)
		)
		(property "Manufacturer" "Bourns"
			(at 0 0 180)
			(unlocked yes)
			(layer "B.Fab")
			(hide yes)
			(effects
				(font
					(size 1 1)
					(thickness 0.15)
				)
				(justify mirror)
			)
		)
		(property "License" "Apache-2.0"
			(at 0 0 180)
			(unlocked yes)
			(layer "B.Fab")
			(hide yes)
			(effects
				(font
					(size 1 1)
					(thickness 0.15)
				)
				(justify mirror)
			)
		)
		(property "Val" "2k2"
			(at 0 0 180)
			(unlocked yes)
			(layer "B.Fab")
			(hide yes)
			(effects
				(font
					(size 1 1)
					(thickness 0.15)
				)
				(justify mirror)
			)
		)
		(property "Tolerance" "1%"
			(at 0 0 180)
			(unlocked yes)
			(layer "B.Fab")
			(hide yes)
			(effects
				(font
					(size 1 1)
					(thickness 0.15)
				)
				(justify mirror)
			)
		)
		(property "Author" "Antmicro"
			(at 0 0 180)
			(unlocked yes)
			(layer "B.Fab")
			(hide yes)
			(effects
				(font
					(size 1 1)
					(thickness 0.15)
				)
				(justify mirror)
			)
		)
		(sheetname "/PD and TB DC-DC/")
		(sheetfile "PD_and_TB_DC_DC.kicad_sch")
		(attr smd)
		(fp_rect
			(start -0.925 0.47)
			(end 0.925 -0.47)
			(stroke
				(width 0.05)
				(type default)
			)
			(fill no)
			(layer "B.CrtYd")
		)
		(fp_rect
			(start -0.5 0.25)
			(end 0.5 -0.25)
			(stroke
				(width 0.15)
				(type solid)
			)
			(fill no)
			(layer "B.Fab")
		)
		(fp_text user "${REFERENCE}"
			(at -0.95 -3.168 0)
			(layer "B.Fab")
			(effects
				(font
					(size 0.7 0.7)
					(thickness 0.15)
				)
				(justify left bottom mirror)
			)
		)
		(fp_text user "License: Apache-2.0"
			(at -0.95 -5.169 0)
			(layer "B.Fab")
			(effects
				(font
					(size 0.7 0.7)
					(thickness 0.15)
				)
				(justify left bottom mirror)
			)
		)
		(fp_text user "Author: Antmicro"
			(at -0.95 -4.169 0)
			(layer "B.Fab")
			(effects
				(font
					(size 0.7 0.7)
					(thickness 0.15)
				)
				(justify left bottom mirror)
			)
		)
		(pad "1" smd roundrect
			(at -0.48 0 180)
			(size 0.59 0.64)
			(layers "B.Cu" "B.Mask" "B.Paste")
			(roundrect_rratio 0.25)
			(net 375 "/PD and TB DC-DC/I2C1.SDA")
			(pintype "passive")
		)
		(pad "2" smd roundrect
			(at 0.48 0 180)
			(size 0.59 0.64)
			(layers "B.Cu" "B.Mask" "B.Paste")
			(roundrect_rratio 0.25)
			(net 57 "+3V3_TB")
			(pintype "passive")
		)
	)
	(footprint "antmicro-footprints:TP_SMD_0.75mm"
		(layer "B.Cu")
		(at 157.381866 79.485117 180)
		(property "Reference" "TP31"
			(at -20.718136 -9.114883 0)
			(layer "B.SilkS")
			(effects
				(font
					(size 0.7 0.7)
					(thickness 0.15)
				)
				(justify mirror)
			)
		)
		(property "Value" "TP_0.75mm_SMD"
			(at 0 -1.2 0)
			(layer "B.Fab")
			(effects
				(font
					(size 0.7 0.7)
					(thickness 0.15)
				)
				(justify left bottom mirror)
			)
		)
		(property "Description" "SMT test point"
			(at 0 0 0)
			(layer "B.Fab")
			(hide yes)
			(effects
				(font
					(size 1.27 1.27)
					(thickness 0.15)
				)
				(justify mirror)
			)
		)
		(property "MPN" ""
			(at 0 0 180)
			(unlocked yes)
			(layer "B.Fab")
			(hide yes)
			(effects
				(font
					(size 1 1)
					(thickness 0.15)
				)
				(justify mirror)
			)
		)
		(property "Manufacturer" ""
			(at 0 0 180)
			(unlocked yes)
			(layer "B.Fab")
			(hide yes)
			(effects
				(font
					(size 1 1)
					(thickness 0.15)
				)
				(justify mirror)
			)
		)
		(property "Author" "Antmicro"
			(at 0 0 180)
			(unlocked yes)
			(layer "B.Fab")
			(hide yes)
			(effects
				(font
					(size 1 1)
					(thickness 0.15)
				)
				(justify mirror)
			)
		)
		(property "License" "Apache-2.0"
			(at 0 0 180)
			(unlocked yes)
			(layer "B.Fab")
			(hide yes)
			(effects
				(font
					(size 1 1)
					(thickness 0.15)
				)
				(justify mirror)
			)
		)
		(sheetname "/X710-AT2 Misc/")
		(sheetfile "x710-at2-mics.kicad_sch")
		(attr exclude_from_pos_files exclude_from_bom)
		(fp_circle
			(center 0 0)
			(end 0.475 0)
			(stroke
				(width 0.05)
				(type default)
			)
			(fill no)
			(layer "B.CrtYd")
		)
		(fp_text user "${REFERENCE}"
			(at -0.4 -2.7 0)
			(layer "B.Fab")
			(effects
				(font
					(size 0.7 0.7)
					(thickness 0.15)
				)
				(justify left bottom mirror)
			)
		)
		(fp_text user "Author: Antmicro"
			(at -0.4 -3.901 0)
			(layer "B.Fab")
			(effects
				(font
					(size 0.7 0.7)
					(thickness 0.15)
				)
				(justify left bottom mirror)
			)
		)
		(fp_text user "License: Apache-2.0"
			(at -0.4 -5.101 0)
			(layer "B.Fab")
			(effects
				(font
					(size 0.7 0.7)
					(thickness 0.15)
				)
				(justify left bottom mirror)
			)
		)
		(pad "1" smd circle
			(at 0 0 180)
			(size 0.75 0.75)
			(layers "B.Cu" "B.Mask")
			(net 104 "/X710-AT2 Misc/PHY_TCK")
			(pinfunction "1")
			(pintype "passive")
		)
	)
	(footprint "antmicro-footprints:C_0402_1005Metric"
		(layer "B.Cu")
		(at 163.25 129.25 180)
		(descr "Capacitor SMD 0402")
		(tags "capacitor SMD 0402")
		(property "Reference" "C288"
			(at -4.5 1.75 0)
			(layer "B.SilkS")
			(effects
				(font
					(size 0.7 0.7)
					(thickness 0.15)
				)
				(justify left bottom mirror)
			)
		)
		(property "Value" "C_100n_0402"
			(at -1.022927 -2.155213 0)
			(layer "B.Fab")
			(effects
				(font
					(size 0.7 0.7)
					(thickness 0.15)
				)
				(justify left bottom mirror)
			)
		)
		(property "Datasheet" "https://www.murata.com/products/productdetail?partno=GRM155R61H104KE14%23"
			(at 0 0 0)
			(layer "B.Fab")
			(hide yes)
			(effects
				(font
					(size 1.27 1.27)
					(thickness 0.15)
				)
				(justify mirror)
			)
		)
		(property "Description" "SMD Multilayer Ceramic Capacitor, 0.1 µF, 50 V, 0402 [1005 Metric], ± 10%, X5R, GRM Series"
			(at 0 0 0)
			(layer "B.Fab")
			(hide yes)
			(effects
				(font
					(size 1.27 1.27)
					(thickness 0.15)
				)
				(justify mirror)
			)
		)
		(property "MPN" "GRM155R61H104KE14D"
			(at 0 0 180)
			(unlocked yes)
			(layer "B.Fab")
			(hide yes)
			(effects
				(font
					(size 1 1)
					(thickness 0.15)
				)
				(justify mirror)
			)
		)
		(property "Val" "100n"
			(at 0 0 180)
			(unlocked yes)
			(layer "B.Fab")
			(hide yes)
			(effects
				(font
					(size 1 1)
					(thickness 0.15)
				)
				(justify mirror)
			)
		)
		(property "Voltage" "50V"
			(at 0 0 180)
			(unlocked yes)
			(layer "B.Fab")
			(hide yes)
			(effects
				(font
					(size 1 1)
					(thickness 0.15)
				)
				(justify mirror)
			)
		)
		(property "Dielectric" "X5R"
			(at 0 0 180)
			(unlocked yes)
			(layer "B.Fab")
			(hide yes)
			(effects
				(font
					(size 1 1)
					(thickness 0.15)
				)
				(justify mirror)
			)
		)
		(property "Manufacturer" "Murata"
			(at 0 0 180)
			(unlocked yes)
			(layer "B.Fab")
			(hide yes)
			(effects
				(font
					(size 1 1)
					(thickness 0.15)
				)
				(justify mirror)
			)
		)
		(property "License" "Apache-2.0"
			(at 0 0 180)
			(unlocked yes)
			(layer "B.Fab")
			(hide yes)
			(effects
				(font
					(size 1 1)
					(thickness 0.15)
				)
				(justify mirror)
			)
		)
		(property "Author" "Antmicro"
			(at 0 0 180)
			(unlocked yes)
			(layer "B.Fab")
			(hide yes)
			(effects
				(font
					(size 1 1)
					(thickness 0.15)
				)
				(justify mirror)
			)
		)
		(sheetname "/2xRJ45/")
		(sheetfile "2xrj45.kicad_sch")
		(attr smd)
		(fp_rect
			(start -0.925 0.47)
			(end 0.925 -0.47)
			(stroke
				(width 0.05)
				(type default)
			)
			(fill no)
			(layer "B.CrtYd")
		)
		(fp_line
			(start 0.504 0.25)
			(end 0.504 -0.248)
			(stroke
				(width 0.15)
				(type solid)
			)
			(layer "B.Fab")
		)
		(fp_line
			(start 0.504 -0.248)
			(end -0.494 -0.248)
			(stroke
				(width 0.15)
				(type solid)
			)
			(layer "B.Fab")
		)
		(fp_line
			(start -0.494 0.25)
			(end 0.504 0.25)
			(stroke
				(width 0.15)
				(type solid)
			)
			(layer "B.Fab")
		)
		(fp_line
			(start -0.494 -0.248)
			(end -0.494 0.25)
			(stroke
				(width 0.15)
				(type solid)
			)
			(layer "B.Fab")
		)
		(fp_text user "Author: Antmicro"
			(at -0.939 -3.399 0)
			(layer "B.Fab")
			(effects
				(font
					(size 0.7 0.7)
					(thickness 0.15)
				)
				(justify left bottom mirror)
			)
		)
		(fp_text user "License: Apache-2.0"
			(at -0.939 -5.799 0)
			(layer "B.Fab")
			(effects
				(font
					(size 0.7 0.7)
					(thickness 0.15)
				)
				(justify left bottom mirror)
			)
		)
		(fp_text user "${REFERENCE}"
			(at -0.939 -4.599 0)
			(layer "B.Fab")
			(effects
				(font
					(size 0.7 0.7)
					(thickness 0.15)
				)
				(justify left bottom mirror)
			)
		)
		(pad "1" smd roundrect
			(at -0.48 0 180)
			(size 0.59 0.64)
			(layers "B.Cu" "B.Mask" "B.Paste")
			(roundrect_rratio 0.25)
			(net 23 "GND")
			(pintype "passive")
		)
		(pad "2" smd roundrect
			(at 0.48 0 180)
			(size 0.59 0.64)
			(layers "B.Cu" "B.Mask" "B.Paste")
			(roundrect_rratio 0.25)
			(net 18 "+1V88")
			(pintype "passive")
		)
	)
	(footprint "antmicro-footprints:R_0402_1005Metric"
		(layer "B.Cu")
		(at 155.481866 74.785117 90)
		(descr "Resistor SMD 0402")
		(tags "resistor SMD 0402")
		(property "Reference" "R202"
			(at -8.014883 21.618136 270)
			(layer "B.SilkS")
			(effects
				(font
					(size 0.7 0.7)
					(thickness 0.15)
				)
				(justify mirror)
			)
		)
		(property "Value" "R_8k2_0402"
			(at -1.011843 -1.772047 270)
			(layer "B.Fab")
			(effects
				(font
					(size 0.7 0.7)
					(thickness 0.15)
				)
				(justify left bottom mirror)
			)
		)
		(property "Datasheet" "https://www.bourns.com/docs/product-datasheets/cr.pdf"
			(at 0 0 270)
			(layer "B.Fab")
			(hide yes)
			(effects
				(font
					(size 1.27 1.27)
					(thickness 0.15)
				)
				(justify mirror)
			)
		)
		(property "Description" "SMD Chip Resistor"
			(at 0 0 270)
			(layer "B.Fab")
			(hide yes)
			(effects
				(font
					(size 1.27 1.27)
					(thickness 0.15)
				)
				(justify mirror)
			)
		)
		(property "MPN" "CR0402-FX-8201GLF"
			(at 0 0 90)
			(unlocked yes)
			(layer "B.Fab")
			(hide yes)
			(effects
				(font
					(size 1 1)
					(thickness 0.15)
				)
				(justify mirror)
			)
		)
		(property "Manufacturer" "Bourns"
			(at 0 0 90)
			(unlocked yes)
			(layer "B.Fab")
			(hide yes)
			(effects
				(font
					(size 1 1)
					(thickness 0.15)
				)
				(justify mirror)
			)
		)
		(property "License" "Apache-2.0"
			(at 0 0 90)
			(unlocked yes)
			(layer "B.Fab")
			(hide yes)
			(effects
				(font
					(size 1 1)
					(thickness 0.15)
				)
				(justify mirror)
			)
		)
		(property "Author" "Antmicro"
			(at 0 0 90)
			(unlocked yes)
			(layer "B.Fab")
			(hide yes)
			(effects
				(font
					(size 1 1)
					(thickness 0.15)
				)
				(justify mirror)
			)
		)
		(property "Val" "8k2"
			(at 0 0 90)
			(unlocked yes)
			(layer "B.Fab")
			(hide yes)
			(effects
				(font
					(size 1 1)
					(thickness 0.15)
				)
				(justify mirror)
			)
		)
		(property "Tolerance" "1%"
			(at 0 0 90)
			(unlocked yes)
			(layer "B.Fab")
			(hide yes)
			(effects
				(font
					(size 1 1)
					(thickness 0.15)
				)
				(justify mirror)
			)
		)
		(sheetname "/X710-AT2 10GbE/")
		(sheetfile "x710-at2-10gbe.kicad_sch")
		(attr smd)
		(fp_rect
			(start -0.925 0.47)
			(end 0.925 -0.47)
			(stroke
				(width 0.05)
				(type default)
			)
			(fill no)
			(layer "B.CrtYd")
		)
		(fp_rect
			(start -0.5 0.25)
			(end 0.5 -0.25)
			(stroke
				(width 0.15)
				(type solid)
			)
			(fill no)
			(layer "B.Fab")
		)
		(fp_text user "${REFERENCE}"
			(at -0.95 -3.168 270)
			(layer "B.Fab")
			(effects
				(font
					(size 0.7 0.7)
					(thickness 0.15)
				)
				(justify left bottom mirror)
			)
		)
		(fp_text user "License: Apache-2.0"
			(at -0.95 -5.169 270)
			(layer "B.Fab")
			(effects
				(font
					(size 0.7 0.7)
					(thickness 0.15)
				)
				(justify left bottom mirror)
			)
		)
		(fp_text user "Author: Antmicro"
			(at -0.95 -4.169 270)
			(layer "B.Fab")
			(effects
				(font
					(size 0.7 0.7)
					(thickness 0.15)
				)
				(justify left bottom mirror)
			)
		)
		(pad "1" smd roundrect
			(at -0.48 0 90)
			(size 0.59 0.64)
			(layers "B.Cu" "B.Mask" "B.Paste")
			(roundrect_rratio 0.25)
			(net 64 "/X710-AT2 10GbE/OSC_SEL")
			(pintype "passive")
		)
		(pad "2" smd roundrect
			(at 0.48 0 90)
			(size 0.59 0.64)
			(layers "B.Cu" "B.Mask" "B.Paste")
			(roundrect_rratio 0.25)
			(net 7 "+3V3")
			(pintype "passive")
		)
	)
	(footprint "antmicro-footprints:C_0402_1005Metric"
		(layer "B.Cu")
		(at 156.111866 83.245117 180)
		(descr "Capacitor SMD 0402")
		(tags "capacitor SMD 0402")
		(property "Reference" "C197"
			(at -19.873134 -9.464883 0)
			(layer "B.SilkS")
			(effects
				(font
					(size 0.7 0.7)
					(thickness 0.15)
				)
				(justify mirror)
			)
		)
		(property "Value" "C_1u_25V_0402"
			(at -1.022927 -2.155213 0)
			(layer "B.Fab")
			(effects
				(font
					(size 0.7 0.7)
					(thickness 0.15)
				)
				(justify left bottom mirror)
			)
		)
		(property "Datasheet" "https://www.murata.com/products/productdetail?partno=GRM155R61E105KE11%23"
			(at 0 0 0)
			(layer "B.Fab")
			(hide yes)
			(effects
				(font
					(size 1.27 1.27)
					(thickness 0.15)
				)
				(justify mirror)
			)
		)
		(property "Description" "SMD Multilayer Ceramic Capacitor, 1 µF, 25 V, 0402 [1005 Metric], ± 10%, X5R, GRM Series"
			(at 0 0 0)
			(layer "B.Fab")
			(hide yes)
			(effects
				(font
					(size 1.27 1.27)
					(thickness 0.15)
				)
				(justify mirror)
			)
		)
		(property "MPN" "GRM155R61E105KE11J"
			(at 0 0 180)
			(unlocked yes)
			(layer "B.Fab")
			(hide yes)
			(effects
				(font
					(size 1 1)
					(thickness 0.15)
				)
				(justify mirror)
			)
		)
		(property "Manufacturer" "Murata"
			(at 0 0 180)
			(unlocked yes)
			(layer "B.Fab")
			(hide yes)
			(effects
				(font
					(size 1 1)
					(thickness 0.15)
				)
				(justify mirror)
			)
		)
		(property "License" "Apache-2.0"
			(at 0 0 180)
			(unlocked yes)
			(layer "B.Fab")
			(hide yes)
			(effects
				(font
					(size 1 1)
					(thickness 0.15)
				)
				(justify mirror)
			)
		)
		(property "Author" "Antmicro"
			(at 0 0 180)
			(unlocked yes)
			(layer "B.Fab")
			(hide yes)
			(effects
				(font
					(size 1 1)
					(thickness 0.15)
				)
				(justify mirror)
			)
		)
		(property "Val" "1u"
			(at 0 0 180)
			(unlocked yes)
			(layer "B.Fab")
			(hide yes)
			(effects
				(font
					(size 1 1)
					(thickness 0.15)
				)
				(justify mirror)
			)
		)
		(property "Voltage" "25V"
			(at 0 0 180)
			(unlocked yes)
			(layer "B.Fab")
			(hide yes)
			(effects
				(font
					(size 1 1)
					(thickness 0.15)
				)
				(justify mirror)
			)
		)
		(property "Dielectric" "X5R"
			(at 0 0 180)
			(unlocked yes)
			(layer "B.Fab")
			(hide yes)
			(effects
				(font
					(size 1 1)
					(thickness 0.15)
				)
				(justify mirror)
			)
		)
		(sheetname "/X710-AT2 power/")
		(sheetfile "x710-at2-power.kicad_sch")
		(attr smd)
		(fp_rect
			(start -0.925 0.47)
			(end 0.925 -0.47)
			(stroke
				(width 0.05)
				(type default)
			)
			(fill no)
			(layer "B.CrtYd")
		)
		(fp_line
			(start 0.504 0.25)
			(end 0.504 -0.248)
			(stroke
				(width 0.15)
				(type solid)
			)
			(layer "B.Fab")
		)
		(fp_line
			(start 0.504 -0.248)
			(end -0.494 -0.248)
			(stroke
				(width 0.15)
				(type solid)
			)
			(layer "B.Fab")
		)
		(fp_line
			(start -0.494 0.25)
			(end 0.504 0.25)
			(stroke
				(width 0.15)
				(type solid)
			)
			(layer "B.Fab")
		)
		(fp_line
			(start -0.494 -0.248)
			(end -0.494 0.25)
			(stroke
				(width 0.15)
				(type solid)
			)
			(layer "B.Fab")
		)
		(fp_text user "Author: Antmicro"
			(at -0.939 -3.399 0)
			(layer "B.Fab")
			(effects
				(font
					(size 0.7 0.7)
					(thickness 0.15)
				)
				(justify left bottom mirror)
			)
		)
		(fp_text user "${REFERENCE}"
			(at -0.939 -4.599 0)
			(layer "B.Fab")
			(effects
				(font
					(size 0.7 0.7)
					(thickness 0.15)
				)
				(justify left bottom mirror)
			)
		)
		(fp_text user "License: Apache-2.0"
			(at -0.939 -5.799 0)
			(layer "B.Fab")
			(effects
				(font
					(size 0.7 0.7)
					(thickness 0.15)
				)
				(justify left bottom mirror)
			)
		)
		(pad "1" smd roundrect
			(at -0.48 0 180)
			(size 0.59 0.64)
			(layers "B.Cu" "B.Mask" "B.Paste")
			(roundrect_rratio 0.25)
			(net 23 "GND")
			(pintype "passive")
		)
		(pad "2" smd roundrect
			(at 0.48 0 180)
			(size 0.59 0.64)
			(layers "B.Cu" "B.Mask" "B.Paste")
			(roundrect_rratio 0.25)
			(net 18 "+1V88")
			(pintype "passive")
		)
	)
	(footprint "antmicro-footprints:R_0402_1005Metric"
		(layer "B.Cu")
		(at 145.031866 71.260117)
		(descr "Resistor SMD 0402")
		(tags "resistor SMD 0402")
		(property "Reference" "R125"
			(at 18.468134 8.039883 180)
			(layer "B.SilkS")
			(effects
				(font
					(size 0.7 0.7)
					(thickness 0.15)
				)
				(justify mirror)
			)
		)
		(property "Value" "R_100R_0402"
			(at -1.011843 -1.772047 180)
			(layer "B.Fab")
			(effects
				(font
					(size 0.7 0.7)
					(thickness 0.15)
				)
				(justify left bottom mirror)
			)
		)
		(property "Datasheet" "https://www.bourns.com/docs/product-datasheets/cr.pdf"
			(at 0 0 180)
			(layer "B.Fab")
			(hide yes)
			(effects
				(font
					(size 1.27 1.27)
					(thickness 0.15)
				)
				(justify mirror)
			)
		)
		(property "Description" "SMD Chip Resistor, 100 ohm, ± 1%, 62.5 mW, 0402 [1005 Metric], Thick Film, General Purpose"
			(at 0 0 180)
			(layer "B.Fab")
			(hide yes)
			(effects
				(font
					(size 1.27 1.27)
					(thickness 0.15)
				)
				(justify mirror)
			)
		)
		(property "MPN" "CR0402-FX-1000GLF"
			(at 0 0 0)
			(unlocked yes)
			(layer "B.Fab")
			(hide yes)
			(effects
				(font
					(size 1 1)
					(thickness 0.15)
				)
				(justify mirror)
			)
		)
		(property "Manufacturer" "Bourns"
			(at 0 0 0)
			(unlocked yes)
			(layer "B.Fab")
			(hide yes)
			(effects
				(font
					(size 1 1)
					(thickness 0.15)
				)
				(justify mirror)
			)
		)
		(property "License" "Apache-2.0"
			(at 0 0 0)
			(unlocked yes)
			(layer "B.Fab")
			(hide yes)
			(effects
				(font
					(size 1 1)
					(thickness 0.15)
				)
				(justify mirror)
			)
		)
		(property "Author" "Antmicro"
			(at 0 0 0)
			(unlocked yes)
			(layer "B.Fab")
			(hide yes)
			(effects
				(font
					(size 1 1)
					(thickness 0.15)
				)
				(justify mirror)
			)
		)
		(property "Val" "100R"
			(at 0 0 0)
			(unlocked yes)
			(layer "B.Fab")
			(hide yes)
			(effects
				(font
					(size 1 1)
					(thickness 0.15)
				)
				(justify mirror)
			)
		)
		(property "Tolerance" "1%"
			(at 0 0 0)
			(unlocked yes)
			(layer "B.Fab")
			(hide yes)
			(effects
				(font
					(size 1 1)
					(thickness 0.15)
				)
				(justify mirror)
			)
		)
		(sheetname "/X710-AT2 RSVD/")
		(sheetfile "x710-at2-rsvd.kicad_sch")
		(attr smd)
		(fp_rect
			(start -0.925 0.47)
			(end 0.925 -0.47)
			(stroke
				(width 0.05)
				(type default)
			)
			(fill no)
			(layer "B.CrtYd")
		)
		(fp_rect
			(start -0.5 0.25)
			(end 0.5 -0.25)
			(stroke
				(width 0.15)
				(type solid)
			)
			(fill no)
			(layer "B.Fab")
		)
		(fp_text user "License: Apache-2.0"
			(at -0.95 -5.169 180)
			(layer "B.Fab")
			(effects
				(font
					(size 0.7 0.7)
					(thickness 0.15)
				)
				(justify left bottom mirror)
			)
		)
		(fp_text user "${REFERENCE}"
			(at -0.95 -3.168 180)
			(layer "B.Fab")
			(effects
				(font
					(size 0.7 0.7)
					(thickness 0.15)
				)
				(justify left bottom mirror)
			)
		)
		(fp_text user "Author: Antmicro"
			(at -0.95 -4.169 180)
			(layer "B.Fab")
			(effects
				(font
					(size 0.7 0.7)
					(thickness 0.15)
				)
				(justify left bottom mirror)
			)
		)
		(pad "1" smd roundrect
			(at -0.48 0)
			(size 0.59 0.64)
			(layers "B.Cu" "B.Mask" "B.Paste")
			(roundrect_rratio 0.25)
			(net 23 "GND")
			(pintype "passive")
		)
		(pad "2" smd roundrect
			(at 0.48 0)
			(size 0.59 0.64)
			(layers "B.Cu" "B.Mask" "B.Paste")
			(roundrect_rratio 0.25)
			(net 96 "/X710-AT2 RSVD/RSVDW1_VSS")
			(pintype "passive")
		)
	)
	(footprint "antmicro-footprints:C_0402_1005Metric"
		(layer "B.Cu")
		(at 148.431866 86.935117 180)
		(descr "Capacitor SMD 0402")
		(tags "capacitor SMD 0402")
		(property "Reference" "C253"
			(at -17.975 -9.475 0)
			(layer "B.SilkS")
			(effects
				(font
					(size 0.7 0.7)
					(thickness 0.15)
				)
				(justify mirror)
			)
		)
		(property "Value" "C_1u_25V_0402"
			(at -1.022927 -2.155213 0)
			(layer "B.Fab")
			(effects
				(font
					(size 0.7 0.7)
					(thickness 0.15)
				)
				(justify left bottom mirror)
			)
		)
		(property "Datasheet" "https://www.murata.com/products/productdetail?partno=GRM155R61E105KE11%23"
			(at 0 0 0)
			(layer "B.Fab")
			(hide yes)
			(effects
				(font
					(size 1.27 1.27)
					(thickness 0.15)
				)
				(justify mirror)
			)
		)
		(property "Description" "SMD Multilayer Ceramic Capacitor, 1 µF, 25 V, 0402 [1005 Metric], ± 10%, X5R, GRM Series"
			(at 0 0 0)
			(layer "B.Fab")
			(hide yes)
			(effects
				(font
					(size 1.27 1.27)
					(thickness 0.15)
				)
				(justify mirror)
			)
		)
		(property "MPN" "GRM155R61E105KE11J"
			(at 0 0 180)
			(unlocked yes)
			(layer "B.Fab")
			(hide yes)
			(effects
				(font
					(size 1 1)
					(thickness 0.15)
				)
				(justify mirror)
			)
		)
		(property "Manufacturer" "Murata"
			(at 0 0 180)
			(unlocked yes)
			(layer "B.Fab")
			(hide yes)
			(effects
				(font
					(size 1 1)
					(thickness 0.15)
				)
				(justify mirror)
			)
		)
		(property "License" "Apache-2.0"
			(at 0 0 180)
			(unlocked yes)
			(layer "B.Fab")
			(hide yes)
			(effects
				(font
					(size 1 1)
					(thickness 0.15)
				)
				(justify mirror)
			)
		)
		(property "Author" "Antmicro"
			(at 0 0 180)
			(unlocked yes)
			(layer "B.Fab")
			(hide yes)
			(effects
				(font
					(size 1 1)
					(thickness 0.15)
				)
				(justify mirror)
			)
		)
		(property "Val" "1u"
			(at 0 0 180)
			(unlocked yes)
			(layer "B.Fab")
			(hide yes)
			(effects
				(font
					(size 1 1)
					(thickness 0.15)
				)
				(justify mirror)
			)
		)
		(property "Voltage" "25V"
			(at 0 0 180)
			(unlocked yes)
			(layer "B.Fab")
			(hide yes)
			(effects
				(font
					(size 1 1)
					(thickness 0.15)
				)
				(justify mirror)
			)
		)
		(property "Dielectric" "X5R"
			(at 0 0 180)
			(unlocked yes)
			(layer "B.Fab")
			(hide yes)
			(effects
				(font
					(size 1 1)
					(thickness 0.15)
				)
				(justify mirror)
			)
		)
		(sheetname "/X710-AT2 power/")
		(sheetfile "x710-at2-power.kicad_sch")
		(attr smd)
		(fp_rect
			(start -0.925 0.47)
			(end 0.925 -0.47)
			(stroke
				(width 0.05)
				(type default)
			)
			(fill no)
			(layer "B.CrtYd")
		)
		(fp_line
			(start 0.504 0.25)
			(end 0.504 -0.248)
			(stroke
				(width 0.15)
				(type solid)
			)
			(layer "B.Fab")
		)
		(fp_line
			(start 0.504 -0.248)
			(end -0.494 -0.248)
			(stroke
				(width 0.15)
				(type solid)
			)
			(layer "B.Fab")
		)
		(fp_line
			(start -0.494 0.25)
			(end 0.504 0.25)
			(stroke
				(width 0.15)
				(type solid)
			)
			(layer "B.Fab")
		)
		(fp_line
			(start -0.494 -0.248)
			(end -0.494 0.25)
			(stroke
				(width 0.15)
				(type solid)
			)
			(layer "B.Fab")
		)
		(fp_text user "${REFERENCE}"
			(at -0.939 -4.599 0)
			(layer "B.Fab")
			(effects
				(font
					(size 0.7 0.7)
					(thickness 0.15)
				)
				(justify left bottom mirror)
			)
		)
		(fp_text user "Author: Antmicro"
			(at -0.939 -3.399 0)
			(layer "B.Fab")
			(effects
				(font
					(size 0.7 0.7)
					(thickness 0.15)
				)
				(justify left bottom mirror)
			)
		)
		(fp_text user "License: Apache-2.0"
			(at -0.939 -5.799 0)
			(layer "B.Fab")
			(effects
				(font
					(size 0.7 0.7)
					(thickness 0.15)
				)
				(justify left bottom mirror)
			)
		)
		(pad "1" smd roundrect
			(at -0.48 0 180)
			(size 0.59 0.64)
			(layers "B.Cu" "B.Mask" "B.Paste")
			(roundrect_rratio 0.25)
			(net 23 "GND")
			(pintype "passive")
		)
		(pad "2" smd roundrect
			(at 0.48 0 180)
			(size 0.59 0.64)
			(layers "B.Cu" "B.Mask" "B.Paste")
			(roundrect_rratio 0.25)
			(net 7 "+3V3")
			(pintype "passive")
		)
	)
	(footprint "antmicro-footprints:R_0402_1005Metric"
		(layer "B.Cu")
		(at 174.58 146.66 90)
		(descr "Resistor SMD 0402")
		(tags "resistor SMD 0402")
		(property "Reference" "R214"
			(at -1.09 0.42 270)
			(layer "B.SilkS")
			(effects
				(font
					(size 0.7 0.7)
					(thickness 0.15)
				)
				(justify left bottom mirror)
			)
		)
		(property "Value" "R_220R_0402"
			(at -1.011843 -1.772047 270)
			(layer "B.Fab")
			(effects
				(font
					(size 0.7 0.7)
					(thickness 0.15)
				)
				(justify left bottom mirror)
			)
		)
		(property "Datasheet" "https://www.bourns.com/docs/product-datasheets/cr.pdf"
			(at 0 0 270)
			(layer "B.Fab")
			(hide yes)
			(effects
				(font
					(size 1.27 1.27)
					(thickness 0.15)
				)
				(justify mirror)
			)
		)
		(property "Description" "SMD Chip Resistor, 220 ohm, ± 1%, 62.5 mW, 0402 [1005 Metric], Thick Film, General Purpose"
			(at 0 0 270)
			(layer "B.Fab")
			(hide yes)
			(effects
				(font
					(size 1.27 1.27)
					(thickness 0.15)
				)
				(justify mirror)
			)
		)
		(property "MPN" "CR0402-FX-2200GLF"
			(at 0 0 90)
			(unlocked yes)
			(layer "B.Fab")
			(hide yes)
			(effects
				(font
					(size 1 1)
					(thickness 0.15)
				)
				(justify mirror)
			)
		)
		(property "Manufacturer" "Bourns"
			(at 0 0 90)
			(unlocked yes)
			(layer "B.Fab")
			(hide yes)
			(effects
				(font
					(size 1 1)
					(thickness 0.15)
				)
				(justify mirror)
			)
		)
		(property "License" "Apache-2.0"
			(at 0 0 90)
			(unlocked yes)
			(layer "B.Fab")
			(hide yes)
			(effects
				(font
					(size 1 1)
					(thickness 0.15)
				)
				(justify mirror)
			)
		)
		(property "Author" "Antmicro"
			(at 0 0 90)
			(unlocked yes)
			(layer "B.Fab")
			(hide yes)
			(effects
				(font
					(size 1 1)
					(thickness 0.15)
				)
				(justify mirror)
			)
		)
		(property "Val" "220R"
			(at 0 0 90)
			(unlocked yes)
			(layer "B.Fab")
			(hide yes)
			(effects
				(font
					(size 1 1)
					(thickness 0.15)
				)
				(justify mirror)
			)
		)
		(property "Tolerance" "1%"
			(at 0 0 90)
			(unlocked yes)
			(layer "B.Fab")
			(hide yes)
			(effects
				(font
					(size 1 1)
					(thickness 0.15)
				)
				(justify mirror)
			)
		)
		(sheetname "/2xRJ45/")
		(sheetfile "2xrj45.kicad_sch")
		(attr smd)
		(fp_rect
			(start -0.925 0.47)
			(end 0.925 -0.47)
			(stroke
				(width 0.05)
				(type default)
			)
			(fill no)
			(layer "B.CrtYd")
		)
		(fp_rect
			(start -0.5 0.25)
			(end 0.5 -0.25)
			(stroke
				(width 0.15)
				(type solid)
			)
			(fill no)
			(layer "B.Fab")
		)
		(fp_text user "Author: Antmicro"
			(at -0.95 -4.169 270)
			(layer "B.Fab")
			(effects
				(font
					(size 0.7 0.7)
					(thickness 0.15)
				)
				(justify left bottom mirror)
			)
		)
		(fp_text user "${REFERENCE}"
			(at -0.95 -3.168 270)
			(layer "B.Fab")
			(effects
				(font
					(size 0.7 0.7)
					(thickness 0.15)
				)
				(justify left bottom mirror)
			)
		)
		(fp_text user "License: Apache-2.0"
			(at -0.95 -5.169 270)
			(layer "B.Fab")
			(effects
				(font
					(size 0.7 0.7)
					(thickness 0.15)
				)
				(justify left bottom mirror)
			)
		)
		(pad "1" smd roundrect
			(at -0.48 0 90)
			(size 0.59 0.64)
			(layers "B.Cu" "B.Mask" "B.Paste")
			(roundrect_rratio 0.25)
			(net 409 "Net-(J4-LED_YG_G-)")
			(pintype "passive")
		)
		(pad "2" smd roundrect
			(at 0.48 0 90)
			(size 0.59 0.64)
			(layers "B.Cu" "B.Mask" "B.Paste")
			(roundrect_rratio 0.25)
			(net 66 "/2xRJ45/~{P1_LED_LINK_10G}")
			(pintype "passive")
		)
	)
	(footprint "antmicro-footprints:R_0402_1005Metric"
		(layer "B.Cu")
		(at 152.131866 70.035117 90)
		(descr "Resistor SMD 0402")
		(tags "resistor SMD 0402")
		(property "Reference" "R194"
			(at -9.464883 19.468134 270)
			(layer "B.SilkS")
			(effects
				(font
					(size 0.7 0.7)
					(thickness 0.15)
				)
				(justify mirror)
			)
		)
		(property "Value" "R_3k3_0402"
			(at -1.011843 -1.772047 270)
			(layer "B.Fab")
			(effects
				(font
					(size 0.7 0.7)
					(thickness 0.15)
				)
				(justify left bottom mirror)
			)
		)
		(property "Datasheet" "https://www.bourns.com/docs/product-datasheets/cr.pdf"
			(at 0 0 270)
			(layer "B.Fab")
			(hide yes)
			(effects
				(font
					(size 1.27 1.27)
					(thickness 0.15)
				)
				(justify mirror)
			)
		)
		(property "Description" "SMD Chip Resistor, 3.3 kohm, ± 1%, 63 mW, 0402 [1005 Metric], Thick Film, General Purpose"
			(at 0 0 270)
			(layer "B.Fab")
			(hide yes)
			(effects
				(font
					(size 1.27 1.27)
					(thickness 0.15)
				)
				(justify mirror)
			)
		)
		(property "MPN" "CR0402-FX-3301GLF"
			(at 0 0 90)
			(unlocked yes)
			(layer "B.Fab")
			(hide yes)
			(effects
				(font
					(size 1 1)
					(thickness 0.15)
				)
				(justify mirror)
			)
		)
		(property "Manufacturer" "Bourns"
			(at 0 0 90)
			(unlocked yes)
			(layer "B.Fab")
			(hide yes)
			(effects
				(font
					(size 1 1)
					(thickness 0.15)
				)
				(justify mirror)
			)
		)
		(property "License" "Apache-2.0"
			(at 0 0 90)
			(unlocked yes)
			(layer "B.Fab")
			(hide yes)
			(effects
				(font
					(size 1 1)
					(thickness 0.15)
				)
				(justify mirror)
			)
		)
		(property "Author" "Antmicro"
			(at 0 0 90)
			(unlocked yes)
			(layer "B.Fab")
			(hide yes)
			(effects
				(font
					(size 1 1)
					(thickness 0.15)
				)
				(justify mirror)
			)
		)
		(property "Val" "3k3"
			(at 0 0 90)
			(unlocked yes)
			(layer "B.Fab")
			(hide yes)
			(effects
				(font
					(size 1 1)
					(thickness 0.15)
				)
				(justify mirror)
			)
		)
		(property "Tolerance" "1%"
			(at 0 0 90)
			(unlocked yes)
			(layer "B.Fab")
			(hide yes)
			(effects
				(font
					(size 1 1)
					(thickness 0.15)
				)
				(justify mirror)
			)
		)
		(sheetname "/X710-AT2 10GbE/")
		(sheetfile "x710-at2-10gbe.kicad_sch")
		(attr smd)
		(fp_rect
			(start -0.925 0.47)
			(end 0.925 -0.47)
			(stroke
				(width 0.05)
				(type default)
			)
			(fill no)
			(layer "B.CrtYd")
		)
		(fp_rect
			(start -0.5 0.25)
			(end 0.5 -0.25)
			(stroke
				(width 0.15)
				(type solid)
			)
			(fill no)
			(layer "B.Fab")
		)
		(fp_text user "Author: Antmicro"
			(at -0.95 -4.169 270)
			(layer "B.Fab")
			(effects
				(font
					(size 0.7 0.7)
					(thickness 0.15)
				)
				(justify left bottom mirror)
			)
		)
		(fp_text user "License: Apache-2.0"
			(at -0.95 -5.169 270)
			(layer "B.Fab")
			(effects
				(font
					(size 0.7 0.7)
					(thickness 0.15)
				)
				(justify left bottom mirror)
			)
		)
		(fp_text user "${REFERENCE}"
			(at -0.95 -3.168 270)
			(layer "B.Fab")
			(effects
				(font
					(size 0.7 0.7)
					(thickness 0.15)
				)
				(justify left bottom mirror)
			)
		)
		(pad "1" smd roundrect
			(at -0.48 0 90)
			(size 0.59 0.64)
			(layers "B.Cu" "B.Mask" "B.Paste")
			(roundrect_rratio 0.25)
			(net 76 "/X710-AT2 10GbE/MDIO2_SDA2")
			(pintype "passive")
		)
		(pad "2" smd roundrect
			(at 0.48 0 90)
			(size 0.59 0.64)
			(layers "B.Cu" "B.Mask" "B.Paste")
			(roundrect_rratio 0.25)
			(net 7 "+3V3")
			(pintype "passive")
		)
	)
	(footprint "antmicro-footprints:TP_SMD_0.75mm"
		(layer "B.Cu")
		(at 159.731866 65.935117 90)
		(property "Reference" "TP24"
			(at -0.064883 3.268134 180)
			(layer "B.SilkS")
			(effects
				(font
					(size 0.7 0.7)
					(thickness 0.15)
				)
				(justify left bottom mirror)
			)
		)
		(property "Value" "TP_0.75mm_SMD"
			(at 0 -1.2 270)
			(layer "B.Fab")
			(effects
				(font
					(size 0.7 0.7)
					(thickness 0.15)
				)
				(justify left bottom mirror)
			)
		)
		(property "Description" "SMT test point"
			(at 0 0 270)
			(layer "B.Fab")
			(hide yes)
			(effects
				(font
					(size 1.27 1.27)
					(thickness 0.15)
				)
				(justify mirror)
			)
		)
		(property "MPN" ""
			(at 0 0 90)
			(unlocked yes)
			(layer "B.Fab")
			(hide yes)
			(effects
				(font
					(size 1 1)
					(thickness 0.15)
				)
				(justify mirror)
			)
		)
		(property "Manufacturer" ""
			(at 0 0 90)
			(unlocked yes)
			(layer "B.Fab")
			(hide yes)
			(effects
				(font
					(size 1 1)
					(thickness 0.15)
				)
				(justify mirror)
			)
		)
		(property "Author" "Antmicro"
			(at 0 0 90)
			(unlocked yes)
			(layer "B.Fab")
			(hide yes)
			(effects
				(font
					(size 1 1)
					(thickness 0.15)
				)
				(justify mirror)
			)
		)
		(property "License" "Apache-2.0"
			(at 0 0 90)
			(unlocked yes)
			(layer "B.Fab")
			(hide yes)
			(effects
				(font
					(size 1 1)
					(thickness 0.15)
				)
				(justify mirror)
			)
		)
		(sheetname "/X710-AT2 Misc/")
		(sheetfile "x710-at2-mics.kicad_sch")
		(attr exclude_from_pos_files exclude_from_bom)
		(fp_circle
			(center 0 0)
			(end 0.475 0)
			(stroke
				(width 0.05)
				(type default)
			)
			(fill no)
			(layer "B.CrtYd")
		)
		(fp_text user "License: Apache-2.0"
			(at -0.4 -5.101 270)
			(layer "B.Fab")
			(effects
				(font
					(size 0.7 0.7)
					(thickness 0.15)
				)
				(justify left bottom mirror)
			)
		)
		(fp_text user "Author: Antmicro"
			(at -0.4 -3.901 270)
			(layer "B.Fab")
			(effects
				(font
					(size 0.7 0.7)
					(thickness 0.15)
				)
				(justify left bottom mirror)
			)
		)
		(fp_text user "${REFERENCE}"
			(at -0.4 -2.7 270)
			(layer "B.Fab")
			(effects
				(font
					(size 0.7 0.7)
					(thickness 0.15)
				)
				(justify left bottom mirror)
			)
		)
		(pad "1" smd circle
			(at 0 0 90)
			(size 0.75 0.75)
			(layers "B.Cu" "B.Mask")
			(net 142 "/X710-AT2 Misc/NCSI.CRS_DV")
			(pinfunction "1")
			(pintype "passive")
		)
	)
	(footprint "antmicro-footprints:SOD-523"
		(layer "B.Cu")
		(at 121.5 81.1)
		(property "Reference" "D13"
			(at 0.9 -0.8 180)
			(layer "B.SilkS")
			(effects
				(font
					(size 0.7 0.7)
					(thickness 0.15)
				)
				(justify left bottom mirror)
			)
		)
		(property "Value" "PESD5Z5_0F"
			(at 0 -1.499 180)
			(layer "B.Fab")
			(effects
				(font
					(size 0.7 0.7)
					(thickness 0.15)
				)
				(justify left bottom mirror)
			)
		)
		(property "Datasheet" "https://assets.nexperia.com/documents/data-sheet/PESD5Z5_0.pdf"
			(at 0 0 180)
			(layer "B.Fab")
			(hide yes)
			(effects
				(font
					(size 1.27 1.27)
					(thickness 0.15)
				)
				(justify mirror)
			)
		)
		(property "Description" "Unidirectional TVS, 30 kV,  SOD-523, 5 V, 89 pF"
			(at 0 0 180)
			(layer "B.Fab")
			(hide yes)
			(effects
				(font
					(size 1.27 1.27)
					(thickness 0.15)
				)
				(justify mirror)
			)
		)
		(property "Manufacturer" "Nexperia"
			(at 0 0 0)
			(unlocked yes)
			(layer "B.Fab")
			(hide yes)
			(effects
				(font
					(size 1 1)
					(thickness 0.15)
				)
				(justify mirror)
			)
		)
		(property "MPN" "PESD5Z5.0F"
			(at 0 0 0)
			(unlocked yes)
			(layer "B.Fab")
			(hide yes)
			(effects
				(font
					(size 1 1)
					(thickness 0.15)
				)
				(justify mirror)
			)
		)
		(property "Author" "Antmicro"
			(at 0 0 0)
			(unlocked yes)
			(layer "B.Fab")
			(hide yes)
			(effects
				(font
					(size 1 1)
					(thickness 0.15)
				)
				(justify mirror)
			)
		)
		(property "License" "Apache-2.0"
			(at 0 0 0)
			(unlocked yes)
			(layer "B.Fab")
			(hide yes)
			(effects
				(font
					(size 1 1)
					(thickness 0.15)
				)
				(justify mirror)
			)
		)
		(sheetname "/Fan controller/")
		(sheetfile "fan-controller.kicad_sch")
		(attr smd)
		(fp_line
			(start -0.35 0.5)
			(end -0.35 -0.5)
			(stroke
				(width 0.15)
				(type solid)
			)
			(layer "B.SilkS")
		)
		(fp_rect
			(start -1 0.6)
			(end 1 -0.6)
			(stroke
				(width 0.05)
				(type solid)
			)
			(fill no)
			(layer "B.CrtYd")
		)
		(fp_line
			(start -0.652 -0.423)
			(end -0.652 0.425)
			(stroke
				(width 0.15)
				(type solid)
			)
			(layer "B.Fab")
		)
		(fp_line
			(start -0.652 -0.423)
			(end 0.65 -0.423)
			(stroke
				(width 0.15)
				(type solid)
			)
			(layer "B.Fab")
		)
		(fp_line
			(start -0.652 0.425)
			(end 0.65 0.425)
			(stroke
				(width 0.15)
				(type solid)
			)
			(layer "B.Fab")
		)
		(fp_line
			(start -0.35 0.4)
			(end -0.35 -0.4)
			(stroke
				(width 0.15)
				(type solid)
			)
			(layer "B.Fab")
		)
		(fp_line
			(start 0.65 0.425)
			(end 0.65 -0.423)
			(stroke
				(width 0.15)
				(type solid)
			)
			(layer "B.Fab")
		)
		(fp_text user "${REFERENCE}"
			(at -1.276 -3.499 180)
			(layer "B.Fab")
			(effects
				(font
					(size 0.7 0.7)
					(thickness 0.15)
				)
				(justify left bottom mirror)
			)
		)
		(fp_text user "License: Apache-2.0"
			(at -1.276 -5.9 180)
			(layer "B.Fab")
			(effects
				(font
					(size 0.7 0.7)
					(thickness 0.15)
				)
				(justify left bottom mirror)
			)
		)
		(fp_text user "Author: Antmicro"
			(at -1.276 -4.7 180)
			(layer "B.Fab")
			(effects
				(font
					(size 0.7 0.7)
					(thickness 0.15)
				)
				(justify left bottom mirror)
			)
		)
		(pad "1" smd roundrect
			(at -0.701 0)
			(size 0.5 0.6)
			(layers "B.Cu" "B.Mask" "B.Paste")
			(roundrect_rratio 0.25)
			(net 40 "+5V")
			(pinfunction "C")
			(pintype "passive")
		)
		(pad "2" smd roundrect
			(at 0.699 0)
			(size 0.5 0.6)
			(layers "B.Cu" "B.Mask" "B.Paste")
			(roundrect_rratio 0.25)
			(net 23 "GND")
			(pinfunction "A")
			(pintype "passive")
		)
	)
	(footprint "antmicro-footprints:R_0402_1005Metric"
		(layer "B.Cu")
		(at 136.500001 115.1 180)
		(descr "Resistor SMD 0402")
		(tags "resistor SMD 0402")
		(property "Reference" "R34"
			(at -19.525001 7.450001 0)
			(layer "B.SilkS")
			(effects
				(font
					(size 0.7 0.7)
					(thickness 0.15)
				)
				(justify mirror)
			)
		)
		(property "Value" "R_100k_0402"
			(at -1.011843 -1.772047 0)
			(layer "B.Fab")
			(effects
				(font
					(size 0.7 0.7)
					(thickness 0.15)
				)
				(justify left bottom mirror)
			)
		)
		(property "Datasheet" "https://www.bourns.com/docs/product-datasheets/cr.pdf"
			(at 0 0 0)
			(layer "B.Fab")
			(hide yes)
			(effects
				(font
					(size 1.27 1.27)
					(thickness 0.15)
				)
				(justify mirror)
			)
		)
		(property "Description" "SMD Chip Resistor, 100 kohm, ± 1%, 62.5 mW, 0402 [1005 Metric], Thick Film, General Purpose"
			(at 0 0 0)
			(layer "B.Fab")
			(hide yes)
			(effects
				(font
					(size 1.27 1.27)
					(thickness 0.15)
				)
				(justify mirror)
			)
		)
		(property "MPN" "CR0402-FX-1003GLF"
			(at 0 0 180)
			(unlocked yes)
			(layer "B.Fab")
			(hide yes)
			(effects
				(font
					(size 1 1)
					(thickness 0.15)
				)
				(justify mirror)
			)
		)
		(property "Manufacturer" "Bourns"
			(at 0 0 180)
			(unlocked yes)
			(layer "B.Fab")
			(hide yes)
			(effects
				(font
					(size 1 1)
					(thickness 0.15)
				)
				(justify mirror)
			)
		)
		(property "License" "Apache-2.0"
			(at 0 0 180)
			(unlocked yes)
			(layer "B.Fab")
			(hide yes)
			(effects
				(font
					(size 1 1)
					(thickness 0.15)
				)
				(justify mirror)
			)
		)
		(property "Val" "100k"
			(at 0 0 180)
			(unlocked yes)
			(layer "B.Fab")
			(hide yes)
			(effects
				(font
					(size 1 1)
					(thickness 0.15)
				)
				(justify mirror)
			)
		)
		(property "Tolerance" "1%"
			(at 0 0 180)
			(unlocked yes)
			(layer "B.Fab")
			(hide yes)
			(effects
				(font
					(size 1 1)
					(thickness 0.15)
				)
				(justify mirror)
			)
		)
		(property "Author" "Antmicro"
			(at 0 0 180)
			(unlocked yes)
			(layer "B.Fab")
			(hide yes)
			(effects
				(font
					(size 1 1)
					(thickness 0.15)
				)
				(justify mirror)
			)
		)
		(sheetname "/TB Controller/")
		(sheetfile "tb.kicad_sch")
		(attr smd)
		(fp_rect
			(start -0.925 0.47)
			(end 0.925 -0.47)
			(stroke
				(width 0.05)
				(type default)
			)
			(fill no)
			(layer "B.CrtYd")
		)
		(fp_rect
			(start -0.5 0.25)
			(end 0.5 -0.25)
			(stroke
				(width 0.15)
				(type solid)
			)
			(fill no)
			(layer "B.Fab")
		)
		(fp_text user "License: Apache-2.0"
			(at -0.95 -5.169 0)
			(layer "B.Fab")
			(effects
				(font
					(size 0.7 0.7)
					(thickness 0.15)
				)
				(justify left bottom mirror)
			)
		)
		(fp_text user "Author: Antmicro"
			(at -0.95 -4.169 0)
			(layer "B.Fab")
			(effects
				(font
					(size 0.7 0.7)
					(thickness 0.15)
				)
				(justify left bottom mirror)
			)
		)
		(fp_text user "${REFERENCE}"
			(at -0.95 -3.168 0)
			(layer "B.Fab")
			(effects
				(font
					(size 0.7 0.7)
					(thickness 0.15)
				)
				(justify left bottom mirror)
			)
		)
		(pad "1" smd roundrect
			(at -0.48 0 180)
			(size 0.59 0.64)
			(layers "B.Cu" "B.Mask" "B.Paste")
			(roundrect_rratio 0.25)
			(net 23 "GND")
			(pintype "passive")
		)
		(pad "2" smd roundrect
			(at 0.48 0 180)
			(size 0.59 0.64)
			(layers "B.Cu" "B.Mask" "B.Paste")
			(roundrect_rratio 0.25)
			(net 217 "Net-(U4C-DPSNK0_HPD)")
			(pintype "passive")
		)
	)
	(footprint "antmicro-footprints:R_0402_1005Metric"
		(layer "B.Cu")
		(at 151.131866 70.035117 90)
		(descr "Resistor SMD 0402")
		(tags "resistor SMD 0402")
		(property "Reference" "R192"
			(at -9.464883 19.468134 270)
			(layer "B.SilkS")
			(effects
				(font
					(size 0.7 0.7)
					(thickness 0.15)
				)
				(justify mirror)
			)
		)
		(property "Value" "R_3k3_0402"
			(at -1.011843 -1.772047 270)
			(layer "B.Fab")
			(effects
				(font
					(size 0.7 0.7)
					(thickness 0.15)
				)
				(justify left bottom mirror)
			)
		)
		(property "Datasheet" "https://www.bourns.com/docs/product-datasheets/cr.pdf"
			(at 0 0 270)
			(layer "B.Fab")
			(hide yes)
			(effects
				(font
					(size 1.27 1.27)
					(thickness 0.15)
				)
				(justify mirror)
			)
		)
		(property "Description" "SMD Chip Resistor, 3.3 kohm, ± 1%, 63 mW, 0402 [1005 Metric], Thick Film, General Purpose"
			(at 0 0 270)
			(layer "B.Fab")
			(hide yes)
			(effects
				(font
					(size 1.27 1.27)
					(thickness 0.15)
				)
				(justify mirror)
			)
		)
		(property "MPN" "CR0402-FX-3301GLF"
			(at 0 0 90)
			(unlocked yes)
			(layer "B.Fab")
			(hide yes)
			(effects
				(font
					(size 1 1)
					(thickness 0.15)
				)
				(justify mirror)
			)
		)
		(property "Manufacturer" "Bourns"
			(at 0 0 90)
			(unlocked yes)
			(layer "B.Fab")
			(hide yes)
			(effects
				(font
					(size 1 1)
					(thickness 0.15)
				)
				(justify mirror)
			)
		)
		(property "License" "Apache-2.0"
			(at 0 0 90)
			(unlocked yes)
			(layer "B.Fab")
			(hide yes)
			(effects
				(font
					(size 1 1)
					(thickness 0.15)
				)
				(justify mirror)
			)
		)
		(property "Author" "Antmicro"
			(at 0 0 90)
			(unlocked yes)
			(layer "B.Fab")
			(hide yes)
			(effects
				(font
					(size 1 1)
					(thickness 0.15)
				)
				(justify mirror)
			)
		)
		(property "Val" "3k3"
			(at 0 0 90)
			(unlocked yes)
			(layer "B.Fab")
			(hide yes)
			(effects
				(font
					(size 1 1)
					(thickness 0.15)
				)
				(justify mirror)
			)
		)
		(property "Tolerance" "1%"
			(at 0 0 90)
			(unlocked yes)
			(layer "B.Fab")
			(hide yes)
			(effects
				(font
					(size 1 1)
					(thickness 0.15)
				)
				(justify mirror)
			)
		)
		(sheetname "/X710-AT2 10GbE/")
		(sheetfile "x710-at2-10gbe.kicad_sch")
		(attr smd)
		(fp_rect
			(start -0.925 0.47)
			(end 0.925 -0.47)
			(stroke
				(width 0.05)
				(type default)
			)
			(fill no)
			(layer "B.CrtYd")
		)
		(fp_rect
			(start -0.5 0.25)
			(end 0.5 -0.25)
			(stroke
				(width 0.15)
				(type solid)
			)
			(fill no)
			(layer "B.Fab")
		)
		(fp_text user "Author: Antmicro"
			(at -0.95 -4.169 270)
			(layer "B.Fab")
			(effects
				(font
					(size 0.7 0.7)
					(thickness 0.15)
				)
				(justify left bottom mirror)
			)
		)
		(fp_text user "${REFERENCE}"
			(at -0.95 -3.168 270)
			(layer "B.Fab")
			(effects
				(font
					(size 0.7 0.7)
					(thickness 0.15)
				)
				(justify left bottom mirror)
			)
		)
		(fp_text user "License: Apache-2.0"
			(at -0.95 -5.169 270)
			(layer "B.Fab")
			(effects
				(font
					(size 0.7 0.7)
					(thickness 0.15)
				)
				(justify left bottom mirror)
			)
		)
		(pad "1" smd roundrect
			(at -0.48 0 90)
			(size 0.59 0.64)
			(layers "B.Cu" "B.Mask" "B.Paste")
			(roundrect_rratio 0.25)
			(net 72 "/X710-AT2 10GbE/MDC2_SCL2")
			(pintype "passive")
		)
		(pad "2" smd roundrect
			(at 0.48 0 90)
			(size 0.59 0.64)
			(layers "B.Cu" "B.Mask" "B.Paste")
			(roundrect_rratio 0.25)
			(net 7 "+3V3")
			(pintype "passive")
		)
	)
	(footprint "antmicro-footprints:C_0402_1005Metric"
		(layer "B.Cu")
		(at 171.58 146.66 -90)
		(descr "Capacitor SMD 0402")
		(tags "capacitor SMD 0402")
		(property "Reference" "C307"
			(at 1.09 -0.42 90)
			(layer "B.SilkS")
			(effects
				(font
					(size 0.7 0.7)
					(thickness 0.15)
				)
				(justify left bottom mirror)
			)
		)
		(property "Value" "C_470p_0402"
			(at -1.022927 -2.155213 90)
			(layer "B.Fab")
			(effects
				(font
					(size 0.7 0.7)
					(thickness 0.15)
				)
				(justify left bottom mirror)
			)
		)
		(property "Datasheet" "https://www.passivecomponent.com/wp-content/uploads/datasheet/WTC_MLCC_General_Purpose.pdf"
			(at 0 0 90)
			(layer "B.Fab")
			(hide yes)
			(effects
				(font
					(size 1.27 1.27)
					(thickness 0.15)
				)
				(justify mirror)
			)
		)
		(property "Description" "SMD Multilayer Ceramic Capacitor, General Purpose, 470 pF, 25 V, 0402 [1005 Metric], ± 10%, X7R"
			(at 0 0 90)
			(layer "B.Fab")
			(hide yes)
			(effects
				(font
					(size 1.27 1.27)
					(thickness 0.15)
				)
				(justify mirror)
			)
		)
		(property "MPN" "0402B471K250CT"
			(at 0 0 270)
			(unlocked yes)
			(layer "B.Fab")
			(hide yes)
			(effects
				(font
					(size 1 1)
					(thickness 0.15)
				)
				(justify mirror)
			)
		)
		(property "Manufacturer" "Walsin"
			(at 0 0 270)
			(unlocked yes)
			(layer "B.Fab")
			(hide yes)
			(effects
				(font
					(size 1 1)
					(thickness 0.15)
				)
				(justify mirror)
			)
		)
		(property "License" "Apache-2.0"
			(at 0 0 270)
			(unlocked yes)
			(layer "B.Fab")
			(hide yes)
			(effects
				(font
					(size 1 1)
					(thickness 0.15)
				)
				(justify mirror)
			)
		)
		(property "Author" "Antmicro"
			(at 0 0 270)
			(unlocked yes)
			(layer "B.Fab")
			(hide yes)
			(effects
				(font
					(size 1 1)
					(thickness 0.15)
				)
				(justify mirror)
			)
		)
		(property "Val" "470p"
			(at 0 0 270)
			(unlocked yes)
			(layer "B.Fab")
			(hide yes)
			(effects
				(font
					(size 1 1)
					(thickness 0.15)
				)
				(justify mirror)
			)
		)
		(property "Voltage" "25V"
			(at 0 0 270)
			(unlocked yes)
			(layer "B.Fab")
			(hide yes)
			(effects
				(font
					(size 1 1)
					(thickness 0.15)
				)
				(justify mirror)
			)
		)
		(property "Dielectric" "X7R"
			(at 0 0 270)
			(unlocked yes)
			(layer "B.Fab")
			(hide yes)
			(effects
				(font
					(size 1 1)
					(thickness 0.15)
				)
				(justify mirror)
			)
		)
		(sheetname "/2xRJ45/")
		(sheetfile "2xrj45.kicad_sch")
		(attr smd)
		(fp_rect
			(start -0.925 0.47)
			(end 0.925 -0.47)
			(stroke
				(width 0.05)
				(type default)
			)
			(fill no)
			(layer "B.CrtYd")
		)
		(fp_line
			(start -0.494 0.25)
			(end 0.504 0.25)
			(stroke
				(width 0.15)
				(type solid)
			)
			(layer "B.Fab")
		)
		(fp_line
			(start 0.504 0.25)
			(end 0.504 -0.248)
			(stroke
				(width 0.15)
				(type solid)
			)
			(layer "B.Fab")
		)
		(fp_line
			(start -0.494 -0.248)
			(end -0.494 0.25)
			(stroke
				(width 0.15)
				(type solid)
			)
			(layer "B.Fab")
		)
		(fp_line
			(start 0.504 -0.248)
			(end -0.494 -0.248)
			(stroke
				(width 0.15)
				(type solid)
			)
			(layer "B.Fab")
		)
		(fp_text user "Author: Antmicro"
			(at -0.939 -3.399 90)
			(layer "B.Fab")
			(effects
				(font
					(size 0.7 0.7)
					(thickness 0.15)
				)
				(justify left bottom mirror)
			)
		)
		(fp_text user "${REFERENCE}"
			(at -0.939 -4.599 90)
			(layer "B.Fab")
			(effects
				(font
					(size 0.7 0.7)
					(thickness 0.15)
				)
				(justify left bottom mirror)
			)
		)
		(fp_text user "License: Apache-2.0"
			(at -0.939 -5.799 90)
			(layer "B.Fab")
			(effects
				(font
					(size 0.7 0.7)
					(thickness 0.15)
				)
				(justify left bottom mirror)
			)
		)
		(pad "1" smd roundrect
			(at -0.48 0 270)
			(size 0.59 0.64)
			(layers "B.Cu" "B.Mask" "B.Paste")
			(roundrect_rratio 0.25)
			(net 23 "GND")
			(pintype "passive")
		)
		(pad "2" smd roundrect
			(at 0.48 0 270)
			(size 0.59 0.64)
			(layers "B.Cu" "B.Mask" "B.Paste")
			(roundrect_rratio 0.25)
			(net 411 "Net-(J4-LED_GRN-)")
			(pintype "passive")
		)
	)
	(footprint "antmicro-footprints:C_0402_1005Metric"
		(layer "B.Cu")
		(at 139.4 105 90)
		(descr "Capacitor SMD 0402")
		(tags "capacitor SMD 0402")
		(property "Reference" "C150"
			(at 1.4 -0.6 270)
			(layer "B.SilkS")
			(effects
				(font
					(size 0.7 0.7)
					(thickness 0.15)
				)
				(justify left bottom mirror)
			)
		)
		(property "Value" "C_100n_0402"
			(at -1.022927 -2.155213 270)
			(layer "B.Fab")
			(effects
				(font
					(size 0.7 0.7)
					(thickness 0.15)
				)
				(justify left bottom mirror)
			)
		)
		(property "Datasheet" "https://www.murata.com/products/productdetail?partno=GRM155R61H104KE14%23"
			(at 0 0 270)
			(layer "B.Fab")
			(hide yes)
			(effects
				(font
					(size 1.27 1.27)
					(thickness 0.15)
				)
				(justify mirror)
			)
		)
		(property "Description" "SMD Multilayer Ceramic Capacitor, 0.1 µF, 50 V, 0402 [1005 Metric], ± 10%, X5R, GRM Series"
			(at 0 0 270)
			(layer "B.Fab")
			(hide yes)
			(effects
				(font
					(size 1.27 1.27)
					(thickness 0.15)
				)
				(justify mirror)
			)
		)
		(property "MPN" "GRM155R61H104KE14D"
			(at 0 0 90)
			(unlocked yes)
			(layer "B.Fab")
			(hide yes)
			(effects
				(font
					(size 1 1)
					(thickness 0.15)
				)
				(justify mirror)
			)
		)
		(property "Manufacturer" "Murata"
			(at 0 0 90)
			(unlocked yes)
			(layer "B.Fab")
			(hide yes)
			(effects
				(font
					(size 1 1)
					(thickness 0.15)
				)
				(justify mirror)
			)
		)
		(property "License" "Apache-2.0"
			(at 0 0 90)
			(unlocked yes)
			(layer "B.Fab")
			(hide yes)
			(effects
				(font
					(size 1 1)
					(thickness 0.15)
				)
				(justify mirror)
			)
		)
		(property "Author" "Antmicro"
			(at 0 0 90)
			(unlocked yes)
			(layer "B.Fab")
			(hide yes)
			(effects
				(font
					(size 1 1)
					(thickness 0.15)
				)
				(justify mirror)
			)
		)
		(property "Val" "100n"
			(at 0 0 90)
			(unlocked yes)
			(layer "B.Fab")
			(hide yes)
			(effects
				(font
					(size 1 1)
					(thickness 0.15)
				)
				(justify mirror)
			)
		)
		(property "Voltage" "50V"
			(at 0 0 90)
			(unlocked yes)
			(layer "B.Fab")
			(hide yes)
			(effects
				(font
					(size 1 1)
					(thickness 0.15)
				)
				(justify mirror)
			)
		)
		(property "Dielectric" "X5R"
			(at 0 0 90)
			(unlocked yes)
			(layer "B.Fab")
			(hide yes)
			(effects
				(font
					(size 1 1)
					(thickness 0.15)
				)
				(justify mirror)
			)
		)
		(sheetname "/X710 DCDC converters/")
		(sheetfile "DCDC_converters_X710.kicad_sch")
		(attr smd)
		(fp_rect
			(start -0.925 0.47)
			(end 0.925 -0.47)
			(stroke
				(width 0.05)
				(type default)
			)
			(fill no)
			(layer "B.CrtYd")
		)
		(fp_line
			(start 0.504 -0.248)
			(end -0.494 -0.248)
			(stroke
				(width 0.15)
				(type solid)
			)
			(layer "B.Fab")
		)
		(fp_line
			(start -0.494 -0.248)
			(end -0.494 0.25)
			(stroke
				(width 0.15)
				(type solid)
			)
			(layer "B.Fab")
		)
		(fp_line
			(start 0.504 0.25)
			(end 0.504 -0.248)
			(stroke
				(width 0.15)
				(type solid)
			)
			(layer "B.Fab")
		)
		(fp_line
			(start -0.494 0.25)
			(end 0.504 0.25)
			(stroke
				(width 0.15)
				(type solid)
			)
			(layer "B.Fab")
		)
		(fp_text user "Author: Antmicro"
			(at -0.939 -3.399 270)
			(layer "B.Fab")
			(effects
				(font
					(size 0.7 0.7)
					(thickness 0.15)
				)
				(justify left bottom mirror)
			)
		)
		(fp_text user "License: Apache-2.0"
			(at -0.939 -5.799 270)
			(layer "B.Fab")
			(effects
				(font
					(size 0.7 0.7)
					(thickness 0.15)
				)
				(justify left bottom mirror)
			)
		)
		(fp_text user "${REFERENCE}"
			(at -0.939 -4.599 270)
			(layer "B.Fab")
			(effects
				(font
					(size 0.7 0.7)
					(thickness 0.15)
				)
				(justify left bottom mirror)
			)
		)
		(pad "1" smd roundrect
			(at -0.48 0 90)
			(size 0.59 0.64)
			(layers "B.Cu" "B.Mask" "B.Paste")
			(roundrect_rratio 0.25)
			(net 23 "GND")
			(pintype "passive")
		)
		(pad "2" smd roundrect
			(at 0.48 0 90)
			(size 0.59 0.64)
			(layers "B.Cu" "B.Mask" "B.Paste")
			(roundrect_rratio 0.25)
			(net 335 "/X710 DCDC converters/+VCCD_OUT")
			(pintype "passive")
		)
	)
	(footprint "antmicro-footprints:R_0402_1005Metric"
		(layer "B.Cu")
		(at 153.131866 70.035117 90)
		(descr "Resistor SMD 0402")
		(tags "resistor SMD 0402")
		(property "Reference" "R190"
			(at -9.464883 19.468134 270)
			(layer "B.SilkS")
			(effects
				(font
					(size 0.7 0.7)
					(thickness 0.15)
				)
				(justify mirror)
			)
		)
		(property "Value" "R_3k3_0402"
			(at -1.011843 -1.772047 270)
			(layer "B.Fab")
			(effects
				(font
					(size 0.7 0.7)
					(thickness 0.15)
				)
				(justify left bottom mirror)
			)
		)
		(property "Datasheet" "https://www.bourns.com/docs/product-datasheets/cr.pdf"
			(at 0 0 270)
			(layer "B.Fab")
			(hide yes)
			(effects
				(font
					(size 1.27 1.27)
					(thickness 0.15)
				)
				(justify mirror)
			)
		)
		(property "Description" "SMD Chip Resistor, 3.3 kohm, ± 1%, 63 mW, 0402 [1005 Metric], Thick Film, General Purpose"
			(at 0 0 270)
			(layer "B.Fab")
			(hide yes)
			(effects
				(font
					(size 1.27 1.27)
					(thickness 0.15)
				)
				(justify mirror)
			)
		)
		(property "MPN" "CR0402-FX-3301GLF"
			(at 0 0 90)
			(unlocked yes)
			(layer "B.Fab")
			(hide yes)
			(effects
				(font
					(size 1 1)
					(thickness 0.15)
				)
				(justify mirror)
			)
		)
		(property "Manufacturer" "Bourns"
			(at 0 0 90)
			(unlocked yes)
			(layer "B.Fab")
			(hide yes)
			(effects
				(font
					(size 1 1)
					(thickness 0.15)
				)
				(justify mirror)
			)
		)
		(property "License" "Apache-2.0"
			(at 0 0 90)
			(unlocked yes)
			(layer "B.Fab")
			(hide yes)
			(effects
				(font
					(size 1 1)
					(thickness 0.15)
				)
				(justify mirror)
			)
		)
		(property "Author" "Antmicro"
			(at 0 0 90)
			(unlocked yes)
			(layer "B.Fab")
			(hide yes)
			(effects
				(font
					(size 1 1)
					(thickness 0.15)
				)
				(justify mirror)
			)
		)
		(property "Val" "3k3"
			(at 0 0 90)
			(unlocked yes)
			(layer "B.Fab")
			(hide yes)
			(effects
				(font
					(size 1 1)
					(thickness 0.15)
				)
				(justify mirror)
			)
		)
		(property "Tolerance" "1%"
			(at 0 0 90)
			(unlocked yes)
			(layer "B.Fab")
			(hide yes)
			(effects
				(font
					(size 1 1)
					(thickness 0.15)
				)
				(justify mirror)
			)
		)
		(sheetname "/X710-AT2 10GbE/")
		(sheetfile "x710-at2-10gbe.kicad_sch")
		(attr smd)
		(fp_rect
			(start -0.925 0.47)
			(end 0.925 -0.47)
			(stroke
				(width 0.05)
				(type default)
			)
			(fill no)
			(layer "B.CrtYd")
		)
		(fp_rect
			(start -0.5 0.25)
			(end 0.5 -0.25)
			(stroke
				(width 0.15)
				(type solid)
			)
			(fill no)
			(layer "B.Fab")
		)
		(fp_text user "License: Apache-2.0"
			(at -0.95 -5.169 270)
			(layer "B.Fab")
			(effects
				(font
					(size 0.7 0.7)
					(thickness 0.15)
				)
				(justify left bottom mirror)
			)
		)
		(fp_text user "${REFERENCE}"
			(at -0.95 -3.168 270)
			(layer "B.Fab")
			(effects
				(font
					(size 0.7 0.7)
					(thickness 0.15)
				)
				(justify left bottom mirror)
			)
		)
		(fp_text user "Author: Antmicro"
			(at -0.95 -4.169 270)
			(layer "B.Fab")
			(effects
				(font
					(size 0.7 0.7)
					(thickness 0.15)
				)
				(justify left bottom mirror)
			)
		)
		(pad "1" smd roundrect
			(at -0.48 0 90)
			(size 0.59 0.64)
			(layers "B.Cu" "B.Mask" "B.Paste")
			(roundrect_rratio 0.25)
			(net 71 "/X710-AT2 10GbE/MDIO3_SDA3")
			(pintype "passive")
		)
		(pad "2" smd roundrect
			(at 0.48 0 90)
			(size 0.59 0.64)
			(layers "B.Cu" "B.Mask" "B.Paste")
			(roundrect_rratio 0.25)
			(net 7 "+3V3")
			(pintype "passive")
		)
	)
	(footprint "antmicro-footprints:C_0402_1005Metric"
		(layer "B.Cu")
		(at 147.481866 78.260117 180)
		(descr "Capacitor SMD 0402")
		(tags "capacitor SMD 0402")
		(property "Reference" "C251"
			(at -18.618135 -9.464883 0)
			(layer "B.SilkS")
			(effects
				(font
					(size 0.7 0.7)
					(thickness 0.15)
				)
				(justify mirror)
			)
		)
		(property "Value" "C_1u_25V_0402"
			(at -1.022927 -2.155213 0)
			(layer "B.Fab")
			(effects
				(font
					(size 0.7 0.7)
					(thickness 0.15)
				)
				(justify left bottom mirror)
			)
		)
		(property "Datasheet" "https://www.murata.com/products/productdetail?partno=GRM155R61E105KE11%23"
			(at 0 0 0)
			(layer "B.Fab")
			(hide yes)
			(effects
				(font
					(size 1.27 1.27)
					(thickness 0.15)
				)
				(justify mirror)
			)
		)
		(property "Description" "SMD Multilayer Ceramic Capacitor, 1 µF, 25 V, 0402 [1005 Metric], ± 10%, X5R, GRM Series"
			(at 0 0 0)
			(layer "B.Fab")
			(hide yes)
			(effects
				(font
					(size 1.27 1.27)
					(thickness 0.15)
				)
				(justify mirror)
			)
		)
		(property "MPN" "GRM155R61E105KE11J"
			(at 0 0 180)
			(unlocked yes)
			(layer "B.Fab")
			(hide yes)
			(effects
				(font
					(size 1 1)
					(thickness 0.15)
				)
				(justify mirror)
			)
		)
		(property "Manufacturer" "Murata"
			(at 0 0 180)
			(unlocked yes)
			(layer "B.Fab")
			(hide yes)
			(effects
				(font
					(size 1 1)
					(thickness 0.15)
				)
				(justify mirror)
			)
		)
		(property "License" "Apache-2.0"
			(at 0 0 180)
			(unlocked yes)
			(layer "B.Fab")
			(hide yes)
			(effects
				(font
					(size 1 1)
					(thickness 0.15)
				)
				(justify mirror)
			)
		)
		(property "Author" "Antmicro"
			(at 0 0 180)
			(unlocked yes)
			(layer "B.Fab")
			(hide yes)
			(effects
				(font
					(size 1 1)
					(thickness 0.15)
				)
				(justify mirror)
			)
		)
		(property "Val" "1u"
			(at 0 0 180)
			(unlocked yes)
			(layer "B.Fab")
			(hide yes)
			(effects
				(font
					(size 1 1)
					(thickness 0.15)
				)
				(justify mirror)
			)
		)
		(property "Voltage" "25V"
			(at 0 0 180)
			(unlocked yes)
			(layer "B.Fab")
			(hide yes)
			(effects
				(font
					(size 1 1)
					(thickness 0.15)
				)
				(justify mirror)
			)
		)
		(property "Dielectric" "X5R"
			(at 0 0 180)
			(unlocked yes)
			(layer "B.Fab")
			(hide yes)
			(effects
				(font
					(size 1 1)
					(thickness 0.15)
				)
				(justify mirror)
			)
		)
		(sheetname "/X710-AT2 power/")
		(sheetfile "x710-at2-power.kicad_sch")
		(attr smd)
		(fp_rect
			(start -0.925 0.47)
			(end 0.925 -0.47)
			(stroke
				(width 0.05)
				(type default)
			)
			(fill no)
			(layer "B.CrtYd")
		)
		(fp_line
			(start 0.504 0.25)
			(end 0.504 -0.248)
			(stroke
				(width 0.15)
				(type solid)
			)
			(layer "B.Fab")
		)
		(fp_line
			(start 0.504 -0.248)
			(end -0.494 -0.248)
			(stroke
				(width 0.15)
				(type solid)
			)
			(layer "B.Fab")
		)
		(fp_line
			(start -0.494 0.25)
			(end 0.504 0.25)
			(stroke
				(width 0.15)
				(type solid)
			)
			(layer "B.Fab")
		)
		(fp_line
			(start -0.494 -0.248)
			(end -0.494 0.25)
			(stroke
				(width 0.15)
				(type solid)
			)
			(layer "B.Fab")
		)
		(fp_text user "${REFERENCE}"
			(at -0.939 -4.599 0)
			(layer "B.Fab")
			(effects
				(font
					(size 0.7 0.7)
					(thickness 0.15)
				)
				(justify left bottom mirror)
			)
		)
		(fp_text user "License: Apache-2.0"
			(at -0.939 -5.799 0)
			(layer "B.Fab")
			(effects
				(font
					(size 0.7 0.7)
					(thickness 0.15)
				)
				(justify left bottom mirror)
			)
		)
		(fp_text user "Author: Antmicro"
			(at -0.939 -3.399 0)
			(layer "B.Fab")
			(effects
				(font
					(size 0.7 0.7)
					(thickness 0.15)
				)
				(justify left bottom mirror)
			)
		)
		(pad "1" smd roundrect
			(at -0.48 0 180)
			(size 0.59 0.64)
			(layers "B.Cu" "B.Mask" "B.Paste")
			(roundrect_rratio 0.25)
			(net 23 "GND")
			(pintype "passive")
		)
		(pad "2" smd roundrect
			(at 0.48 0 180)
			(size 0.59 0.64)
			(layers "B.Cu" "B.Mask" "B.Paste")
			(roundrect_rratio 0.25)
			(net 9 "VCCD")
			(pintype "passive")
		)
	)
	(footprint "antmicro-footprints:R_0402_1005Metric"
		(layer "B.Cu")
		(at 142.5 116.124996 180)
		(descr "Resistor SMD 0402")
		(tags "resistor SMD 0402")
		(property "Reference" "R63"
			(at -19.75 7.450001 0)
			(layer "B.SilkS")
			(effects
				(font
					(size 0.7 0.7)
					(thickness 0.15)
				)
				(justify mirror)
			)
		)
		(property "Value" "R_10k_0402"
			(at -1.011843 -1.772047 0)
			(layer "B.Fab")
			(effects
				(font
					(size 0.7 0.7)
					(thickness 0.15)
				)
				(justify left bottom mirror)
			)
		)
		(property "Datasheet" "https://www.bourns.com/docs/product-datasheets/cr.pdf"
			(at 0 0 0)
			(layer "B.Fab")
			(hide yes)
			(effects
				(font
					(size 1.27 1.27)
					(thickness 0.15)
				)
				(justify mirror)
			)
		)
		(property "Description" "SMD Chip Resistor, 10 kohm, ± 1%, 62.5 mW, 0402 [1005 Metric], Thick Film, General Purpose"
			(at 0 0 0)
			(layer "B.Fab")
			(hide yes)
			(effects
				(font
					(size 1.27 1.27)
					(thickness 0.15)
				)
				(justify mirror)
			)
		)
		(property "MPN" "CR0402-FX-1002GLF"
			(at 0 0 180)
			(unlocked yes)
			(layer "B.Fab")
			(hide yes)
			(effects
				(font
					(size 1 1)
					(thickness 0.15)
				)
				(justify mirror)
			)
		)
		(property "Manufacturer" "Bourns"
			(at 0 0 180)
			(unlocked yes)
			(layer "B.Fab")
			(hide yes)
			(effects
				(font
					(size 1 1)
					(thickness 0.15)
				)
				(justify mirror)
			)
		)
		(property "License" "Apache-2.0"
			(at 0 0 180)
			(unlocked yes)
			(layer "B.Fab")
			(hide yes)
			(effects
				(font
					(size 1 1)
					(thickness 0.15)
				)
				(justify mirror)
			)
		)
		(property "Val" "10k"
			(at 0 0 180)
			(unlocked yes)
			(layer "B.Fab")
			(hide yes)
			(effects
				(font
					(size 1 1)
					(thickness 0.15)
				)
				(justify mirror)
			)
		)
		(property "Tolerance" "1%"
			(at 0 0 180)
			(unlocked yes)
			(layer "B.Fab")
			(hide yes)
			(effects
				(font
					(size 1 1)
					(thickness 0.15)
				)
				(justify mirror)
			)
		)
		(property "Author" "Antmicro"
			(at 0 0 180)
			(unlocked yes)
			(layer "B.Fab")
			(hide yes)
			(effects
				(font
					(size 1 1)
					(thickness 0.15)
				)
				(justify mirror)
			)
		)
		(sheetname "/TB Controller/")
		(sheetfile "tb.kicad_sch")
		(attr smd)
		(fp_rect
			(start -0.925 0.47)
			(end 0.925 -0.47)
			(stroke
				(width 0.05)
				(type default)
			)
			(fill no)
			(layer "B.CrtYd")
		)
		(fp_rect
			(start -0.5 0.25)
			(end 0.5 -0.25)
			(stroke
				(width 0.15)
				(type solid)
			)
			(fill no)
			(layer "B.Fab")
		)
		(fp_text user "Author: Antmicro"
			(at -0.95 -4.169 0)
			(layer "B.Fab")
			(effects
				(font
					(size 0.7 0.7)
					(thickness 0.15)
				)
				(justify left bottom mirror)
			)
		)
		(fp_text user "License: Apache-2.0"
			(at -0.95 -5.169 0)
			(layer "B.Fab")
			(effects
				(font
					(size 0.7 0.7)
					(thickness 0.15)
				)
				(justify left bottom mirror)
			)
		)
		(fp_text user "${REFERENCE}"
			(at -0.95 -3.168 0)
			(layer "B.Fab")
			(effects
				(font
					(size 0.7 0.7)
					(thickness 0.15)
				)
				(justify left bottom mirror)
			)
		)
		(pad "1" smd roundrect
			(at -0.48 0 180)
			(size 0.59 0.64)
			(layers "B.Cu" "B.Mask" "B.Paste")
			(roundrect_rratio 0.25)
			(net 57 "+3V3_TB")
			(pintype "passive")
		)
		(pad "2" smd roundrect
			(at 0.48 0 180)
			(size 0.59 0.64)
			(layers "B.Cu" "B.Mask" "B.Paste")
			(roundrect_rratio 0.25)
			(net 225 "Net-(U4D-TMS)")
			(pintype "passive")
		)
	)
	(footprint "antmicro-footprints:C_0402_1005Metric"
		(layer "B.Cu")
		(at 127.049999 128.324999)
		(descr "Capacitor SMD 0402")
		(tags "capacitor SMD 0402")
		(property "Reference" "C83"
			(at 21.900002 -7.700002 180)
			(layer "B.SilkS")
			(effects
				(font
					(size 0.7 0.7)
					(thickness 0.15)
				)
				(justify mirror)
			)
		)
		(property "Value" "C_1u_0402"
			(at -1.022927 -2.155213 180)
			(layer "B.Fab")
			(effects
				(font
					(size 0.7 0.7)
					(thickness 0.15)
				)
				(justify left bottom mirror)
			)
		)
		(property "Datasheet" "https://product.tdk.com/en/search/capacitor/ceramic/mlcc/info?part_no=C1005X6S1A105K050BC"
			(at 0 0 180)
			(layer "B.Fab")
			(hide yes)
			(effects
				(font
					(size 1.27 1.27)
					(thickness 0.15)
				)
				(justify mirror)
			)
		)
		(property "Description" "SMD Multilayer Ceramic Capacitor, 1 µF, 10 V, 0402 [1005 Metric], ± 10%, X6S, C"
			(at 0 0 180)
			(layer "B.Fab")
			(hide yes)
			(effects
				(font
					(size 1.27 1.27)
					(thickness 0.15)
				)
				(justify mirror)
			)
		)
		(property "MPN" "C1005X6S1A105K050BC"
			(at 0 0 0)
			(unlocked yes)
			(layer "B.Fab")
			(hide yes)
			(effects
				(font
					(size 1 1)
					(thickness 0.15)
				)
				(justify mirror)
			)
		)
		(property "Manufacturer" "TDK"
			(at 0 0 0)
			(unlocked yes)
			(layer "B.Fab")
			(hide yes)
			(effects
				(font
					(size 1 1)
					(thickness 0.15)
				)
				(justify mirror)
			)
		)
		(property "License" "Apache-2.0"
			(at 0 0 0)
			(unlocked yes)
			(layer "B.Fab")
			(hide yes)
			(effects
				(font
					(size 1 1)
					(thickness 0.15)
				)
				(justify mirror)
			)
		)
		(property "Val" "1u"
			(at 0 0 0)
			(unlocked yes)
			(layer "B.Fab")
			(hide yes)
			(effects
				(font
					(size 1 1)
					(thickness 0.15)
				)
				(justify mirror)
			)
		)
		(property "Voltage" ""
			(at 0 0 0)
			(unlocked yes)
			(layer "B.Fab")
			(hide yes)
			(effects
				(font
					(size 1 1)
					(thickness 0.15)
				)
				(justify mirror)
			)
		)
		(property "Dielectric" ""
			(at 0 0 0)
			(unlocked yes)
			(layer "B.Fab")
			(hide yes)
			(effects
				(font
					(size 1 1)
					(thickness 0.15)
				)
				(justify mirror)
			)
		)
		(property "Author" "Antmicro"
			(at 0 0 0)
			(unlocked yes)
			(layer "B.Fab")
			(hide yes)
			(effects
				(font
					(size 1 1)
					(thickness 0.15)
				)
				(justify mirror)
			)
		)
		(sheetname "/TB Controller - Power/")
		(sheetfile "tb-power.kicad_sch")
		(attr smd)
		(fp_rect
			(start -0.925 0.47)
			(end 0.925 -0.47)
			(stroke
				(width 0.05)
				(type default)
			)
			(fill no)
			(layer "B.CrtYd")
		)
		(fp_line
			(start -0.494 -0.248)
			(end -0.494 0.25)
			(stroke
				(width 0.15)
				(type solid)
			)
			(layer "B.Fab")
		)
		(fp_line
			(start -0.494 0.25)
			(end 0.504 0.25)
			(stroke
				(width 0.15)
				(type solid)
			)
			(layer "B.Fab")
		)
		(fp_line
			(start 0.504 -0.248)
			(end -0.494 -0.248)
			(stroke
				(width 0.15)
				(type solid)
			)
			(layer "B.Fab")
		)
		(fp_line
			(start 0.504 0.25)
			(end 0.504 -0.248)
			(stroke
				(width 0.15)
				(type solid)
			)
			(layer "B.Fab")
		)
		(fp_text user "Author: Antmicro"
			(at -0.939 -3.399 180)
			(layer "B.Fab")
			(effects
				(font
					(size 0.7 0.7)
					(thickness 0.15)
				)
				(justify left bottom mirror)
			)
		)
		(fp_text user "License: Apache-2.0"
			(at -0.939 -5.799 180)
			(layer "B.Fab")
			(effects
				(font
					(size 0.7 0.7)
					(thickness 0.15)
				)
				(justify left bottom mirror)
			)
		)
		(fp_text user "${REFERENCE}"
			(at -0.939 -4.599 180)
			(layer "B.Fab")
			(effects
				(font
					(size 0.7 0.7)
					(thickness 0.15)
				)
				(justify left bottom mirror)
			)
		)
		(pad "1" smd roundrect
			(at -0.48 0)
			(size 0.59 0.64)
			(layers "B.Cu" "B.Mask" "B.Paste")
			(roundrect_rratio 0.25)
			(net 23 "GND")
			(pintype "passive")
		)
		(pad "2" smd roundrect
			(at 0.48 0)
			(size 0.59 0.64)
			(layers "B.Cu" "B.Mask" "B.Paste")
			(roundrect_rratio 0.25)
			(net 68 "/TB Controller - Power/VCC_0P9")
			(pintype "passive")
		)
	)
	(footprint "antmicro-footprints:C_Pol_EIA-A"
		(layer "B.Cu")
		(at 156.6 103 -90)
		(property "Reference" "C327"
			(at -5 -1.5 90)
			(layer "B.SilkS")
			(effects
				(font
					(size 0.7 0.7)
					(thickness 0.15)
				)
				(justify left bottom mirror)
			)
		)
		(property "Value" "C_Pol_100u_6V_KEMET-T490-A"
			(at 0 -2 90)
			(layer "B.Fab")
			(effects
				(font
					(size 0.7 0.7)
					(thickness 0.15)
				)
				(justify left bottom mirror)
			)
		)
		(property "Datasheet" "https://www.kemet.com/en/us/capacitors/product/T490A107M006ATE800.html"
			(at 0 0 90)
			(layer "B.Fab")
			(hide yes)
			(effects
				(font
					(size 1.27 1.27)
					(thickness 0.15)
				)
				(justify mirror)
			)
		)
		(property "Description" "Surface Mount Tantalum Capacitor,  Solid SMD 6V 100uF 1206 20% ESR=800mOhms"
			(at 0 0 90)
			(layer "B.Fab")
			(hide yes)
			(effects
				(font
					(size 1.27 1.27)
					(thickness 0.15)
				)
				(justify mirror)
			)
		)
		(property "Val" "100u"
			(at 0 0 270)
			(unlocked yes)
			(layer "B.Fab")
			(hide yes)
			(effects
				(font
					(size 1 1)
					(thickness 0.15)
				)
				(justify mirror)
			)
		)
		(property "MPN" "T490A107M006ATE800"
			(at 0 0 270)
			(unlocked yes)
			(layer "B.Fab")
			(hide yes)
			(effects
				(font
					(size 1 1)
					(thickness 0.15)
				)
				(justify mirror)
			)
		)
		(property "Manufacturer" "KEMET"
			(at 0 0 270)
			(unlocked yes)
			(layer "B.Fab")
			(hide yes)
			(effects
				(font
					(size 1 1)
					(thickness 0.15)
				)
				(justify mirror)
			)
		)
		(property "License" "Apache-2.0"
			(at 0 0 270)
			(unlocked yes)
			(layer "B.Fab")
			(hide yes)
			(effects
				(font
					(size 1 1)
					(thickness 0.15)
				)
				(justify mirror)
			)
		)
		(property "Author" "Antmicro"
			(at 0 0 270)
			(unlocked yes)
			(layer "B.Fab")
			(hide yes)
			(effects
				(font
					(size 1 1)
					(thickness 0.15)
				)
				(justify mirror)
			)
		)
		(property "Voltage" "6V"
			(at 0 0 270)
			(unlocked yes)
			(layer "B.Fab")
			(hide yes)
			(effects
				(font
					(size 1 1)
					(thickness 0.15)
				)
				(justify mirror)
			)
		)
		(property "Dielectric" "template_dielectric"
			(at 0 0 270)
			(unlocked yes)
			(layer "B.Fab")
			(hide yes)
			(effects
				(font
					(size 1 1)
					(thickness 0.15)
				)
				(justify mirror)
			)
		)
		(sheetname "/X710-AT2 power/")
		(sheetfile "x710-at2-power.kicad_sch")
		(attr smd)
		(fp_line
			(start -1.95 1.25)
			(end -1.95 0.95)
			(stroke
				(width 0.12)
				(type solid)
			)
			(layer "B.SilkS")
		)
		(fp_line
			(start -2.1 1.1)
			(end -1.8 1.1)
			(stroke
				(width 0.12)
				(type solid)
			)
			(layer "B.SilkS")
		)
		(fp_line
			(start -1.5 0.85)
			(end 1.5 0.85)
			(stroke
				(width 0.12)
				(type solid)
			)
			(layer "B.SilkS")
		)
		(fp_line
			(start -1.5 0.75)
			(end -1.5 0.85)
			(stroke
				(width 0.12)
				(type solid)
			)
			(layer "B.SilkS")
		)
		(fp_line
			(start 1.5 0.75)
			(end 1.5 0.85)
			(stroke
				(width 0.12)
				(type solid)
			)
			(layer "B.SilkS")
		)
		(fp_line
			(start -1.5 -0.75)
			(end -1.5 -0.85)
			(stroke
				(width 0.12)
				(type solid)
			)
			(layer "B.SilkS")
		)
		(fp_line
			(start 1.5 -0.75)
			(end 1.5 -0.85)
			(stroke
				(width 0.12)
				(type solid)
			)
			(layer "B.SilkS")
		)
		(fp_line
			(start 1.5 -0.85)
			(end -1.5 -0.85)
			(stroke
				(width 0.12)
				(type solid)
			)
			(layer "B.SilkS")
		)
		(fp_line
			(start 1.7 1.05)
			(end -1.7 1.05)
			(stroke
				(width 0.05)
				(type solid)
			)
			(layer "B.CrtYd")
		)
		(fp_line
			(start -2.05 0.85)
			(end -2.05 -0.85)
			(stroke
				(width 0.05)
				(type solid)
			)
			(layer "B.CrtYd")
		)
		(fp_line
			(start -1.7 0.85)
			(end -1.7 1.05)
			(stroke
				(width 0.05)
				(type solid)
			)
			(layer "B.CrtYd")
		)
		(fp_line
			(start -1.7 0.85)
			(end -2.05 0.85)
			(stroke
				(width 0.05)
				(type solid)
			)
			(layer "B.CrtYd")
		)
		(fp_line
			(start 1.7 0.85)
			(end 1.7 1.05)
			(stroke
				(width 0.05)
				(type solid)
			)
			(layer "B.CrtYd")
		)
		(fp_line
			(start 2.05 0.85)
			(end 1.7 0.85)
			(stroke
				(width 0.05)
				(type solid)
			)
			(layer "B.CrtYd")
		)
		(fp_line
			(start 2.05 0.85)
			(end 2.05 -0.85)
			(stroke
				(width 0.05)
				(type solid)
			)
			(layer "B.CrtYd")
		)
		(fp_line
			(start -1.7 -0.85)
			(end -2.05 -0.85)
			(stroke
				(width 0.05)
				(type solid)
			)
			(layer "B.CrtYd")
		)
		(fp_line
			(start 2.05 -0.85)
			(end 1.7 -0.85)
			(stroke
				(width 0.05)
				(type solid)
			)
			(layer "B.CrtYd")
		)
		(fp_line
			(start -1.7 -1.05)
			(end -1.7 -0.85)
			(stroke
				(width 0.05)
				(type solid)
			)
			(layer "B.CrtYd")
		)
		(fp_line
			(start 1.7 -1.05)
			(end 1.7 -0.85)
			(stroke
				(width 0.05)
				(type solid)
			)
			(layer "B.CrtYd")
		)
		(fp_line
			(start 1.7 -1.05)
			(end -1.7 -1.05)
			(stroke
				(width 0.05)
				(type solid)
			)
			(layer "B.CrtYd")
		)
		(fp_rect
			(start -1.601 0.802)
			(end 1.6 -0.8)
			(stroke
				(width 0.1)
				(type solid)
			)
			(fill no)
			(layer "B.Fab")
		)
		(fp_text user "${REFERENCE}"
			(at -2.1 -4.198 90)
			(layer "B.Fab")
			(effects
				(font
					(size 0.7 0.7)
					(thickness 0.15)
				)
				(justify left bottom mirror)
			)
		)
		(fp_text user "Author: Antmicro"
			(at -2.1 -6.198 90)
			(layer "B.Fab")
			(effects
				(font
					(size 0.7 0.7)
					(thickness 0.15)
				)
				(justify left bottom mirror)
			)
		)
		(fp_text user "License: Apache-2.0"
			(at -2.1 -5.198 90)
			(layer "B.Fab")
			(effects
				(font
					(size 0.7 0.7)
					(thickness 0.15)
				)
				(justify left bottom mirror)
			)
		)
		(pad "1" smd roundrect
			(at -1.2 0 270)
			(size 1.2 1.2)
			(layers "B.Cu" "B.Mask" "B.Paste")
			(roundrect_rratio 0.1)
			(net 136 "+1V0")
			(pintype "passive")
		)
		(pad "2" smd roundrect
			(at 1.2 0 270)
			(size 1.2 1.2)
			(layers "B.Cu" "B.Mask" "B.Paste")
			(roundrect_rratio 0.1)
			(net 23 "GND")
			(pintype "passive")
		)
	)
	(footprint "antmicro-footprints:R_0402_1005Metric"
		(layer "B.Cu")
		(at 150.58 146.66 90)
		(descr "Resistor SMD 0402")
		(tags "resistor SMD 0402")
		(property "Reference" "R212"
			(at -1.09 0.42 270)
			(layer "B.SilkS")
			(effects
				(font
					(size 0.7 0.7)
					(thickness 0.15)
				)
				(justify left bottom mirror)
			)
		)
		(property "Value" "R_220R_0402"
			(at -1.011843 -1.772047 270)
			(layer "B.Fab")
			(effects
				(font
					(size 0.7 0.7)
					(thickness 0.15)
				)
				(justify left bottom mirror)
			)
		)
		(property "Datasheet" "https://www.bourns.com/docs/product-datasheets/cr.pdf"
			(at 0 0 270)
			(layer "B.Fab")
			(hide yes)
			(effects
				(font
					(size 1.27 1.27)
					(thickness 0.15)
				)
				(justify mirror)
			)
		)
		(property "Description" "SMD Chip Resistor, 220 ohm, ± 1%, 62.5 mW, 0402 [1005 Metric], Thick Film, General Purpose"
			(at 0 0 270)
			(layer "B.Fab")
			(hide yes)
			(effects
				(font
					(size 1.27 1.27)
					(thickness 0.15)
				)
				(justify mirror)
			)
		)
		(property "MPN" "CR0402-FX-2200GLF"
			(at 0 0 90)
			(unlocked yes)
			(layer "B.Fab")
			(hide yes)
			(effects
				(font
					(size 1 1)
					(thickness 0.15)
				)
				(justify mirror)
			)
		)
		(property "Manufacturer" "Bourns"
			(at 0 0 90)
			(unlocked yes)
			(layer "B.Fab")
			(hide yes)
			(effects
				(font
					(size 1 1)
					(thickness 0.15)
				)
				(justify mirror)
			)
		)
		(property "License" "Apache-2.0"
			(at 0 0 90)
			(unlocked yes)
			(layer "B.Fab")
			(hide yes)
			(effects
				(font
					(size 1 1)
					(thickness 0.15)
				)
				(justify mirror)
			)
		)
		(property "Author" "Antmicro"
			(at 0 0 90)
			(unlocked yes)
			(layer "B.Fab")
			(hide yes)
			(effects
				(font
					(size 1 1)
					(thickness 0.15)
				)
				(justify mirror)
			)
		)
		(property "Val" "220R"
			(at 0 0 90)
			(unlocked yes)
			(layer "B.Fab")
			(hide yes)
			(effects
				(font
					(size 1 1)
					(thickness 0.15)
				)
				(justify mirror)
			)
		)
		(property "Tolerance" "1%"
			(at 0 0 90)
			(unlocked yes)
			(layer "B.Fab")
			(hide yes)
			(effects
				(font
					(size 1 1)
					(thickness 0.15)
				)
				(justify mirror)
			)
		)
		(sheetname "/2xRJ45/")
		(sheetfile "2xrj45.kicad_sch")
		(attr smd)
		(fp_rect
			(start -0.925 0.47)
			(end 0.925 -0.47)
			(stroke
				(width 0.05)
				(type default)
			)
			(fill no)
			(layer "B.CrtYd")
		)
		(fp_rect
			(start -0.5 0.25)
			(end 0.5 -0.25)
			(stroke
				(width 0.15)
				(type solid)
			)
			(fill no)
			(layer "B.Fab")
		)
		(fp_text user "License: Apache-2.0"
			(at -0.95 -5.169 270)
			(layer "B.Fab")
			(effects
				(font
					(size 0.7 0.7)
					(thickness 0.15)
				)
				(justify left bottom mirror)
			)
		)
		(fp_text user "Author: Antmicro"
			(at -0.95 -4.169 270)
			(layer "B.Fab")
			(effects
				(font
					(size 0.7 0.7)
					(thickness 0.15)
				)
				(justify left bottom mirror)
			)
		)
		(fp_text user "${REFERENCE}"
			(at -0.95 -3.168 270)
			(layer "B.Fab")
			(effects
				(font
					(size 0.7 0.7)
					(thickness 0.15)
				)
				(justify left bottom mirror)
			)
		)
		(pad "1" smd roundrect
			(at -0.48 0 90)
			(size 0.59 0.64)
			(layers "B.Cu" "B.Mask" "B.Paste")
			(roundrect_rratio 0.25)
			(net 410 "Net-(J3-LED_GRN-)")
			(pintype "passive")
		)
		(pad "2" smd roundrect
			(at 0.48 0 90)
			(size 0.59 0.64)
			(layers "B.Cu" "B.Mask" "B.Paste")
			(roundrect_rratio 0.25)
			(net 61 "/2xRJ45/~{P0_LED_ACT}")
			(pintype "passive")
		)
	)
	(footprint "antmicro-footprints:C_0402_1005Metric"
		(layer "B.Cu")
		(at 149.681866 92.485117 90)
		(descr "Capacitor SMD 0402")
		(tags "capacitor SMD 0402")
		(property "Reference" "C279"
			(at -10.814884 18.718134 270)
			(layer "B.SilkS")
			(effects
				(font
					(size 0.7 0.7)
					(thickness 0.15)
				)
				(justify mirror)
			)
		)
		(property "Value" "C_1u_25V_0402"
			(at -1.022927 -2.155213 270)
			(layer "B.Fab")
			(effects
				(font
					(size 0.7 0.7)
					(thickness 0.15)
				)
				(justify left bottom mirror)
			)
		)
		(property "Datasheet" "https://www.murata.com/products/productdetail?partno=GRM155R61E105KE11%23"
			(at 0 0 270)
			(layer "B.Fab")
			(hide yes)
			(effects
				(font
					(size 1.27 1.27)
					(thickness 0.15)
				)
				(justify mirror)
			)
		)
		(property "Description" "SMD Multilayer Ceramic Capacitor, 1 µF, 25 V, 0402 [1005 Metric], ± 10%, X5R, GRM Series"
			(at 0 0 270)
			(layer "B.Fab")
			(hide yes)
			(effects
				(font
					(size 1.27 1.27)
					(thickness 0.15)
				)
				(justify mirror)
			)
		)
		(property "MPN" "GRM155R61E105KE11J"
			(at 0 0 90)
			(unlocked yes)
			(layer "B.Fab")
			(hide yes)
			(effects
				(font
					(size 1 1)
					(thickness 0.15)
				)
				(justify mirror)
			)
		)
		(property "Manufacturer" "Murata"
			(at 0 0 90)
			(unlocked yes)
			(layer "B.Fab")
			(hide yes)
			(effects
				(font
					(size 1 1)
					(thickness 0.15)
				)
				(justify mirror)
			)
		)
		(property "License" "Apache-2.0"
			(at 0 0 90)
			(unlocked yes)
			(layer "B.Fab")
			(hide yes)
			(effects
				(font
					(size 1 1)
					(thickness 0.15)
				)
				(justify mirror)
			)
		)
		(property "Author" "Antmicro"
			(at 0 0 90)
			(unlocked yes)
			(layer "B.Fab")
			(hide yes)
			(effects
				(font
					(size 1 1)
					(thickness 0.15)
				)
				(justify mirror)
			)
		)
		(property "Val" "1u"
			(at 0 0 90)
			(unlocked yes)
			(layer "B.Fab")
			(hide yes)
			(effects
				(font
					(size 1 1)
					(thickness 0.15)
				)
				(justify mirror)
			)
		)
		(property "Voltage" "25V"
			(at 0 0 90)
			(unlocked yes)
			(layer "B.Fab")
			(hide yes)
			(effects
				(font
					(size 1 1)
					(thickness 0.15)
				)
				(justify mirror)
			)
		)
		(property "Dielectric" "X5R"
			(at 0 0 90)
			(unlocked yes)
			(layer "B.Fab")
			(hide yes)
			(effects
				(font
					(size 1 1)
					(thickness 0.15)
				)
				(justify mirror)
			)
		)
		(sheetname "/X710-AT2 Misc/")
		(sheetfile "x710-at2-mics.kicad_sch")
		(attr smd)
		(fp_rect
			(start -0.925 0.47)
			(end 0.925 -0.47)
			(stroke
				(width 0.05)
				(type default)
			)
			(fill no)
			(layer "B.CrtYd")
		)
		(fp_line
			(start 0.504 -0.248)
			(end -0.494 -0.248)
			(stroke
				(width 0.15)
				(type solid)
			)
			(layer "B.Fab")
		)
		(fp_line
			(start -0.494 -0.248)
			(end -0.494 0.25)
			(stroke
				(width 0.15)
				(type solid)
			)
			(layer "B.Fab")
		)
		(fp_line
			(start 0.504 0.25)
			(end 0.504 -0.248)
			(stroke
				(width 0.15)
				(type solid)
			)
			(layer "B.Fab")
		)
		(fp_line
			(start -0.494 0.25)
			(end 0.504 0.25)
			(stroke
				(width 0.15)
				(type solid)
			)
			(layer "B.Fab")
		)
		(fp_text user "Author: Antmicro"
			(at -0.939 -3.399 270)
			(layer "B.Fab")
			(effects
				(font
					(size 0.7 0.7)
					(thickness 0.15)
				)
				(justify left bottom mirror)
			)
		)
		(fp_text user "${REFERENCE}"
			(at -0.939 -4.599 270)
			(layer "B.Fab")
			(effects
				(font
					(size 0.7 0.7)
					(thickness 0.15)
				)
				(justify left bottom mirror)
			)
		)
		(fp_text user "License: Apache-2.0"
			(at -0.939 -5.799 270)
			(layer "B.Fab")
			(effects
				(font
					(size 0.7 0.7)
					(thickness 0.15)
				)
				(justify left bottom mirror)
			)
		)
		(pad "1" smd roundrect
			(at -0.48 0 90)
			(size 0.59 0.64)
			(layers "B.Cu" "B.Mask" "B.Paste")
			(roundrect_rratio 0.25)
			(net 23 "GND")
			(pintype "passive")
		)
		(pad "2" smd roundrect
			(at 0.48 0 90)
			(size 0.59 0.64)
			(layers "B.Cu" "B.Mask" "B.Paste")
			(roundrect_rratio 0.25)
			(net 35 "/X710-AT2 Misc/POR_BYPASS")
			(pintype "passive")
		)
	)
	(footprint "antmicro-footprints:C_0402_1005Metric"
		(layer "B.Cu")
		(at 154.261866 85.265117 180)
		(descr "Capacitor SMD 0402")
		(tags "capacitor SMD 0402")
		(property "Reference" "C207"
			(at -17.938134 -9.464883 0)
			(layer "B.SilkS")
			(effects
				(font
					(size 0.7 0.7)
					(thickness 0.15)
				)
				(justify mirror)
			)
		)
		(property "Value" "C_1u_25V_0402"
			(at -1.022927 -2.155213 0)
			(layer "B.Fab")
			(effects
				(font
					(size 0.7 0.7)
					(thickness 0.15)
				)
				(justify left bottom mirror)
			)
		)
		(property "Datasheet" "https://www.murata.com/products/productdetail?partno=GRM155R61E105KE11%23"
			(at 0 0 0)
			(layer "B.Fab")
			(hide yes)
			(effects
				(font
					(size 1.27 1.27)
					(thickness 0.15)
				)
				(justify mirror)
			)
		)
		(property "Description" "SMD Multilayer Ceramic Capacitor, 1 µF, 25 V, 0402 [1005 Metric], ± 10%, X5R, GRM Series"
			(at 0 0 0)
			(layer "B.Fab")
			(hide yes)
			(effects
				(font
					(size 1.27 1.27)
					(thickness 0.15)
				)
				(justify mirror)
			)
		)
		(property "MPN" "GRM155R61E105KE11J"
			(at 0 0 180)
			(unlocked yes)
			(layer "B.Fab")
			(hide yes)
			(effects
				(font
					(size 1 1)
					(thickness 0.15)
				)
				(justify mirror)
			)
		)
		(property "Manufacturer" "Murata"
			(at 0 0 180)
			(unlocked yes)
			(layer "B.Fab")
			(hide yes)
			(effects
				(font
					(size 1 1)
					(thickness 0.15)
				)
				(justify mirror)
			)
		)
		(property "License" "Apache-2.0"
			(at 0 0 180)
			(unlocked yes)
			(layer "B.Fab")
			(hide yes)
			(effects
				(font
					(size 1 1)
					(thickness 0.15)
				)
				(justify mirror)
			)
		)
		(property "Author" "Antmicro"
			(at 0 0 180)
			(unlocked yes)
			(layer "B.Fab")
			(hide yes)
			(effects
				(font
					(size 1 1)
					(thickness 0.15)
				)
				(justify mirror)
			)
		)
		(property "Val" "1u"
			(at 0 0 180)
			(unlocked yes)
			(layer "B.Fab")
			(hide yes)
			(effects
				(font
					(size 1 1)
					(thickness 0.15)
				)
				(justify mirror)
			)
		)
		(property "Voltage" "25V"
			(at 0 0 180)
			(unlocked yes)
			(layer "B.Fab")
			(hide yes)
			(effects
				(font
					(size 1 1)
					(thickness 0.15)
				)
				(justify mirror)
			)
		)
		(property "Dielectric" "X5R"
			(at 0 0 180)
			(unlocked yes)
			(layer "B.Fab")
			(hide yes)
			(effects
				(font
					(size 1 1)
					(thickness 0.15)
				)
				(justify mirror)
			)
		)
		(sheetname "/X710-AT2 power/")
		(sheetfile "x710-at2-power.kicad_sch")
		(attr smd)
		(fp_rect
			(start -0.925 0.47)
			(end 0.925 -0.47)
			(stroke
				(width 0.05)
				(type default)
			)
			(fill no)
			(layer "B.CrtYd")
		)
		(fp_line
			(start 0.504 0.25)
			(end 0.504 -0.248)
			(stroke
				(width 0.15)
				(type solid)
			)
			(layer "B.Fab")
		)
		(fp_line
			(start 0.504 -0.248)
			(end -0.494 -0.248)
			(stroke
				(width 0.15)
				(type solid)
			)
			(layer "B.Fab")
		)
		(fp_line
			(start -0.494 0.25)
			(end 0.504 0.25)
			(stroke
				(width 0.15)
				(type solid)
			)
			(layer "B.Fab")
		)
		(fp_line
			(start -0.494 -0.248)
			(end -0.494 0.25)
			(stroke
				(width 0.15)
				(type solid)
			)
			(layer "B.Fab")
		)
		(fp_text user "Author: Antmicro"
			(at -0.939 -3.399 0)
			(layer "B.Fab")
			(effects
				(font
					(size 0.7 0.7)
					(thickness 0.15)
				)
				(justify left bottom mirror)
			)
		)
		(fp_text user "${REFERENCE}"
			(at -0.939 -4.599 0)
			(layer "B.Fab")
			(effects
				(font
					(size 0.7 0.7)
					(thickness 0.15)
				)
				(justify left bottom mirror)
			)
		)
		(fp_text user "License: Apache-2.0"
			(at -0.939 -5.799 0)
			(layer "B.Fab")
			(effects
				(font
					(size 0.7 0.7)
					(thickness 0.15)
				)
				(justify left bottom mirror)
			)
		)
		(pad "1" smd roundrect
			(at -0.48 0 180)
			(size 0.59 0.64)
			(layers "B.Cu" "B.Mask" "B.Paste")
			(roundrect_rratio 0.25)
			(net 23 "GND")
			(pintype "passive")
		)
		(pad "2" smd roundrect
			(at 0.48 0 180)
			(size 0.59 0.64)
			(layers "B.Cu" "B.Mask" "B.Paste")
			(roundrect_rratio 0.25)
			(net 12 "XFI_VDD")
			(pintype "passive")
		)
	)
	(footprint "antmicro-footprints:C_0402_1005Metric"
		(layer "B.Cu")
		(at 145.631866 78.260118 180)
		(descr "Capacitor SMD 0402")
		(tags "capacitor SMD 0402")
		(property "Reference" "C259"
			(at -17.768134 -9.464883 0)
			(layer "B.SilkS")
			(effects
				(font
					(size 0.7 0.7)
					(thickness 0.15)
				)
				(justify mirror)
			)
		)
		(property "Value" "C_1u_25V_0402"
			(at -1.022927 -2.155213 0)
			(layer "B.Fab")
			(effects
				(font
					(size 0.7 0.7)
					(thickness 0.15)
				)
				(justify left bottom mirror)
			)
		)
		(property "Datasheet" "https://www.murata.com/products/productdetail?partno=GRM155R61E105KE11%23"
			(at 0 0 0)
			(layer "B.Fab")
			(hide yes)
			(effects
				(font
					(size 1.27 1.27)
					(thickness 0.15)
				)
				(justify mirror)
			)
		)
		(property "Description" "SMD Multilayer Ceramic Capacitor, 1 µF, 25 V, 0402 [1005 Metric], ± 10%, X5R, GRM Series"
			(at 0 0 0)
			(layer "B.Fab")
			(hide yes)
			(effects
				(font
					(size 1.27 1.27)
					(thickness 0.15)
				)
				(justify mirror)
			)
		)
		(property "MPN" "GRM155R61E105KE11J"
			(at 0 0 180)
			(unlocked yes)
			(layer "B.Fab")
			(hide yes)
			(effects
				(font
					(size 1 1)
					(thickness 0.15)
				)
				(justify mirror)
			)
		)
		(property "Manufacturer" "Murata"
			(at 0 0 180)
			(unlocked yes)
			(layer "B.Fab")
			(hide yes)
			(effects
				(font
					(size 1 1)
					(thickness 0.15)
				)
				(justify mirror)
			)
		)
		(property "License" "Apache-2.0"
			(at 0 0 180)
			(unlocked yes)
			(layer "B.Fab")
			(hide yes)
			(effects
				(font
					(size 1 1)
					(thickness 0.15)
				)
				(justify mirror)
			)
		)
		(property "Author" "Antmicro"
			(at 0 0 180)
			(unlocked yes)
			(layer "B.Fab")
			(hide yes)
			(effects
				(font
					(size 1 1)
					(thickness 0.15)
				)
				(justify mirror)
			)
		)
		(property "Val" "1u"
			(at 0 0 180)
			(unlocked yes)
			(layer "B.Fab")
			(hide yes)
			(effects
				(font
					(size 1 1)
					(thickness 0.15)
				)
				(justify mirror)
			)
		)
		(property "Voltage" "25V"
			(at 0 0 180)
			(unlocked yes)
			(layer "B.Fab")
			(hide yes)
			(effects
				(font
					(size 1 1)
					(thickness 0.15)
				)
				(justify mirror)
			)
		)
		(property "Dielectric" "X5R"
			(at 0 0 180)
			(unlocked yes)
			(layer "B.Fab")
			(hide yes)
			(effects
				(font
					(size 1 1)
					(thickness 0.15)
				)
				(justify mirror)
			)
		)
		(sheetname "/X710-AT2 power/")
		(sheetfile "x710-at2-power.kicad_sch")
		(attr smd)
		(fp_rect
			(start -0.925 0.47)
			(end 0.925 -0.47)
			(stroke
				(width 0.05)
				(type default)
			)
			(fill no)
			(layer "B.CrtYd")
		)
		(fp_line
			(start 0.504 0.25)
			(end 0.504 -0.248)
			(stroke
				(width 0.15)
				(type solid)
			)
			(layer "B.Fab")
		)
		(fp_line
			(start 0.504 -0.248)
			(end -0.494 -0.248)
			(stroke
				(width 0.15)
				(type solid)
			)
			(layer "B.Fab")
		)
		(fp_line
			(start -0.494 0.25)
			(end 0.504 0.25)
			(stroke
				(width 0.15)
				(type solid)
			)
			(layer "B.Fab")
		)
		(fp_line
			(start -0.494 -0.248)
			(end -0.494 0.25)
			(stroke
				(width 0.15)
				(type solid)
			)
			(layer "B.Fab")
		)
		(fp_text user "${REFERENCE}"
			(at -0.939 -4.599 0)
			(layer "B.Fab")
			(effects
				(font
					(size 0.7 0.7)
					(thickness 0.15)
				)
				(justify left bottom mirror)
			)
		)
		(fp_text user "License: Apache-2.0"
			(at -0.939 -5.799 0)
			(layer "B.Fab")
			(effects
				(font
					(size 0.7 0.7)
					(thickness 0.15)
				)
				(justify left bottom mirror)
			)
		)
		(fp_text user "Author: Antmicro"
			(at -0.939 -3.399 0)
			(layer "B.Fab")
			(effects
				(font
					(size 0.7 0.7)
					(thickness 0.15)
				)
				(justify left bottom mirror)
			)
		)
		(pad "1" smd roundrect
			(at -0.48 0 180)
			(size 0.59 0.64)
			(layers "B.Cu" "B.Mask" "B.Paste")
			(roundrect_rratio 0.25)
			(net 23 "GND")
			(pintype "passive")
		)
		(pad "2" smd roundrect
			(at 0.48 0 180)
			(size 0.59 0.64)
			(layers "B.Cu" "B.Mask" "B.Paste")
			(roundrect_rratio 0.25)
			(net 1 "VCCA")
			(pintype "passive")
		)
	)
	(footprint "antmicro-footprints:R_0402_1005Metric"
		(layer "B.Cu")
		(at 136.5 122.15)
		(descr "Resistor SMD 0402")
		(tags "resistor SMD 0402")
		(property "Reference" "R53"
			(at 19.525001 -7.450001 180)
			(layer "B.SilkS")
			(effects
				(font
					(size 0.7 0.7)
					(thickness 0.15)
				)
				(justify mirror)
			)
		)
		(property "Value" "R_100k_0402"
			(at -1.011843 -1.772047 180)
			(layer "B.Fab")
			(effects
				(font
					(size 0.7 0.7)
					(thickness 0.15)
				)
				(justify left bottom mirror)
			)
		)
		(property "Datasheet" "https://www.bourns.com/docs/product-datasheets/cr.pdf"
			(at 0 0 180)
			(layer "B.Fab")
			(hide yes)
			(effects
				(font
					(size 1.27 1.27)
					(thickness 0.15)
				)
				(justify mirror)
			)
		)
		(property "Description" "SMD Chip Resistor, 100 kohm, ± 1%, 62.5 mW, 0402 [1005 Metric], Thick Film, General Purpose"
			(at 0 0 180)
			(layer "B.Fab")
			(hide yes)
			(effects
				(font
					(size 1.27 1.27)
					(thickness 0.15)
				)
				(justify mirror)
			)
		)
		(property "MPN" "CR0402-FX-1003GLF"
			(at 0 0 0)
			(unlocked yes)
			(layer "B.Fab")
			(hide yes)
			(effects
				(font
					(size 1 1)
					(thickness 0.15)
				)
				(justify mirror)
			)
		)
		(property "Manufacturer" "Bourns"
			(at 0 0 0)
			(unlocked yes)
			(layer "B.Fab")
			(hide yes)
			(effects
				(font
					(size 1 1)
					(thickness 0.15)
				)
				(justify mirror)
			)
		)
		(property "License" "Apache-2.0"
			(at 0 0 0)
			(unlocked yes)
			(layer "B.Fab")
			(hide yes)
			(effects
				(font
					(size 1 1)
					(thickness 0.15)
				)
				(justify mirror)
			)
		)
		(property "Val" "100k"
			(at 0 0 0)
			(unlocked yes)
			(layer "B.Fab")
			(hide yes)
			(effects
				(font
					(size 1 1)
					(thickness 0.15)
				)
				(justify mirror)
			)
		)
		(property "Tolerance" "1%"
			(at 0 0 0)
			(unlocked yes)
			(layer "B.Fab")
			(hide yes)
			(effects
				(font
					(size 1 1)
					(thickness 0.15)
				)
				(justify mirror)
			)
		)
		(property "Author" "Antmicro"
			(at 0 0 0)
			(unlocked yes)
			(layer "B.Fab")
			(hide yes)
			(effects
				(font
					(size 1 1)
					(thickness 0.15)
				)
				(justify mirror)
			)
		)
		(sheetname "/TB Controller/")
		(sheetfile "tb.kicad_sch")
		(attr smd)
		(fp_rect
			(start -0.925 0.47)
			(end 0.925 -0.47)
			(stroke
				(width 0.05)
				(type default)
			)
			(fill no)
			(layer "B.CrtYd")
		)
		(fp_rect
			(start -0.5 0.25)
			(end 0.5 -0.25)
			(stroke
				(width 0.15)
				(type solid)
			)
			(fill no)
			(layer "B.Fab")
		)
		(fp_text user "Author: Antmicro"
			(at -0.95 -4.169 180)
			(layer "B.Fab")
			(effects
				(font
					(size 0.7 0.7)
					(thickness 0.15)
				)
				(justify left bottom mirror)
			)
		)
		(fp_text user "License: Apache-2.0"
			(at -0.95 -5.169 180)
			(layer "B.Fab")
			(effects
				(font
					(size 0.7 0.7)
					(thickness 0.15)
				)
				(justify left bottom mirror)
			)
		)
		(fp_text user "${REFERENCE}"
			(at -0.95 -3.168 180)
			(layer "B.Fab")
			(effects
				(font
					(size 0.7 0.7)
					(thickness 0.15)
				)
				(justify left bottom mirror)
			)
		)
		(pad "1" smd roundrect
			(at -0.48 0)
			(size 0.59 0.64)
			(layers "B.Cu" "B.Mask" "B.Paste")
			(roundrect_rratio 0.25)
			(net 236 "Net-(U4C-POC_GPIO_6)")
			(pintype "passive")
		)
		(pad "2" smd roundrect
			(at 0.48 0)
			(size 0.59 0.64)
			(layers "B.Cu" "B.Mask" "B.Paste")
			(roundrect_rratio 0.25)
			(net 23 "GND")
			(pintype "passive")
		)
	)
	(footprint "antmicro-footprints:C_0402_1005Metric"
		(layer "B.Cu")
		(at 155.231866 89.260117)
		(descr "Capacitor SMD 0402")
		(tags "capacitor SMD 0402")
		(property "Reference" "C203"
			(at 18.968134 10.739883 180)
			(layer "B.SilkS")
			(effects
				(font
					(size 0.7 0.7)
					(thickness 0.15)
				)
				(justify mirror)
			)
		)
		(property "Value" "C_1u_25V_0402"
			(at -1.022927 -2.155213 180)
			(layer "B.Fab")
			(effects
				(font
					(size 0.7 0.7)
					(thickness 0.15)
				)
				(justify left bottom mirror)
			)
		)
		(property "Datasheet" "https://www.murata.com/products/productdetail?partno=GRM155R61E105KE11%23"
			(at 0 0 180)
			(layer "B.Fab")
			(hide yes)
			(effects
				(font
					(size 1.27 1.27)
					(thickness 0.15)
				)
				(justify mirror)
			)
		)
		(property "Description" "SMD Multilayer Ceramic Capacitor, 1 µF, 25 V, 0402 [1005 Metric], ± 10%, X5R, GRM Series"
			(at 0 0 180)
			(layer "B.Fab")
			(hide yes)
			(effects
				(font
					(size 1.27 1.27)
					(thickness 0.15)
				)
				(justify mirror)
			)
		)
		(property "MPN" "GRM155R61E105KE11J"
			(at 0 0 0)
			(unlocked yes)
			(layer "B.Fab")
			(hide yes)
			(effects
				(font
					(size 1 1)
					(thickness 0.15)
				)
				(justify mirror)
			)
		)
		(property "Manufacturer" "Murata"
			(at 0 0 0)
			(unlocked yes)
			(layer "B.Fab")
			(hide yes)
			(effects
				(font
					(size 1 1)
					(thickness 0.15)
				)
				(justify mirror)
			)
		)
		(property "License" "Apache-2.0"
			(at 0 0 0)
			(unlocked yes)
			(layer "B.Fab")
			(hide yes)
			(effects
				(font
					(size 1 1)
					(thickness 0.15)
				)
				(justify mirror)
			)
		)
		(property "Author" "Antmicro"
			(at 0 0 0)
			(unlocked yes)
			(layer "B.Fab")
			(hide yes)
			(effects
				(font
					(size 1 1)
					(thickness 0.15)
				)
				(justify mirror)
			)
		)
		(property "Val" "1u"
			(at 0 0 0)
			(unlocked yes)
			(layer "B.Fab")
			(hide yes)
			(effects
				(font
					(size 1 1)
					(thickness 0.15)
				)
				(justify mirror)
			)
		)
		(property "Voltage" "25V"
			(at 0 0 0)
			(unlocked yes)
			(layer "B.Fab")
			(hide yes)
			(effects
				(font
					(size 1 1)
					(thickness 0.15)
				)
				(justify mirror)
			)
		)
		(property "Dielectric" "X5R"
			(at 0 0 0)
			(unlocked yes)
			(layer "B.Fab")
			(hide yes)
			(effects
				(font
					(size 1 1)
					(thickness 0.15)
				)
				(justify mirror)
			)
		)
		(sheetname "/X710-AT2 power/")
		(sheetfile "x710-at2-power.kicad_sch")
		(attr smd)
		(fp_rect
			(start -0.925 0.47)
			(end 0.925 -0.47)
			(stroke
				(width 0.05)
				(type default)
			)
			(fill no)
			(layer "B.CrtYd")
		)
		(fp_line
			(start -0.494 -0.248)
			(end -0.494 0.25)
			(stroke
				(width 0.15)
				(type solid)
			)
			(layer "B.Fab")
		)
		(fp_line
			(start -0.494 0.25)
			(end 0.504 0.25)
			(stroke
				(width 0.15)
				(type solid)
			)
			(layer "B.Fab")
		)
		(fp_line
			(start 0.504 -0.248)
			(end -0.494 -0.248)
			(stroke
				(width 0.15)
				(type solid)
			)
			(layer "B.Fab")
		)
		(fp_line
			(start 0.504 0.25)
			(end 0.504 -0.248)
			(stroke
				(width 0.15)
				(type solid)
			)
			(layer "B.Fab")
		)
		(fp_text user "License: Apache-2.0"
			(at -0.939 -5.799 180)
			(layer "B.Fab")
			(effects
				(font
					(size 0.7 0.7)
					(thickness 0.15)
				)
				(justify left bottom mirror)
			)
		)
		(fp_text user "${REFERENCE}"
			(at -0.939 -4.599 180)
			(layer "B.Fab")
			(effects
				(font
					(size 0.7 0.7)
					(thickness 0.15)
				)
				(justify left bottom mirror)
			)
		)
		(fp_text user "Author: Antmicro"
			(at -0.939 -3.399 180)
			(layer "B.Fab")
			(effects
				(font
					(size 0.7 0.7)
					(thickness 0.15)
				)
				(justify left bottom mirror)
			)
		)
		(pad "1" smd roundrect
			(at -0.48 0)
			(size 0.59 0.64)
			(layers "B.Cu" "B.Mask" "B.Paste")
			(roundrect_rratio 0.25)
			(net 23 "GND")
			(pintype "passive")
		)
		(pad "2" smd roundrect
			(at 0.48 0)
			(size 0.59 0.64)
			(layers "B.Cu" "B.Mask" "B.Paste")
			(roundrect_rratio 0.25)
			(net 18 "+1V88")
			(pintype "passive")
		)
	)
	(footprint "antmicro-footprints:C_0402_1005Metric"
		(layer "B.Cu")
		(at 151.58 146.659998 -90)
		(descr "Capacitor SMD 0402")
		(tags "capacitor SMD 0402")
		(property "Reference" "C304"
			(at 1.09 -0.42 90)
			(layer "B.SilkS")
			(effects
				(font
					(size 0.7 0.7)
					(thickness 0.15)
				)
				(justify left bottom mirror)
			)
		)
		(property "Value" "C_470p_0402"
			(at -1.022927 -2.155213 90)
			(layer "B.Fab")
			(effects
				(font
					(size 0.7 0.7)
					(thickness 0.15)
				)
				(justify left bottom mirror)
			)
		)
		(property "Datasheet" "https://www.passivecomponent.com/wp-content/uploads/datasheet/WTC_MLCC_General_Purpose.pdf"
			(at 0 0 90)
			(layer "B.Fab")
			(hide yes)
			(effects
				(font
					(size 1.27 1.27)
					(thickness 0.15)
				)
				(justify mirror)
			)
		)
		(property "Description" "SMD Multilayer Ceramic Capacitor, General Purpose, 470 pF, 25 V, 0402 [1005 Metric], ± 10%, X7R"
			(at 0 0 90)
			(layer "B.Fab")
			(hide yes)
			(effects
				(font
					(size 1.27 1.27)
					(thickness 0.15)
				)
				(justify mirror)
			)
		)
		(property "MPN" "0402B471K250CT"
			(at 0 0 270)
			(unlocked yes)
			(layer "B.Fab")
			(hide yes)
			(effects
				(font
					(size 1 1)
					(thickness 0.15)
				)
				(justify mirror)
			)
		)
		(property "Manufacturer" "Walsin"
			(at 0 0 270)
			(unlocked yes)
			(layer "B.Fab")
			(hide yes)
			(effects
				(font
					(size 1 1)
					(thickness 0.15)
				)
				(justify mirror)
			)
		)
		(property "License" "Apache-2.0"
			(at 0 0 270)
			(unlocked yes)
			(layer "B.Fab")
			(hide yes)
			(effects
				(font
					(size 1 1)
					(thickness 0.15)
				)
				(justify mirror)
			)
		)
		(property "Author" "Antmicro"
			(at 0 0 270)
			(unlocked yes)
			(layer "B.Fab")
			(hide yes)
			(effects
				(font
					(size 1 1)
					(thickness 0.15)
				)
				(justify mirror)
			)
		)
		(property "Val" "470p"
			(at 0 0 270)
			(unlocked yes)
			(layer "B.Fab")
			(hide yes)
			(effects
				(font
					(size 1 1)
					(thickness 0.15)
				)
				(justify mirror)
			)
		)
		(property "Voltage" "25V"
			(at 0 0 270)
			(unlocked yes)
			(layer "B.Fab")
			(hide yes)
			(effects
				(font
					(size 1 1)
					(thickness 0.15)
				)
				(justify mirror)
			)
		)
		(property "Dielectric" "X7R"
			(at 0 0 270)
			(unlocked yes)
			(layer "B.Fab")
			(hide yes)
			(effects
				(font
					(size 1 1)
					(thickness 0.15)
				)
				(justify mirror)
			)
		)
		(sheetname "/2xRJ45/")
		(sheetfile "2xrj45.kicad_sch")
		(attr smd)
		(fp_rect
			(start -0.925 0.47)
			(end 0.925 -0.47)
			(stroke
				(width 0.05)
				(type default)
			)
			(fill no)
			(layer "B.CrtYd")
		)
		(fp_line
			(start -0.494 0.25)
			(end 0.504 0.25)
			(stroke
				(width 0.15)
				(type solid)
			)
			(layer "B.Fab")
		)
		(fp_line
			(start 0.504 0.25)
			(end 0.504 -0.248)
			(stroke
				(width 0.15)
				(type solid)
			)
			(layer "B.Fab")
		)
		(fp_line
			(start -0.494 -0.248)
			(end -0.494 0.25)
			(stroke
				(width 0.15)
				(type solid)
			)
			(layer "B.Fab")
		)
		(fp_line
			(start 0.504 -0.248)
			(end -0.494 -0.248)
			(stroke
				(width 0.15)
				(type solid)
			)
			(layer "B.Fab")
		)
		(fp_text user "License: Apache-2.0"
			(at -0.939 -5.799 90)
			(layer "B.Fab")
			(effects
				(font
					(size 0.7 0.7)
					(thickness 0.15)
				)
				(justify left bottom mirror)
			)
		)
		(fp_text user "Author: Antmicro"
			(at -0.939 -3.399 90)
			(layer "B.Fab")
			(effects
				(font
					(size 0.7 0.7)
					(thickness 0.15)
				)
				(justify left bottom mirror)
			)
		)
		(fp_text user "${REFERENCE}"
			(at -0.939 -4.599 90)
			(layer "B.Fab")
			(effects
				(font
					(size 0.7 0.7)
					(thickness 0.15)
				)
				(justify left bottom mirror)
			)
		)
		(pad "1" smd roundrect
			(at -0.48 0 270)
			(size 0.59 0.64)
			(layers "B.Cu" "B.Mask" "B.Paste")
			(roundrect_rratio 0.25)
			(net 23 "GND")
			(pintype "passive")
		)
		(pad "2" smd roundrect
			(at 0.48 0 270)
			(size 0.59 0.64)
			(layers "B.Cu" "B.Mask" "B.Paste")
			(roundrect_rratio 0.25)
			(net 408 "Net-(J3-LED_YG_G-)")
			(pintype "passive")
		)
	)
	(footprint "antmicro-footprints:R_0402_1005Metric"
		(layer "B.Cu")
		(at 138.351932 138.558596 180)
		(descr "Resistor SMD 0402")
		(tags "resistor SMD 0402")
		(property "Reference" "R18"
			(at -19.525001 8.1 0)
			(layer "B.SilkS")
			(effects
				(font
					(size 0.7 0.7)
					(thickness 0.15)
				)
				(justify mirror)
			)
		)
		(property "Value" "R_10k_0402"
			(at -1.011843 -1.772047 0)
			(layer "B.Fab")
			(effects
				(font
					(size 0.7 0.7)
					(thickness 0.15)
				)
				(justify left bottom mirror)
			)
		)
		(property "Datasheet" "https://www.bourns.com/docs/product-datasheets/cr.pdf"
			(at 0 0 0)
			(layer "B.Fab")
			(hide yes)
			(effects
				(font
					(size 1.27 1.27)
					(thickness 0.15)
				)
				(justify mirror)
			)
		)
		(property "Description" "SMD Chip Resistor, 10 kohm, ± 1%, 62.5 mW, 0402 [1005 Metric], Thick Film, General Purpose"
			(at 0 0 0)
			(layer "B.Fab")
			(hide yes)
			(effects
				(font
					(size 1.27 1.27)
					(thickness 0.15)
				)
				(justify mirror)
			)
		)
		(property "MPN" "CR0402-FX-1002GLF"
			(at 0 0 180)
			(unlocked yes)
			(layer "B.Fab")
			(hide yes)
			(effects
				(font
					(size 1 1)
					(thickness 0.15)
				)
				(justify mirror)
			)
		)
		(property "Manufacturer" "Bourns"
			(at 0 0 180)
			(unlocked yes)
			(layer "B.Fab")
			(hide yes)
			(effects
				(font
					(size 1 1)
					(thickness 0.15)
				)
				(justify mirror)
			)
		)
		(property "License" "Apache-2.0"
			(at 0 0 180)
			(unlocked yes)
			(layer "B.Fab")
			(hide yes)
			(effects
				(font
					(size 1 1)
					(thickness 0.15)
				)
				(justify mirror)
			)
		)
		(property "Val" "10k"
			(at 0 0 180)
			(unlocked yes)
			(layer "B.Fab")
			(hide yes)
			(effects
				(font
					(size 1 1)
					(thickness 0.15)
				)
				(justify mirror)
			)
		)
		(property "Tolerance" "1%"
			(at 0 0 180)
			(unlocked yes)
			(layer "B.Fab")
			(hide yes)
			(effects
				(font
					(size 1 1)
					(thickness 0.15)
				)
				(justify mirror)
			)
		)
		(property "Author" "Antmicro"
			(at 0 0 180)
			(unlocked yes)
			(layer "B.Fab")
			(hide yes)
			(effects
				(font
					(size 1 1)
					(thickness 0.15)
				)
				(justify mirror)
			)
		)
		(sheetname "/PD and TB DC-DC/")
		(sheetfile "PD_and_TB_DC_DC.kicad_sch")
		(attr smd)
		(fp_rect
			(start -0.925 0.47)
			(end 0.925 -0.47)
			(stroke
				(width 0.05)
				(type default)
			)
			(fill no)
			(layer "B.CrtYd")
		)
		(fp_rect
			(start -0.5 0.25)
			(end 0.5 -0.25)
			(stroke
				(width 0.15)
				(type solid)
			)
			(fill no)
			(layer "B.Fab")
		)
		(fp_text user "License: Apache-2.0"
			(at -0.95 -5.169 0)
			(layer "B.Fab")
			(effects
				(font
					(size 0.7 0.7)
					(thickness 0.15)
				)
				(justify left bottom mirror)
			)
		)
		(fp_text user "Author: Antmicro"
			(at -0.95 -4.169 0)
			(layer "B.Fab")
			(effects
				(font
					(size 0.7 0.7)
					(thickness 0.15)
				)
				(justify left bottom mirror)
			)
		)
		(fp_text user "${REFERENCE}"
			(at -0.95 -3.168 0)
			(layer "B.Fab")
			(effects
				(font
					(size 0.7 0.7)
					(thickness 0.15)
				)
				(justify left bottom mirror)
			)
		)
		(pad "1" smd roundrect
			(at -0.48 0 180)
			(size 0.59 0.64)
			(layers "B.Cu" "B.Mask" "B.Paste")
			(roundrect_rratio 0.25)
			(net 304 "/PD and TB DC-DC/TPS_3V3")
			(pintype "passive")
		)
		(pad "2" smd roundrect
			(at 0.48 0 180)
			(size 0.59 0.64)
			(layers "B.Cu" "B.Mask" "B.Paste")
			(roundrect_rratio 0.25)
			(net 204 "Net-(U3-GPIO7)")
			(pintype "passive")
		)
	)
	(footprint "antmicro-footprints:R_0402_1005Metric"
		(layer "B.Cu")
		(at 117.500002 89.750001 -90)
		(descr "Resistor SMD 0402")
		(tags "resistor SMD 0402")
		(property "Reference" "R76"
			(at 5.85 -0.3 90)
			(layer "B.SilkS")
			(effects
				(font
					(size 0.7 0.7)
					(thickness 0.15)
				)
				(justify left bottom mirror)
			)
		)
		(property "Value" "R_1k_0402"
			(at -1.011843 -1.772047 90)
			(layer "B.Fab")
			(effects
				(font
					(size 0.7 0.7)
					(thickness 0.15)
				)
				(justify left bottom mirror)
			)
		)
		(property "Datasheet" "https://www.bourns.com/docs/product-datasheets/cr.pdf"
			(at 0 0 90)
			(layer "B.Fab")
			(hide yes)
			(effects
				(font
					(size 1.27 1.27)
					(thickness 0.15)
				)
				(justify mirror)
			)
		)
		(property "Description" "SMD Chip Resistor, 1 kohm, ± 1%, 63 mW, 0402 [1005 Metric], Thick Film, General Purpose"
			(at 0 0 90)
			(layer "B.Fab")
			(hide yes)
			(effects
				(font
					(size 1.27 1.27)
					(thickness 0.15)
				)
				(justify mirror)
			)
		)
		(property "MPN" "CR0402-FX-1001GLF"
			(at 0 0 270)
			(unlocked yes)
			(layer "B.Fab")
			(hide yes)
			(effects
				(font
					(size 1 1)
					(thickness 0.15)
				)
				(justify mirror)
			)
		)
		(property "Manufacturer" "Bourns"
			(at 0 0 270)
			(unlocked yes)
			(layer "B.Fab")
			(hide yes)
			(effects
				(font
					(size 1 1)
					(thickness 0.15)
				)
				(justify mirror)
			)
		)
		(property "License" "Apache-2.0"
			(at 0 0 270)
			(unlocked yes)
			(layer "B.Fab")
			(hide yes)
			(effects
				(font
					(size 1 1)
					(thickness 0.15)
				)
				(justify mirror)
			)
		)
		(property "Author" "Antmicro"
			(at 0 0 270)
			(unlocked yes)
			(layer "B.Fab")
			(hide yes)
			(effects
				(font
					(size 1 1)
					(thickness 0.15)
				)
				(justify mirror)
			)
		)
		(property "Val" "1k"
			(at 0 0 270)
			(unlocked yes)
			(layer "B.Fab")
			(hide yes)
			(effects
				(font
					(size 1 1)
					(thickness 0.15)
				)
				(justify mirror)
			)
		)
		(property "Tolerance" "1%"
			(at 0 0 270)
			(unlocked yes)
			(layer "B.Fab")
			(hide yes)
			(effects
				(font
					(size 1 1)
					(thickness 0.15)
				)
				(justify mirror)
			)
		)
		(sheetname "/TB Controller - Power/")
		(sheetfile "tb-power.kicad_sch")
		(attr smd)
		(fp_rect
			(start -0.925 0.47)
			(end 0.925 -0.47)
			(stroke
				(width 0.05)
				(type default)
			)
			(fill no)
			(layer "B.CrtYd")
		)
		(fp_rect
			(start -0.5 0.25)
			(end 0.5 -0.25)
			(stroke
				(width 0.15)
				(type solid)
			)
			(fill no)
			(layer "B.Fab")
		)
		(fp_text user "License: Apache-2.0"
			(at -0.95 -5.169 90)
			(layer "B.Fab")
			(effects
				(font
					(size 0.7 0.7)
					(thickness 0.15)
				)
				(justify left bottom mirror)
			)
		)
		(fp_text user "${REFERENCE}"
			(at -0.95 -3.168 90)
			(layer "B.Fab")
			(effects
				(font
					(size 0.7 0.7)
					(thickness 0.15)
				)
				(justify left bottom mirror)
			)
		)
		(fp_text user "Author: Antmicro"
			(at -0.95 -4.169 90)
			(layer "B.Fab")
			(effects
				(font
					(size 0.7 0.7)
					(thickness 0.15)
				)
				(justify left bottom mirror)
			)
		)
		(pad "1" smd roundrect
			(at -0.48 0 270)
			(size 0.59 0.64)
			(layers "B.Cu" "B.Mask" "B.Paste")
			(roundrect_rratio 0.25)
			(net 23 "GND")
			(pintype "passive")
		)
		(pad "2" smd roundrect
			(at 0.48 0 270)
			(size 0.59 0.64)
			(layers "B.Cu" "B.Mask" "B.Paste")
			(roundrect_rratio 0.25)
			(net 435 "Net-(R75-Pad1)")
			(pintype "passive")
		)
	)
	(footprint "antmicro-footprints:C_0402_1005Metric"
		(layer "B.Cu")
		(at 159.961866 86.905118 -150)
		(descr "Capacitor SMD 0402")
		(tags "capacitor SMD 0402")
		(property "Reference" "C187"
			(at -12.81231 -19.284696 30)
			(layer "B.SilkS")
			(effects
				(font
					(size 0.7 0.7)
					(thickness 0.15)
				)
				(justify mirror)
			)
		)
		(property "Value" "C_1u_25V_0402"
			(at -1.022927 -2.155213 30)
			(layer "B.Fab")
			(effects
				(font
					(size 0.7 0.7)
					(thickness 0.15)
				)
				(justify left bottom mirror)
			)
		)
		(property "Datasheet" "https://www.murata.com/products/productdetail?partno=GRM155R61E105KE11%23"
			(at 0 0 30)
			(layer "B.Fab")
			(hide yes)
			(effects
				(font
					(size 1.27 1.27)
					(thickness 0.15)
				)
				(justify mirror)
			)
		)
		(property "Description" "SMD Multilayer Ceramic Capacitor, 1 µF, 25 V, 0402 [1005 Metric], ± 10%, X5R, GRM Series"
			(at 0 0 30)
			(layer "B.Fab")
			(hide yes)
			(effects
				(font
					(size 1.27 1.27)
					(thickness 0.15)
				)
				(justify mirror)
			)
		)
		(property "MPN" "GRM155R61E105KE11J"
			(at 0 0 210)
			(unlocked yes)
			(layer "B.Fab")
			(hide yes)
			(effects
				(font
					(size 1 1)
					(thickness 0.15)
				)
				(justify mirror)
			)
		)
		(property "Manufacturer" "Murata"
			(at 0 0 210)
			(unlocked yes)
			(layer "B.Fab")
			(hide yes)
			(effects
				(font
					(size 1 1)
					(thickness 0.15)
				)
				(justify mirror)
			)
		)
		(property "License" "Apache-2.0"
			(at 0 0 210)
			(unlocked yes)
			(layer "B.Fab")
			(hide yes)
			(effects
				(font
					(size 1 1)
					(thickness 0.15)
				)
				(justify mirror)
			)
		)
		(property "Author" "Antmicro"
			(at 0 0 210)
			(unlocked yes)
			(layer "B.Fab")
			(hide yes)
			(effects
				(font
					(size 1 1)
					(thickness 0.15)
				)
				(justify mirror)
			)
		)
		(property "Val" "1u"
			(at 0 0 210)
			(unlocked yes)
			(layer "B.Fab")
			(hide yes)
			(effects
				(font
					(size 1 1)
					(thickness 0.15)
				)
				(justify mirror)
			)
		)
		(property "Voltage" "25V"
			(at 0 0 210)
			(unlocked yes)
			(layer "B.Fab")
			(hide yes)
			(effects
				(font
					(size 1 1)
					(thickness 0.15)
				)
				(justify mirror)
			)
		)
		(property "Dielectric" "X5R"
			(at 0 0 210)
			(unlocked yes)
			(layer "B.Fab")
			(hide yes)
			(effects
				(font
					(size 1 1)
					(thickness 0.15)
				)
				(justify mirror)
			)
		)
		(sheetname "/X710-AT2 power/")
		(sheetfile "x710-at2-power.kicad_sch")
		(attr smd)
		(fp_poly
			(pts
				(xy -0.925 0.47) (xy 0.925 0.47) (xy 0.925 -0.47) (xy -0.925 -0.47)
			)
			(stroke
				(width 0.05)
				(type default)
			)
			(fill no)
			(layer "B.CrtYd")
		)
		(fp_line
			(start 0.504 0.25)
			(end 0.504 -0.248)
			(stroke
				(width 0.15)
				(type solid)
			)
			(layer "B.Fab")
		)
		(fp_line
			(start 0.504 -0.248)
			(end -0.494001 -0.248)
			(stroke
				(width 0.15)
				(type solid)
			)
			(layer "B.Fab")
		)
		(fp_line
			(start -0.494 0.249999)
			(end 0.504 0.25)
			(stroke
				(width 0.15)
				(type solid)
			)
			(layer "B.Fab")
		)
		(fp_line
			(start -0.494001 -0.248)
			(end -0.494 0.249999)
			(stroke
				(width 0.15)
				(type solid)
			)
			(layer "B.Fab")
		)
		(fp_text user "License: Apache-2.0"
			(at -0.939 -5.799 30)
			(layer "B.Fab")
			(effects
				(font
					(size 0.7 0.7)
					(thickness 0.15)
				)
				(justify left bottom mirror)
			)
		)
		(fp_text user "Author: Antmicro"
			(at -0.939 -3.399 30)
			(layer "B.Fab")
			(effects
				(font
					(size 0.7 0.7)
					(thickness 0.15)
				)
				(justify left bottom mirror)
			)
		)
		(fp_text user "${REFERENCE}"
			(at -0.939 -4.599 30)
			(layer "B.Fab")
			(effects
				(font
					(size 0.7 0.7)
					(thickness 0.15)
				)
				(justify left bottom mirror)
			)
		)
		(pad "1" smd roundrect
			(at -0.48 0 210)
			(size 0.59 0.64)
			(layers "B.Cu" "B.Mask" "B.Paste")
			(roundrect_rratio 0.25)
			(net 23 "GND")
			(pintype "passive")
		)
		(pad "2" smd roundrect
			(at 0.48 0 210)
			(size 0.59 0.64)
			(layers "B.Cu" "B.Mask" "B.Paste")
			(roundrect_rratio 0.25)
			(net 5 "P0_AVDDL")
			(pintype "passive")
		)
	)
	(footprint "antmicro-footprints:C_0402_1005Metric"
		(layer "B.Cu")
		(at 151.181865 80.260117 180)
		(descr "Capacitor SMD 0402")
		(tags "capacitor SMD 0402")
		(property "Reference" "C256"
			(at -20.368136 -9.464883 0)
			(layer "B.SilkS")
			(effects
				(font
					(size 0.7 0.7)
					(thickness 0.15)
				)
				(justify mirror)
			)
		)
		(property "Value" "C_1u_25V_0402"
			(at -1.022927 -2.155213 0)
			(layer "B.Fab")
			(effects
				(font
					(size 0.7 0.7)
					(thickness 0.15)
				)
				(justify left bottom mirror)
			)
		)
		(property "Datasheet" "https://www.murata.com/products/productdetail?partno=GRM155R61E105KE11%23"
			(at 0 0 0)
			(layer "B.Fab")
			(hide yes)
			(effects
				(font
					(size 1.27 1.27)
					(thickness 0.15)
				)
				(justify mirror)
			)
		)
		(property "Description" "SMD Multilayer Ceramic Capacitor, 1 µF, 25 V, 0402 [1005 Metric], ± 10%, X5R, GRM Series"
			(at 0 0 0)
			(layer "B.Fab")
			(hide yes)
			(effects
				(font
					(size 1.27 1.27)
					(thickness 0.15)
				)
				(justify mirror)
			)
		)
		(property "MPN" "GRM155R61E105KE11J"
			(at 0 0 180)
			(unlocked yes)
			(layer "B.Fab")
			(hide yes)
			(effects
				(font
					(size 1 1)
					(thickness 0.15)
				)
				(justify mirror)
			)
		)
		(property "Manufacturer" "Murata"
			(at 0 0 180)
			(unlocked yes)
			(layer "B.Fab")
			(hide yes)
			(effects
				(font
					(size 1 1)
					(thickness 0.15)
				)
				(justify mirror)
			)
		)
		(property "License" "Apache-2.0"
			(at 0 0 180)
			(unlocked yes)
			(layer "B.Fab")
			(hide yes)
			(effects
				(font
					(size 1 1)
					(thickness 0.15)
				)
				(justify mirror)
			)
		)
		(property "Author" "Antmicro"
			(at 0 0 180)
			(unlocked yes)
			(layer "B.Fab")
			(hide yes)
			(effects
				(font
					(size 1 1)
					(thickness 0.15)
				)
				(justify mirror)
			)
		)
		(property "Val" "1u"
			(at 0 0 180)
			(unlocked yes)
			(layer "B.Fab")
			(hide yes)
			(effects
				(font
					(size 1 1)
					(thickness 0.15)
				)
				(justify mirror)
			)
		)
		(property "Voltage" "25V"
			(at 0 0 180)
			(unlocked yes)
			(layer "B.Fab")
			(hide yes)
			(effects
				(font
					(size 1 1)
					(thickness 0.15)
				)
				(justify mirror)
			)
		)
		(property "Dielectric" "X5R"
			(at 0 0 180)
			(unlocked yes)
			(layer "B.Fab")
			(hide yes)
			(effects
				(font
					(size 1 1)
					(thickness 0.15)
				)
				(justify mirror)
			)
		)
		(sheetname "/X710-AT2 power/")
		(sheetfile "x710-at2-power.kicad_sch")
		(attr smd)
		(fp_rect
			(start -0.925 0.47)
			(end 0.925 -0.47)
			(stroke
				(width 0.05)
				(type default)
			)
			(fill no)
			(layer "B.CrtYd")
		)
		(fp_line
			(start 0.504 0.25)
			(end 0.504 -0.248)
			(stroke
				(width 0.15)
				(type solid)
			)
			(layer "B.Fab")
		)
		(fp_line
			(start 0.504 -0.248)
			(end -0.494 -0.248)
			(stroke
				(width 0.15)
				(type solid)
			)
			(layer "B.Fab")
		)
		(fp_line
			(start -0.494 0.25)
			(end 0.504 0.25)
			(stroke
				(width 0.15)
				(type solid)
			)
			(layer "B.Fab")
		)
		(fp_line
			(start -0.494 -0.248)
			(end -0.494 0.25)
			(stroke
				(width 0.15)
				(type solid)
			)
			(layer "B.Fab")
		)
		(fp_text user "Author: Antmicro"
			(at -0.939 -3.399 0)
			(layer "B.Fab")
			(effects
				(font
					(size 0.7 0.7)
					(thickness 0.15)
				)
				(justify left bottom mirror)
			)
		)
		(fp_text user "${REFERENCE}"
			(at -0.939 -4.599 0)
			(layer "B.Fab")
			(effects
				(font
					(size 0.7 0.7)
					(thickness 0.15)
				)
				(justify left bottom mirror)
			)
		)
		(fp_text user "License: Apache-2.0"
			(at -0.939 -5.799 0)
			(layer "B.Fab")
			(effects
				(font
					(size 0.7 0.7)
					(thickness 0.15)
				)
				(justify left bottom mirror)
			)
		)
		(pad "1" smd roundrect
			(at -0.48 0 180)
			(size 0.59 0.64)
			(layers "B.Cu" "B.Mask" "B.Paste")
			(roundrect_rratio 0.25)
			(net 23 "GND")
			(pintype "passive")
		)
		(pad "2" smd roundrect
			(at 0.48 0 180)
			(size 0.59 0.64)
			(layers "B.Cu" "B.Mask" "B.Paste")
			(roundrect_rratio 0.25)
			(net 9 "VCCD")
			(pintype "passive")
		)
	)
	(footprint "antmicro-footprints:C_0402_1005Metric"
		(layer "B.Cu")
		(at 156.111865 86.125116 180)
		(descr "Capacitor SMD 0402")
		(tags "capacitor SMD 0402")
		(property "Reference" "C190"
			(at -19.873134 -9.464883 0)
			(layer "B.SilkS")
			(effects
				(font
					(size 0.7 0.7)
					(thickness 0.15)
				)
				(justify mirror)
			)
		)
		(property "Value" "C_1u_25V_0402"
			(at -1.022927 -2.155213 0)
			(layer "B.Fab")
			(effects
				(font
					(size 0.7 0.7)
					(thickness 0.15)
				)
				(justify left bottom mirror)
			)
		)
		(property "Datasheet" "https://www.murata.com/products/productdetail?partno=GRM155R61E105KE11%23"
			(at 0 0 0)
			(layer "B.Fab")
			(hide yes)
			(effects
				(font
					(size 1.27 1.27)
					(thickness 0.15)
				)
				(justify mirror)
			)
		)
		(property "Description" "SMD Multilayer Ceramic Capacitor, 1 µF, 25 V, 0402 [1005 Metric], ± 10%, X5R, GRM Series"
			(at 0 0 0)
			(layer "B.Fab")
			(hide yes)
			(effects
				(font
					(size 1.27 1.27)
					(thickness 0.15)
				)
				(justify mirror)
			)
		)
		(property "MPN" "GRM155R61E105KE11J"
			(at 0 0 180)
			(unlocked yes)
			(layer "B.Fab")
			(hide yes)
			(effects
				(font
					(size 1 1)
					(thickness 0.15)
				)
				(justify mirror)
			)
		)
		(property "Manufacturer" "Murata"
			(at 0 0 180)
			(unlocked yes)
			(layer "B.Fab")
			(hide yes)
			(effects
				(font
					(size 1 1)
					(thickness 0.15)
				)
				(justify mirror)
			)
		)
		(property "License" "Apache-2.0"
			(at 0 0 180)
			(unlocked yes)
			(layer "B.Fab")
			(hide yes)
			(effects
				(font
					(size 1 1)
					(thickness 0.15)
				)
				(justify mirror)
			)
		)
		(property "Author" "Antmicro"
			(at 0 0 180)
			(unlocked yes)
			(layer "B.Fab")
			(hide yes)
			(effects
				(font
					(size 1 1)
					(thickness 0.15)
				)
				(justify mirror)
			)
		)
		(property "Val" "1u"
			(at 0 0 180)
			(unlocked yes)
			(layer "B.Fab")
			(hide yes)
			(effects
				(font
					(size 1 1)
					(thickness 0.15)
				)
				(justify mirror)
			)
		)
		(property "Voltage" "25V"
			(at 0 0 180)
			(unlocked yes)
			(layer "B.Fab")
			(hide yes)
			(effects
				(font
					(size 1 1)
					(thickness 0.15)
				)
				(justify mirror)
			)
		)
		(property "Dielectric" "X5R"
			(at 0 0 180)
			(unlocked yes)
			(layer "B.Fab")
			(hide yes)
			(effects
				(font
					(size 1 1)
					(thickness 0.15)
				)
				(justify mirror)
			)
		)
		(sheetname "/X710-AT2 power/")
		(sheetfile "x710-at2-power.kicad_sch")
		(attr smd)
		(fp_rect
			(start -0.925 0.47)
			(end 0.925 -0.47)
			(stroke
				(width 0.05)
				(type default)
			)
			(fill no)
			(layer "B.CrtYd")
		)
		(fp_line
			(start 0.504 0.25)
			(end 0.504 -0.248)
			(stroke
				(width 0.15)
				(type solid)
			)
			(layer "B.Fab")
		)
		(fp_line
			(start 0.504 -0.248)
			(end -0.494 -0.248)
			(stroke
				(width 0.15)
				(type solid)
			)
			(layer "B.Fab")
		)
		(fp_line
			(start -0.494 0.25)
			(end 0.504 0.25)
			(stroke
				(width 0.15)
				(type solid)
			)
			(layer "B.Fab")
		)
		(fp_line
			(start -0.494 -0.248)
			(end -0.494 0.25)
			(stroke
				(width 0.15)
				(type solid)
			)
			(layer "B.Fab")
		)
		(fp_text user "${REFERENCE}"
			(at -0.939 -4.599 0)
			(layer "B.Fab")
			(effects
				(font
					(size 0.7 0.7)
					(thickness 0.15)
				)
				(justify left bottom mirror)
			)
		)
		(fp_text user "Author: Antmicro"
			(at -0.939 -3.399 0)
			(layer "B.Fab")
			(effects
				(font
					(size 0.7 0.7)
					(thickness 0.15)
				)
				(justify left bottom mirror)
			)
		)
		(fp_text user "License: Apache-2.0"
			(at -0.939 -5.799 0)
			(layer "B.Fab")
			(effects
				(font
					(size 0.7 0.7)
					(thickness 0.15)
				)
				(justify left bottom mirror)
			)
		)
		(pad "1" smd roundrect
			(at -0.48 0 180)
			(size 0.59 0.64)
			(layers "B.Cu" "B.Mask" "B.Paste")
			(roundrect_rratio 0.25)
			(net 23 "GND")
			(pintype "passive")
		)
		(pad "2" smd roundrect
			(at 0.48 0 180)
			(size 0.59 0.64)
			(layers "B.Cu" "B.Mask" "B.Paste")
			(roundrect_rratio 0.25)
			(net 6 "DVDD")
			(pintype "passive")
		)
	)
	(footprint "antmicro-footprints:C_0402_1005Metric"
		(layer "B.Cu")
		(at 157.511866 87.605117 -90)
		(descr "Capacitor SMD 0402")
		(tags "capacitor SMD 0402")
		(property "Reference" "C183"
			(at 9.794883 -20.393133 90)
			(layer "B.SilkS")
			(effects
				(font
					(size 0.7 0.7)
					(thickness 0.15)
				)
				(justify mirror)
			)
		)
		(property "Value" "C_1u_25V_0402"
			(at -1.022927 -2.155213 90)
			(layer "B.Fab")
			(effects
				(font
					(size 0.7 0.7)
					(thickness 0.15)
				)
				(justify left bottom mirror)
			)
		)
		(property "Datasheet" "https://www.murata.com/products/productdetail?partno=GRM155R61E105KE11%23"
			(at 0 0 90)
			(layer "B.Fab")
			(hide yes)
			(effects
				(font
					(size 1.27 1.27)
					(thickness 0.15)
				)
				(justify mirror)
			)
		)
		(property "Description" "SMD Multilayer Ceramic Capacitor, 1 µF, 25 V, 0402 [1005 Metric], ± 10%, X5R, GRM Series"
			(at 0 0 90)
			(layer "B.Fab")
			(hide yes)
			(effects
				(font
					(size 1.27 1.27)
					(thickness 0.15)
				)
				(justify mirror)
			)
		)
		(property "MPN" "GRM155R61E105KE11J"
			(at 0 0 270)
			(unlocked yes)
			(layer "B.Fab")
			(hide yes)
			(effects
				(font
					(size 1 1)
					(thickness 0.15)
				)
				(justify mirror)
			)
		)
		(property "Manufacturer" "Murata"
			(at 0 0 270)
			(unlocked yes)
			(layer "B.Fab")
			(hide yes)
			(effects
				(font
					(size 1 1)
					(thickness 0.15)
				)
				(justify mirror)
			)
		)
		(property "License" "Apache-2.0"
			(at 0 0 270)
			(unlocked yes)
			(layer "B.Fab")
			(hide yes)
			(effects
				(font
					(size 1 1)
					(thickness 0.15)
				)
				(justify mirror)
			)
		)
		(property "Author" "Antmicro"
			(at 0 0 270)
			(unlocked yes)
			(layer "B.Fab")
			(hide yes)
			(effects
				(font
					(size 1 1)
					(thickness 0.15)
				)
				(justify mirror)
			)
		)
		(property "Val" "1u"
			(at 0 0 270)
			(unlocked yes)
			(layer "B.Fab")
			(hide yes)
			(effects
				(font
					(size 1 1)
					(thickness 0.15)
				)
				(justify mirror)
			)
		)
		(property "Voltage" "25V"
			(at 0 0 270)
			(unlocked yes)
			(layer "B.Fab")
			(hide yes)
			(effects
				(font
					(size 1 1)
					(thickness 0.15)
				)
				(justify mirror)
			)
		)
		(property "Dielectric" "X5R"
			(at 0 0 270)
			(unlocked yes)
			(layer "B.Fab")
			(hide yes)
			(effects
				(font
					(size 1 1)
					(thickness 0.15)
				)
				(justify mirror)
			)
		)
		(sheetname "/X710-AT2 power/")
		(sheetfile "x710-at2-power.kicad_sch")
		(attr smd)
		(fp_rect
			(start -0.925 0.47)
			(end 0.925 -0.47)
			(stroke
				(width 0.05)
				(type default)
			)
			(fill no)
			(layer "B.CrtYd")
		)
		(fp_line
			(start -0.494 0.25)
			(end 0.504 0.25)
			(stroke
				(width 0.15)
				(type solid)
			)
			(layer "B.Fab")
		)
		(fp_line
			(start 0.504 0.25)
			(end 0.504 -0.248)
			(stroke
				(width 0.15)
				(type solid)
			)
			(layer "B.Fab")
		)
		(fp_line
			(start -0.494 -0.248)
			(end -0.494 0.25)
			(stroke
				(width 0.15)
				(type solid)
			)
			(layer "B.Fab")
		)
		(fp_line
			(start 0.504 -0.248)
			(end -0.494 -0.248)
			(stroke
				(width 0.15)
				(type solid)
			)
			(layer "B.Fab")
		)
		(fp_text user "Author: Antmicro"
			(at -0.939 -3.399 90)
			(layer "B.Fab")
			(effects
				(font
					(size 0.7 0.7)
					(thickness 0.15)
				)
				(justify left bottom mirror)
			)
		)
		(fp_text user "License: Apache-2.0"
			(at -0.939 -5.799 90)
			(layer "B.Fab")
			(effects
				(font
					(size 0.7 0.7)
					(thickness 0.15)
				)
				(justify left bottom mirror)
			)
		)
		(fp_text user "${REFERENCE}"
			(at -0.939 -4.599 90)
			(layer "B.Fab")
			(effects
				(font
					(size 0.7 0.7)
					(thickness 0.15)
				)
				(justify left bottom mirror)
			)
		)
		(pad "1" smd roundrect
			(at -0.48 0 270)
			(size 0.59 0.64)
			(layers "B.Cu" "B.Mask" "B.Paste")
			(roundrect_rratio 0.25)
			(net 23 "GND")
			(pintype "passive")
		)
		(pad "2" smd roundrect
			(at 0.48 0 270)
			(size 0.59 0.64)
			(layers "B.Cu" "B.Mask" "B.Paste")
			(roundrect_rratio 0.25)
			(net 10 "AVDDH")
			(pintype "passive")
		)
	)
	(footprint "antmicro-footprints:C_0402_1005Metric"
		(layer "B.Cu")
		(at 151.181866 77.260117 180)
		(descr "Capacitor SMD 0402")
		(tags "capacitor SMD 0402")
		(property "Reference" "C227"
			(at -20.368136 -9.464883 0)
			(layer "B.SilkS")
			(effects
				(font
					(size 0.7 0.7)
					(thickness 0.15)
				)
				(justify mirror)
			)
		)
		(property "Value" "C_1u_25V_0402"
			(at -1.022927 -2.155213 0)
			(layer "B.Fab")
			(effects
				(font
					(size 0.7 0.7)
					(thickness 0.15)
				)
				(justify left bottom mirror)
			)
		)
		(property "Datasheet" "https://www.murata.com/products/productdetail?partno=GRM155R61E105KE11%23"
			(at 0 0 0)
			(layer "B.Fab")
			(hide yes)
			(effects
				(font
					(size 1.27 1.27)
					(thickness 0.15)
				)
				(justify mirror)
			)
		)
		(property "Description" "SMD Multilayer Ceramic Capacitor, 1 µF, 25 V, 0402 [1005 Metric], ± 10%, X5R, GRM Series"
			(at 0 0 0)
			(layer "B.Fab")
			(hide yes)
			(effects
				(font
					(size 1.27 1.27)
					(thickness 0.15)
				)
				(justify mirror)
			)
		)
		(property "MPN" "GRM155R61E105KE11J"
			(at 0 0 180)
			(unlocked yes)
			(layer "B.Fab")
			(hide yes)
			(effects
				(font
					(size 1 1)
					(thickness 0.15)
				)
				(justify mirror)
			)
		)
		(property "Manufacturer" "Murata"
			(at 0 0 180)
			(unlocked yes)
			(layer "B.Fab")
			(hide yes)
			(effects
				(font
					(size 1 1)
					(thickness 0.15)
				)
				(justify mirror)
			)
		)
		(property "License" "Apache-2.0"
			(at 0 0 180)
			(unlocked yes)
			(layer "B.Fab")
			(hide yes)
			(effects
				(font
					(size 1 1)
					(thickness 0.15)
				)
				(justify mirror)
			)
		)
		(property "Author" "Antmicro"
			(at 0 0 180)
			(unlocked yes)
			(layer "B.Fab")
			(hide yes)
			(effects
				(font
					(size 1 1)
					(thickness 0.15)
				)
				(justify mirror)
			)
		)
		(property "Val" "1u"
			(at 0 0 180)
			(unlocked yes)
			(layer "B.Fab")
			(hide yes)
			(effects
				(font
					(size 1 1)
					(thickness 0.15)
				)
				(justify mirror)
			)
		)
		(property "Voltage" "25V"
			(at 0 0 180)
			(unlocked yes)
			(layer "B.Fab")
			(hide yes)
			(effects
				(font
					(size 1 1)
					(thickness 0.15)
				)
				(justify mirror)
			)
		)
		(property "Dielectric" "X5R"
			(at 0 0 180)
			(unlocked yes)
			(layer "B.Fab")
			(hide yes)
			(effects
				(font
					(size 1 1)
					(thickness 0.15)
				)
				(justify mirror)
			)
		)
		(sheetname "/X710-AT2 power/")
		(sheetfile "x710-at2-power.kicad_sch")
		(attr smd)
		(fp_rect
			(start -0.925 0.47)
			(end 0.925 -0.47)
			(stroke
				(width 0.05)
				(type default)
			)
			(fill no)
			(layer "B.CrtYd")
		)
		(fp_line
			(start 0.504 0.25)
			(end 0.504 -0.248)
			(stroke
				(width 0.15)
				(type solid)
			)
			(layer "B.Fab")
		)
		(fp_line
			(start 0.504 -0.248)
			(end -0.494 -0.248)
			(stroke
				(width 0.15)
				(type solid)
			)
			(layer "B.Fab")
		)
		(fp_line
			(start -0.494 0.25)
			(end 0.504 0.25)
			(stroke
				(width 0.15)
				(type solid)
			)
			(layer "B.Fab")
		)
		(fp_line
			(start -0.494 -0.248)
			(end -0.494 0.25)
			(stroke
				(width 0.15)
				(type solid)
			)
			(layer "B.Fab")
		)
		(fp_text user "${REFERENCE}"
			(at -0.939 -4.599 0)
			(layer "B.Fab")
			(effects
				(font
					(size 0.7 0.7)
					(thickness 0.15)
				)
				(justify left bottom mirror)
			)
		)
		(fp_text user "License: Apache-2.0"
			(at -0.939 -5.799 0)
			(layer "B.Fab")
			(effects
				(font
					(size 0.7 0.7)
					(thickness 0.15)
				)
				(justify left bottom mirror)
			)
		)
		(fp_text user "Author: Antmicro"
			(at -0.939 -3.399 0)
			(layer "B.Fab")
			(effects
				(font
					(size 0.7 0.7)
					(thickness 0.15)
				)
				(justify left bottom mirror)
			)
		)
		(pad "1" smd roundrect
			(at -0.48 0 180)
			(size 0.59 0.64)
			(layers "B.Cu" "B.Mask" "B.Paste")
			(roundrect_rratio 0.25)
			(net 23 "GND")
			(pintype "passive")
		)
		(pad "2" smd roundrect
			(at 0.48 0 180)
			(size 0.59 0.64)
			(layers "B.Cu" "B.Mask" "B.Paste")
			(roundrect_rratio 0.25)
			(net 1 "VCCA")
			(pintype "passive")
		)
	)
	(footprint "antmicro-footprints:C_0402_1005Metric"
		(layer "B.Cu")
		(at 149.331865 79.260116 180)
		(descr "Capacitor SMD 0402")
		(tags "capacitor SMD 0402")
		(property "Reference" "C218"
			(at -19.468135 -9.464883 0)
			(layer "B.SilkS")
			(effects
				(font
					(size 0.7 0.7)
					(thickness 0.15)
				)
				(justify mirror)
			)
		)
		(property "Value" "C_1u_25V_0402"
			(at -1.022927 -2.155213 0)
			(layer "B.Fab")
			(effects
				(font
					(size 0.7 0.7)
					(thickness 0.15)
				)
				(justify left bottom mirror)
			)
		)
		(property "Datasheet" "https://www.murata.com/products/productdetail?partno=GRM155R61E105KE11%23"
			(at 0 0 0)
			(layer "B.Fab")
			(hide yes)
			(effects
				(font
					(size 1.27 1.27)
					(thickness 0.15)
				)
				(justify mirror)
			)
		)
		(property "Description" "SMD Multilayer Ceramic Capacitor, 1 µF, 25 V, 0402 [1005 Metric], ± 10%, X5R, GRM Series"
			(at 0 0 0)
			(layer "B.Fab")
			(hide yes)
			(effects
				(font
					(size 1.27 1.27)
					(thickness 0.15)
				)
				(justify mirror)
			)
		)
		(property "MPN" "GRM155R61E105KE11J"
			(at 0 0 180)
			(unlocked yes)
			(layer "B.Fab")
			(hide yes)
			(effects
				(font
					(size 1 1)
					(thickness 0.15)
				)
				(justify mirror)
			)
		)
		(property "Manufacturer" "Murata"
			(at 0 0 180)
			(unlocked yes)
			(layer "B.Fab")
			(hide yes)
			(effects
				(font
					(size 1 1)
					(thickness 0.15)
				)
				(justify mirror)
			)
		)
		(property "License" "Apache-2.0"
			(at 0 0 180)
			(unlocked yes)
			(layer "B.Fab")
			(hide yes)
			(effects
				(font
					(size 1 1)
					(thickness 0.15)
				)
				(justify mirror)
			)
		)
		(property "Author" "Antmicro"
			(at 0 0 180)
			(unlocked yes)
			(layer "B.Fab")
			(hide yes)
			(effects
				(font
					(size 1 1)
					(thickness 0.15)
				)
				(justify mirror)
			)
		)
		(property "Val" "1u"
			(at 0 0 180)
			(unlocked yes)
			(layer "B.Fab")
			(hide yes)
			(effects
				(font
					(size 1 1)
					(thickness 0.15)
				)
				(justify mirror)
			)
		)
		(property "Voltage" "25V"
			(at 0 0 180)
			(unlocked yes)
			(layer "B.Fab")
			(hide yes)
			(effects
				(font
					(size 1 1)
					(thickness 0.15)
				)
				(justify mirror)
			)
		)
		(property "Dielectric" "X5R"
			(at 0 0 180)
			(unlocked yes)
			(layer "B.Fab")
			(hide yes)
			(effects
				(font
					(size 1 1)
					(thickness 0.15)
				)
				(justify mirror)
			)
		)
		(sheetname "/X710-AT2 power/")
		(sheetfile "x710-at2-power.kicad_sch")
		(attr smd)
		(fp_rect
			(start -0.925 0.47)
			(end 0.925 -0.47)
			(stroke
				(width 0.05)
				(type default)
			)
			(fill no)
			(layer "B.CrtYd")
		)
		(fp_line
			(start 0.504 0.25)
			(end 0.504 -0.248)
			(stroke
				(width 0.15)
				(type solid)
			)
			(layer "B.Fab")
		)
		(fp_line
			(start 0.504 -0.248)
			(end -0.494 -0.248)
			(stroke
				(width 0.15)
				(type solid)
			)
			(layer "B.Fab")
		)
		(fp_line
			(start -0.494 0.25)
			(end 0.504 0.25)
			(stroke
				(width 0.15)
				(type solid)
			)
			(layer "B.Fab")
		)
		(fp_line
			(start -0.494 -0.248)
			(end -0.494 0.25)
			(stroke
				(width 0.15)
				(type solid)
			)
			(layer "B.Fab")
		)
		(fp_text user "Author: Antmicro"
			(at -0.939 -3.399 0)
			(layer "B.Fab")
			(effects
				(font
					(size 0.7 0.7)
					(thickness 0.15)
				)
				(justify left bottom mirror)
			)
		)
		(fp_text user "License: Apache-2.0"
			(at -0.939 -5.799 0)
			(layer "B.Fab")
			(effects
				(font
					(size 0.7 0.7)
					(thickness 0.15)
				)
				(justify left bottom mirror)
			)
		)
		(fp_text user "${REFERENCE}"
			(at -0.939 -4.599 0)
			(layer "B.Fab")
			(effects
				(font
					(size 0.7 0.7)
					(thickness 0.15)
				)
				(justify left bottom mirror)
			)
		)
		(pad "1" smd roundrect
			(at -0.48 0 180)
			(size 0.59 0.64)
			(layers "B.Cu" "B.Mask" "B.Paste")
			(roundrect_rratio 0.25)
			(net 23 "GND")
			(pintype "passive")
		)
		(pad "2" smd roundrect
			(at 0.48 0 180)
			(size 0.59 0.64)
			(layers "B.Cu" "B.Mask" "B.Paste")
			(roundrect_rratio 0.25)
			(net 9 "VCCD")
			(pintype "passive")
		)
	)
	(footprint "antmicro-footprints:C_0402_1005Metric"
		(layer "B.Cu")
		(at 135.850001 133.1 90)
		(descr "Capacitor SMD 0402")
		(tags "capacitor SMD 0402")
		(property "Reference" "C22"
			(at 8.339997 19.525001 270)
			(layer "B.SilkS")
			(effects
				(font
					(size 0.7 0.7)
					(thickness 0.15)
				)
				(justify mirror)
			)
		)
		(property "Value" "C_2u2_0402"
			(at -1.022927 -2.155213 270)
			(layer "B.Fab")
			(effects
				(font
					(size 0.7 0.7)
					(thickness 0.15)
				)
				(justify left bottom mirror)
			)
		)
		(property "Datasheet" "https://product.tdk.com/en/search/capacitor/ceramic/mlcc/info?part_no=C1005X5R1A225K050BC"
			(at 0 0 270)
			(layer "B.Fab")
			(hide yes)
			(effects
				(font
					(size 1.27 1.27)
					(thickness 0.15)
				)
				(justify mirror)
			)
		)
		(property "Description" "SMD Multilayer Ceramic Capacitor, 2.2 µF, 10 V, 0402 [1005 Metric], ± 10%, X5R, C"
			(at 0 0 270)
			(layer "B.Fab")
			(hide yes)
			(effects
				(font
					(size 1.27 1.27)
					(thickness 0.15)
				)
				(justify mirror)
			)
		)
		(property "MPN" "C1005X5R1A225K050BC"
			(at 0 0 90)
			(unlocked yes)
			(layer "B.Fab")
			(hide yes)
			(effects
				(font
					(size 1 1)
					(thickness 0.15)
				)
				(justify mirror)
			)
		)
		(property "Manufacturer" "TDK"
			(at 0 0 90)
			(unlocked yes)
			(layer "B.Fab")
			(hide yes)
			(effects
				(font
					(size 1 1)
					(thickness 0.15)
				)
				(justify mirror)
			)
		)
		(property "License" "Apache-2.0"
			(at 0 0 90)
			(unlocked yes)
			(layer "B.Fab")
			(hide yes)
			(effects
				(font
					(size 1 1)
					(thickness 0.15)
				)
				(justify mirror)
			)
		)
		(property "Val" "2u2"
			(at 0 0 90)
			(unlocked yes)
			(layer "B.Fab")
			(hide yes)
			(effects
				(font
					(size 1 1)
					(thickness 0.15)
				)
				(justify mirror)
			)
		)
		(property "Voltage" ""
			(at 0 0 90)
			(unlocked yes)
			(layer "B.Fab")
			(hide yes)
			(effects
				(font
					(size 1 1)
					(thickness 0.15)
				)
				(justify mirror)
			)
		)
		(property "Dielectric" ""
			(at 0 0 90)
			(unlocked yes)
			(layer "B.Fab")
			(hide yes)
			(effects
				(font
					(size 1 1)
					(thickness 0.15)
				)
				(justify mirror)
			)
		)
		(property "Author" "Antmicro"
			(at 0 0 90)
			(unlocked yes)
			(layer "B.Fab")
			(hide yes)
			(effects
				(font
					(size 1 1)
					(thickness 0.15)
				)
				(justify mirror)
			)
		)
		(sheetname "/PD and TB DC-DC/")
		(sheetfile "PD_and_TB_DC_DC.kicad_sch")
		(attr smd)
		(fp_rect
			(start -0.925 0.47)
			(end 0.925 -0.47)
			(stroke
				(width 0.05)
				(type default)
			)
			(fill no)
			(layer "B.CrtYd")
		)
		(fp_line
			(start 0.504 -0.248)
			(end -0.494 -0.248)
			(stroke
				(width 0.15)
				(type solid)
			)
			(layer "B.Fab")
		)
		(fp_line
			(start -0.494 -0.248)
			(end -0.494 0.25)
			(stroke
				(width 0.15)
				(type solid)
			)
			(layer "B.Fab")
		)
		(fp_line
			(start 0.504 0.25)
			(end 0.504 -0.248)
			(stroke
				(width 0.15)
				(type solid)
			)
			(layer "B.Fab")
		)
		(fp_line
			(start -0.494 0.25)
			(end 0.504 0.25)
			(stroke
				(width 0.15)
				(type solid)
			)
			(layer "B.Fab")
		)
		(fp_text user "License: Apache-2.0"
			(at -0.939 -5.799 270)
			(layer "B.Fab")
			(effects
				(font
					(size 0.7 0.7)
					(thickness 0.15)
				)
				(justify left bottom mirror)
			)
		)
		(fp_text user "${REFERENCE}"
			(at -0.939 -4.599 270)
			(layer "B.Fab")
			(effects
				(font
					(size 0.7 0.7)
					(thickness 0.15)
				)
				(justify left bottom mirror)
			)
		)
		(fp_text user "Author: Antmicro"
			(at -0.939 -3.399 270)
			(layer "B.Fab")
			(effects
				(font
					(size 0.7 0.7)
					(thickness 0.15)
				)
				(justify left bottom mirror)
			)
		)
		(pad "1" smd roundrect
			(at -0.48 0 90)
			(size 0.59 0.64)
			(layers "B.Cu" "B.Mask" "B.Paste")
			(roundrect_rratio 0.25)
			(net 176 "Net-(U3-LDO_BMC)")
			(pintype "passive")
		)
		(pad "2" smd roundrect
			(at 0.48 0 90)
			(size 0.59 0.64)
			(layers "B.Cu" "B.Mask" "B.Paste")
			(roundrect_rratio 0.25)
			(net 23 "GND")
			(pintype "passive")
		)
	)
	(footprint "antmicro-footprints:SOT-416"
		(layer "B.Cu")
		(at 178.5 70.5 -90)
		(descr "SOT-416")
		(tags "SOT-416")
		(property "Reference" "Q3"
			(at -0.75 1.3 90)
			(layer "B.SilkS")
			(effects
				(font
					(size 0.7 0.7)
					(thickness 0.15)
				)
				(justify left bottom mirror)
			)
		)
		(property "Value" "DTC014T_SOT-416"
			(at 0 -2 90)
			(layer "B.Fab")
			(effects
				(font
					(size 0.7 0.7)
					(thickness 0.15)
				)
				(justify left bottom mirror)
			)
		)
		(property "Datasheet" "https://www.rohm.com/datasheet?p=DTC014TEB&dist=Mouser&media=referral&source=mouser.com&campaign=Mouser"
			(at 0 0 90)
			(layer "B.Fab")
			(hide yes)
			(effects
				(font
					(size 1.27 1.27)
					(thickness 0.15)
				)
				(justify mirror)
			)
		)
		(property "Description" "Bipolar (BJT) Single Transistor with built-in base resistor, NPN, 50V, 100mA, 150mW, SOT-416FL, Surface Mount"
			(at 0 0 90)
			(layer "B.Fab")
			(hide yes)
			(effects
				(font
					(size 1.27 1.27)
					(thickness 0.15)
				)
				(justify mirror)
			)
		)
		(property "Manufacturer" "ROHM Semiconductor"
			(at 0 0 270)
			(unlocked yes)
			(layer "B.Fab")
			(hide yes)
			(effects
				(font
					(size 1 1)
					(thickness 0.15)
				)
				(justify mirror)
			)
		)
		(property "MPN" "DTC014TEBTL"
			(at 0 0 270)
			(unlocked yes)
			(layer "B.Fab")
			(hide yes)
			(effects
				(font
					(size 1 1)
					(thickness 0.15)
				)
				(justify mirror)
			)
		)
		(property "Author" "Antmicro"
			(at 0 0 270)
			(unlocked yes)
			(layer "B.Fab")
			(hide yes)
			(effects
				(font
					(size 1 1)
					(thickness 0.15)
				)
				(justify mirror)
			)
		)
		(property "License" "Apache-2.0"
			(at 0 0 270)
			(unlocked yes)
			(layer "B.Fab")
			(hide yes)
			(effects
				(font
					(size 1 1)
					(thickness 0.15)
				)
				(justify mirror)
			)
		)
		(sheetname "/X710 DCDC converters/")
		(sheetfile "DCDC_converters_X710.kicad_sch")
		(attr smd)
		(fp_line
			(start 0.508 0.9)
			(end -0.5 0.9)
			(stroke
				(width 0.15)
				(type solid)
			)
			(layer "B.SilkS")
		)
		(fp_line
			(start 0.508 0.9)
			(end 0.508 0.592)
			(stroke
				(width 0.15)
				(type solid)
			)
			(layer "B.SilkS")
		)
		(fp_line
			(start -0.5 0.15)
			(end -0.5 -0.15)
			(stroke
				(width 0.15)
				(type solid)
			)
			(layer "B.SilkS")
		)
		(fp_line
			(start 0.5 -0.9)
			(end 0.5 -0.7)
			(stroke
				(width 0.15)
				(type solid)
			)
			(layer "B.SilkS")
		)
		(fp_line
			(start 0.5 -0.9)
			(end -0.5 -0.9)
			(stroke
				(width 0.15)
				(type solid)
			)
			(layer "B.SilkS")
		)
		(fp_rect
			(start -1 1.05)
			(end 1 -1.05)
			(stroke
				(width 0.05)
				(type solid)
			)
			(fill no)
			(layer "B.CrtYd")
		)
		(fp_line
			(start -0.05 0.9)
			(end -0.45 0.5)
			(stroke
				(width 0.15)
				(type solid)
			)
			(layer "B.Fab")
		)
		(fp_rect
			(start 0.45 -0.9)
			(end -0.45 0.9)
			(stroke
				(width 0.15)
				(type solid)
			)
			(fill no)
			(layer "B.Fab")
		)
		(fp_text user "${REFERENCE}"
			(at -1 -3.4 90)
			(layer "B.Fab")
			(effects
				(font
					(size 0.7 0.7)
					(thickness 0.15)
				)
				(justify left bottom mirror)
			)
		)
		(fp_text user "License: Apache-2.0"
			(at -1 -5.802 90)
			(layer "B.Fab")
			(effects
				(font
					(size 0.7 0.7)
					(thickness 0.15)
				)
				(justify left bottom mirror)
			)
		)
		(fp_text user "Author: Antmicro"
			(at -1 -4.602 90)
			(layer "B.Fab")
			(effects
				(font
					(size 0.7 0.7)
					(thickness 0.15)
				)
				(justify left bottom mirror)
			)
		)
		(pad "1" smd rect
			(at -0.652 0.5 270)
			(size 0.6 0.5)
			(layers "B.Cu" "B.Mask" "B.Paste")
			(net 338 "/X710 DCDC converters/+1V88_OUT")
			(pinfunction "B")
			(pintype "input")
		)
		(pad "2" smd rect
			(at -0.652 -0.498 270)
			(size 0.6 0.5)
			(layers "B.Cu" "B.Mask" "B.Paste")
			(net 23 "GND")
			(pinfunction "E")
			(pintype "passive")
		)
		(pad "3" smd rect
			(at 0.65 0 270)
			(size 0.6 0.5)
			(layers "B.Cu" "B.Mask" "B.Paste")
			(net 429 "Net-(Q3-C)")
			(pinfunction "C")
			(pintype "passive")
		)
	)
	(footprint "antmicro-footprints:R_0402_1005Metric"
		(layer "B.Cu")
		(at 140.4 135.600001 180)
		(descr "Resistor SMD 0402")
		(tags "resistor SMD 0402")
		(property "Reference" "R13"
			(at -19.525001 8.1 0)
			(layer "B.SilkS")
			(effects
				(font
					(size 0.7 0.7)
					(thickness 0.15)
				)
				(justify mirror)
			)
		)
		(property "Value" "R_3k3_0402"
			(at -1.011843 -1.772047 0)
			(layer "B.Fab")
			(effects
				(font
					(size 0.7 0.7)
					(thickness 0.15)
				)
				(justify left bottom mirror)
			)
		)
		(property "Datasheet" "https://www.bourns.com/docs/product-datasheets/cr.pdf"
			(at 0 0 0)
			(layer "B.Fab")
			(hide yes)
			(effects
				(font
					(size 1.27 1.27)
					(thickness 0.15)
				)
				(justify mirror)
			)
		)
		(property "Description" "SMD Chip Resistor, 3.3 kohm, ± 1%, 63 mW, 0402 [1005 Metric], Thick Film, General Purpose"
			(at 0 0 0)
			(layer "B.Fab")
			(hide yes)
			(effects
				(font
					(size 1.27 1.27)
					(thickness 0.15)
				)
				(justify mirror)
			)
		)
		(property "MPN" "CR0402-FX-3301GLF"
			(at 0 0 180)
			(unlocked yes)
			(layer "B.Fab")
			(hide yes)
			(effects
				(font
					(size 1 1)
					(thickness 0.15)
				)
				(justify mirror)
			)
		)
		(property "Manufacturer" "Bourns"
			(at 0 0 180)
			(unlocked yes)
			(layer "B.Fab")
			(hide yes)
			(effects
				(font
					(size 1 1)
					(thickness 0.15)
				)
				(justify mirror)
			)
		)
		(property "License" "Apache-2.0"
			(at 0 0 180)
			(unlocked yes)
			(layer "B.Fab")
			(hide yes)
			(effects
				(font
					(size 1 1)
					(thickness 0.15)
				)
				(justify mirror)
			)
		)
		(property "Val" "3k3"
			(at 0 0 180)
			(unlocked yes)
			(layer "B.Fab")
			(hide yes)
			(effects
				(font
					(size 1 1)
					(thickness 0.15)
				)
				(justify mirror)
			)
		)
		(property "Tolerance" "1%"
			(at 0 0 180)
			(unlocked yes)
			(layer "B.Fab")
			(hide yes)
			(effects
				(font
					(size 1 1)
					(thickness 0.15)
				)
				(justify mirror)
			)
		)
		(property "Author" "Antmicro"
			(at 0 0 180)
			(unlocked yes)
			(layer "B.Fab")
			(hide yes)
			(effects
				(font
					(size 1 1)
					(thickness 0.15)
				)
				(justify mirror)
			)
		)
		(sheetname "/PD and TB DC-DC/")
		(sheetfile "PD_and_TB_DC_DC.kicad_sch")
		(attr smd)
		(fp_rect
			(start -0.925 0.47)
			(end 0.925 -0.47)
			(stroke
				(width 0.05)
				(type default)
			)
			(fill no)
			(layer "B.CrtYd")
		)
		(fp_rect
			(start -0.5 0.25)
			(end 0.5 -0.25)
			(stroke
				(width 0.15)
				(type solid)
			)
			(fill no)
			(layer "B.Fab")
		)
		(fp_text user "${REFERENCE}"
			(at -0.95 -3.168 0)
			(layer "B.Fab")
			(effects
				(font
					(size 0.7 0.7)
					(thickness 0.15)
				)
				(justify left bottom mirror)
			)
		)
		(fp_text user "Author: Antmicro"
			(at -0.95 -4.169 0)
			(layer "B.Fab")
			(effects
				(font
					(size 0.7 0.7)
					(thickness 0.15)
				)
				(justify left bottom mirror)
			)
		)
		(fp_text user "License: Apache-2.0"
			(at -0.95 -5.169 0)
			(layer "B.Fab")
			(effects
				(font
					(size 0.7 0.7)
					(thickness 0.15)
				)
				(justify left bottom mirror)
			)
		)
		(pad "1" smd roundrect
			(at -0.48 0 180)
			(size 0.59 0.64)
			(layers "B.Cu" "B.Mask" "B.Paste")
			(roundrect_rratio 0.25)
			(net 304 "/PD and TB DC-DC/TPS_3V3")
			(pintype "passive")
		)
		(pad "2" smd roundrect
			(at 0.48 0 180)
			(size 0.59 0.64)
			(layers "B.Cu" "B.Mask" "B.Paste")
			(roundrect_rratio 0.25)
			(net 199 "Net-(U3-I2C_SCL2)")
			(pintype "passive")
		)
	)
	(footprint "antmicro-footprints:R_0402_1005Metric"
		(layer "B.Cu")
		(at 156.131866 70.035117 -90)
		(descr "Resistor SMD 0402")
		(tags "resistor SMD 0402")
		(property "Reference" "R169"
			(at 9.464883 -19.468134 90)
			(layer "B.SilkS")
			(effects
				(font
					(size 0.7 0.7)
					(thickness 0.15)
				)
				(justify mirror)
			)
		)
		(property "Value" "R_22R_0402"
			(at -1.011843 -1.772047 90)
			(layer "B.Fab")
			(effects
				(font
					(size 0.7 0.7)
					(thickness 0.15)
				)
				(justify left bottom mirror)
			)
		)
		(property "Datasheet" "https://www.bourns.com/docs/product-datasheets/cr.pdf"
			(at 0 0 90)
			(layer "B.Fab")
			(hide yes)
			(effects
				(font
					(size 1.27 1.27)
					(thickness 0.15)
				)
				(justify mirror)
			)
		)
		(property "Description" "SMD Chip Resistor, 22 ohm, ± 1%, 62.5 mW, 0402 [1005 Metric], Thick Film, General Purpose"
			(at 0 0 90)
			(layer "B.Fab")
			(hide yes)
			(effects
				(font
					(size 1.27 1.27)
					(thickness 0.15)
				)
				(justify mirror)
			)
		)
		(property "MPN" "CR0402-FX-22R0GLF"
			(at 0 0 270)
			(unlocked yes)
			(layer "B.Fab")
			(hide yes)
			(effects
				(font
					(size 1 1)
					(thickness 0.15)
				)
				(justify mirror)
			)
		)
		(property "Manufacturer" "Bourns"
			(at 0 0 270)
			(unlocked yes)
			(layer "B.Fab")
			(hide yes)
			(effects
				(font
					(size 1 1)
					(thickness 0.15)
				)
				(justify mirror)
			)
		)
		(property "License" "Apache-2.0"
			(at 0 0 270)
			(unlocked yes)
			(layer "B.Fab")
			(hide yes)
			(effects
				(font
					(size 1 1)
					(thickness 0.15)
				)
				(justify mirror)
			)
		)
		(property "Author" "Antmicro"
			(at 0 0 270)
			(unlocked yes)
			(layer "B.Fab")
			(hide yes)
			(effects
				(font
					(size 1 1)
					(thickness 0.15)
				)
				(justify mirror)
			)
		)
		(property "Val" "22R"
			(at 0 0 270)
			(unlocked yes)
			(layer "B.Fab")
			(hide yes)
			(effects
				(font
					(size 1 1)
					(thickness 0.15)
				)
				(justify mirror)
			)
		)
		(property "Tolerance" "1%"
			(at 0 0 270)
			(unlocked yes)
			(layer "B.Fab")
			(hide yes)
			(effects
				(font
					(size 1 1)
					(thickness 0.15)
				)
				(justify mirror)
			)
		)
		(sheetname "/X710-AT2 Misc/")
		(sheetfile "x710-at2-mics.kicad_sch")
		(attr smd)
		(fp_rect
			(start -0.925 0.47)
			(end 0.925 -0.47)
			(stroke
				(width 0.05)
				(type default)
			)
			(fill no)
			(layer "B.CrtYd")
		)
		(fp_rect
			(start -0.5 0.25)
			(end 0.5 -0.25)
			(stroke
				(width 0.15)
				(type solid)
			)
			(fill no)
			(layer "B.Fab")
		)
		(fp_text user "Author: Antmicro"
			(at -0.95 -4.169 90)
			(layer "B.Fab")
			(effects
				(font
					(size 0.7 0.7)
					(thickness 0.15)
				)
				(justify left bottom mirror)
			)
		)
		(fp_text user "${REFERENCE}"
			(at -0.95 -3.168 90)
			(layer "B.Fab")
			(effects
				(font
					(size 0.7 0.7)
					(thickness 0.15)
				)
				(justify left bottom mirror)
			)
		)
		(fp_text user "License: Apache-2.0"
			(at -0.95 -5.169 90)
			(layer "B.Fab")
			(effects
				(font
					(size 0.7 0.7)
					(thickness 0.15)
				)
				(justify left bottom mirror)
			)
		)
		(pad "1" smd roundrect
			(at -0.48 0 270)
			(size 0.59 0.64)
			(layers "B.Cu" "B.Mask" "B.Paste")
			(roundrect_rratio 0.25)
			(net 137 "/X710-AT2 Misc/NCSI.RXD_1")
			(pintype "passive")
		)
		(pad "2" smd roundrect
			(at 0.48 0 270)
			(size 0.59 0.64)
			(layers "B.Cu" "B.Mask" "B.Paste")
			(roundrect_rratio 0.25)
			(net 443 "Net-(U14D-NCSI_RXD_1)")
			(pintype "passive")
		)
	)
	(footprint "antmicro-footprints:R_0402_1005Metric"
		(layer "B.Cu")
		(at 144.181866 76.260117 -90)
		(descr "Resistor SMD 0402")
		(tags "resistor SMD 0402")
		(property "Reference" "R116"
			(at -0.010117 1.181866 90)
			(layer "B.SilkS")
			(effects
				(font
					(size 0.7 0.7)
					(thickness 0.15)
				)
				(justify mirror)
			)
		)
		(property "Value" "R_4k75_0.5%_0402"
			(at -1.011843 -1.772047 90)
			(layer "B.Fab")
			(effects
				(font
					(size 0.7 0.7)
					(thickness 0.15)
				)
				(justify left bottom mirror)
			)
		)
		(property "Datasheet" "https://industrial.panasonic.com/cdbs/www-data/pdf/RDQ0000/ast-ind-151033.pdf"
			(at 0 0 90)
			(layer "B.Fab")
			(hide yes)
			(effects
				(font
					(size 1.27 1.27)
					(thickness 0.15)
				)
				(justify mirror)
			)
		)
		(property "Description" "SMD Chip Resistor, 4.75 kohm, ± 0.5%, 100 mW, 0402 [1005 Metric], Thick Film, High Temperature"
			(at 0 0 90)
			(layer "B.Fab")
			(hide yes)
			(effects
				(font
					(size 1.27 1.27)
					(thickness 0.15)
				)
				(justify mirror)
			)
		)
		(property "MPN" "ERJ-H2RD4751X"
			(at 0 0 270)
			(unlocked yes)
			(layer "B.Fab")
			(hide yes)
			(effects
				(font
					(size 1 1)
					(thickness 0.15)
				)
				(justify mirror)
			)
		)
		(property "Manufacturer" "Panasonic"
			(at 0 0 270)
			(unlocked yes)
			(layer "B.Fab")
			(hide yes)
			(effects
				(font
					(size 1 1)
					(thickness 0.15)
				)
				(justify mirror)
			)
		)
		(property "License" "Apache-2.0"
			(at 0 0 270)
			(unlocked yes)
			(layer "B.Fab")
			(hide yes)
			(effects
				(font
					(size 1 1)
					(thickness 0.15)
				)
				(justify mirror)
			)
		)
		(property "Author" "Antmicro"
			(at 0 0 270)
			(unlocked yes)
			(layer "B.Fab")
			(hide yes)
			(effects
				(font
					(size 1 1)
					(thickness 0.15)
				)
				(justify mirror)
			)
		)
		(property "Val" "4k75"
			(at 0 0 270)
			(unlocked yes)
			(layer "B.Fab")
			(hide yes)
			(effects
				(font
					(size 1 1)
					(thickness 0.15)
				)
				(justify mirror)
			)
		)
		(property "Tolerance" "0.5%"
			(at 0 0 270)
			(unlocked yes)
			(layer "B.Fab")
			(hide yes)
			(effects
				(font
					(size 1 1)
					(thickness 0.15)
				)
				(justify mirror)
			)
		)
		(sheetname "/X710-AT2 PCIe/")
		(sheetfile "x710-at2-pcie.kicad_sch")
		(attr smd)
		(fp_rect
			(start -0.925 0.47)
			(end 0.925 -0.47)
			(stroke
				(width 0.05)
				(type default)
			)
			(fill no)
			(layer "B.CrtYd")
		)
		(fp_rect
			(start -0.5 0.25)
			(end 0.5 -0.25)
			(stroke
				(width 0.15)
				(type solid)
			)
			(fill no)
			(layer "B.Fab")
		)
		(fp_text user "License: Apache-2.0"
			(at -0.95 -5.169 90)
			(layer "B.Fab")
			(effects
				(font
					(size 0.7 0.7)
					(thickness 0.15)
				)
				(justify left bottom mirror)
			)
		)
		(fp_text user "Author: Antmicro"
			(at -0.95 -4.169 90)
			(layer "B.Fab")
			(effects
				(font
					(size 0.7 0.7)
					(thickness 0.15)
				)
				(justify left bottom mirror)
			)
		)
		(fp_text user "${REFERENCE}"
			(at -0.95 -3.168 90)
			(layer "B.Fab")
			(effects
				(font
					(size 0.7 0.7)
					(thickness 0.15)
				)
				(justify left bottom mirror)
			)
		)
		(pad "1" smd roundrect
			(at -0.48 0 270)
			(size 0.59 0.64)
			(layers "B.Cu" "B.Mask" "B.Paste")
			(roundrect_rratio 0.25)
			(net 3 "/X710-AT2 PCIe/RBIAS")
			(pintype "passive")
		)
		(pad "2" smd roundrect
			(at 0.48 0 270)
			(size 0.59 0.64)
			(layers "B.Cu" "B.Mask" "B.Paste")
			(roundrect_rratio 0.25)
			(net 2 "/X710-AT2 PCIe/RSENSE")
			(pintype "passive")
		)
	)
	(footprint "antmicro-footprints:R_0402_1005Metric"
		(layer "B.Cu")
		(at 152.580001 146.66 90)
		(descr "Resistor SMD 0402")
		(tags "resistor SMD 0402")
		(property "Reference" "R211"
			(at -1.09 0.42 270)
			(layer "B.SilkS")
			(effects
				(font
					(size 0.7 0.7)
					(thickness 0.15)
				)
				(justify left bottom mirror)
			)
		)
		(property "Value" "R_220R_0402"
			(at -1.011843 -1.772047 270)
			(layer "B.Fab")
			(effects
				(font
					(size 0.7 0.7)
					(thickness 0.15)
				)
				(justify left bottom mirror)
			)
		)
		(property "Datasheet" "https://www.bourns.com/docs/product-datasheets/cr.pdf"
			(at 0 0 270)
			(layer "B.Fab")
			(hide yes)
			(effects
				(font
					(size 1.27 1.27)
					(thickness 0.15)
				)
				(justify mirror)
			)
		)
		(property "Description" "SMD Chip Resistor, 220 ohm, ± 1%, 62.5 mW, 0402 [1005 Metric], Thick Film, General Purpose"
			(at 0 0 270)
			(layer "B.Fab")
			(hide yes)
			(effects
				(font
					(size 1.27 1.27)
					(thickness 0.15)
				)
				(justify mirror)
			)
		)
		(property "MPN" "CR0402-FX-2200GLF"
			(at 0 0 90)
			(unlocked yes)
			(layer "B.Fab")
			(hide yes)
			(effects
				(font
					(size 1 1)
					(thickness 0.15)
				)
				(justify mirror)
			)
		)
		(property "Manufacturer" "Bourns"
			(at 0 0 90)
			(unlocked yes)
			(layer "B.Fab")
			(hide yes)
			(effects
				(font
					(size 1 1)
					(thickness 0.15)
				)
				(justify mirror)
			)
		)
		(property "License" "Apache-2.0"
			(at 0 0 90)
			(unlocked yes)
			(layer "B.Fab")
			(hide yes)
			(effects
				(font
					(size 1 1)
					(thickness 0.15)
				)
				(justify mirror)
			)
		)
		(property "Author" "Antmicro"
			(at 0 0 90)
			(unlocked yes)
			(layer "B.Fab")
			(hide yes)
			(effects
				(font
					(size 1 1)
					(thickness 0.15)
				)
				(justify mirror)
			)
		)
		(property "Val" "220R"
			(at 0 0 90)
			(unlocked yes)
			(layer "B.Fab")
			(hide yes)
			(effects
				(font
					(size 1 1)
					(thickness 0.15)
				)
				(justify mirror)
			)
		)
		(property "Tolerance" "1%"
			(at 0 0 90)
			(unlocked yes)
			(layer "B.Fab")
			(hide yes)
			(effects
				(font
					(size 1 1)
					(thickness 0.15)
				)
				(justify mirror)
			)
		)
		(sheetname "/2xRJ45/")
		(sheetfile "2xrj45.kicad_sch")
		(attr smd)
		(fp_rect
			(start -0.925 0.47)
			(end 0.925 -0.47)
			(stroke
				(width 0.05)
				(type default)
			)
			(fill no)
			(layer "B.CrtYd")
		)
		(fp_rect
			(start -0.5 0.25)
			(end 0.5 -0.25)
			(stroke
				(width 0.15)
				(type solid)
			)
			(fill no)
			(layer "B.Fab")
		)
		(fp_text user "License: Apache-2.0"
			(at -0.95 -5.169 270)
			(layer "B.Fab")
			(effects
				(font
					(size 0.7 0.7)
					(thickness 0.15)
				)
				(justify left bottom mirror)
			)
		)
		(fp_text user "Author: Antmicro"
			(at -0.95 -4.169 270)
			(layer "B.Fab")
			(effects
				(font
					(size 0.7 0.7)
					(thickness 0.15)
				)
				(justify left bottom mirror)
			)
		)
		(fp_text user "${REFERENCE}"
			(at -0.95 -3.168 270)
			(layer "B.Fab")
			(effects
				(font
					(size 0.7 0.7)
					(thickness 0.15)
				)
				(justify left bottom mirror)
			)
		)
		(pad "1" smd roundrect
			(at -0.48 0 90)
			(size 0.59 0.64)
			(layers "B.Cu" "B.Mask" "B.Paste")
			(roundrect_rratio 0.25)
			(net 408 "Net-(J3-LED_YG_G-)")
			(pintype "passive")
		)
		(pad "2" smd roundrect
			(at 0.48 0 90)
			(size 0.59 0.64)
			(layers "B.Cu" "B.Mask" "B.Paste")
			(roundrect_rratio 0.25)
			(net 60 "/2xRJ45/~{P0_LED_LINK_10G}")
			(pintype "passive")
		)
	)
	(footprint "antmicro-footprints:R_0402_1005Metric"
		(layer "B.Cu")
		(at 136.5 118.175)
		(descr "Resistor SMD 0402")
		(tags "resistor SMD 0402")
		(property "Reference" "R43"
			(at 19.525001 -7.450001 180)
			(layer "B.SilkS")
			(effects
				(font
					(size 0.7 0.7)
					(thickness 0.15)
				)
				(justify mirror)
			)
		)
		(property "Value" "R_100k_0402"
			(at -1.011843 -1.772047 180)
			(layer "B.Fab")
			(effects
				(font
					(size 0.7 0.7)
					(thickness 0.15)
				)
				(justify left bottom mirror)
			)
		)
		(property "Datasheet" "https://www.bourns.com/docs/product-datasheets/cr.pdf"
			(at 0 0 180)
			(layer "B.Fab")
			(hide yes)
			(effects
				(font
					(size 1.27 1.27)
					(thickness 0.15)
				)
				(justify mirror)
			)
		)
		(property "Description" "SMD Chip Resistor, 100 kohm, ± 1%, 62.5 mW, 0402 [1005 Metric], Thick Film, General Purpose"
			(at 0 0 180)
			(layer "B.Fab")
			(hide yes)
			(effects
				(font
					(size 1.27 1.27)
					(thickness 0.15)
				)
				(justify mirror)
			)
		)
		(property "MPN" "CR0402-FX-1003GLF"
			(at 0 0 0)
			(unlocked yes)
			(layer "B.Fab")
			(hide yes)
			(effects
				(font
					(size 1 1)
					(thickness 0.15)
				)
				(justify mirror)
			)
		)
		(property "Manufacturer" "Bourns"
			(at 0 0 0)
			(unlocked yes)
			(layer "B.Fab")
			(hide yes)
			(effects
				(font
					(size 1 1)
					(thickness 0.15)
				)
				(justify mirror)
			)
		)
		(property "License" "Apache-2.0"
			(at 0 0 0)
			(unlocked yes)
			(layer "B.Fab")
			(hide yes)
			(effects
				(font
					(size 1 1)
					(thickness 0.15)
				)
				(justify mirror)
			)
		)
		(property "Val" "100k"
			(at 0 0 0)
			(unlocked yes)
			(layer "B.Fab")
			(hide yes)
			(effects
				(font
					(size 1 1)
					(thickness 0.15)
				)
				(justify mirror)
			)
		)
		(property "Tolerance" "1%"
			(at 0 0 0)
			(unlocked yes)
			(layer "B.Fab")
			(hide yes)
			(effects
				(font
					(size 1 1)
					(thickness 0.15)
				)
				(justify mirror)
			)
		)
		(property "Author" "Antmicro"
			(at 0 0 0)
			(unlocked yes)
			(layer "B.Fab")
			(hide yes)
			(effects
				(font
					(size 1 1)
					(thickness 0.15)
				)
				(justify mirror)
			)
		)
		(sheetname "/TB Controller/")
		(sheetfile "tb.kicad_sch")
		(attr smd)
		(fp_rect
			(start -0.925 0.47)
			(end 0.925 -0.47)
			(stroke
				(width 0.05)
				(type default)
			)
			(fill no)
			(layer "B.CrtYd")
		)
		(fp_rect
			(start -0.5 0.25)
			(end 0.5 -0.25)
			(stroke
				(width 0.15)
				(type solid)
			)
			(fill no)
			(layer "B.Fab")
		)
		(fp_text user "License: Apache-2.0"
			(at -0.95 -5.169 180)
			(layer "B.Fab")
			(effects
				(font
					(size 0.7 0.7)
					(thickness 0.15)
				)
				(justify left bottom mirror)
			)
		)
		(fp_text user "Author: Antmicro"
			(at -0.95 -4.169 180)
			(layer "B.Fab")
			(effects
				(font
					(size 0.7 0.7)
					(thickness 0.15)
				)
				(justify left bottom mirror)
			)
		)
		(fp_text user "${REFERENCE}"
			(at -0.95 -3.168 180)
			(layer "B.Fab")
			(effects
				(font
					(size 0.7 0.7)
					(thickness 0.15)
				)
				(justify left bottom mirror)
			)
		)
		(pad "1" smd roundrect
			(at -0.48 0)
			(size 0.59 0.64)
			(layers "B.Cu" "B.Mask" "B.Paste")
			(roundrect_rratio 0.25)
			(net 186 "Net-(U4C-GPIO_3)")
			(pintype "passive")
		)
		(pad "2" smd roundrect
			(at 0.48 0)
			(size 0.59 0.64)
			(layers "B.Cu" "B.Mask" "B.Paste")
			(roundrect_rratio 0.25)
			(net 23 "GND")
			(pintype "passive")
		)
	)
	(footprint "antmicro-footprints:R_0402_1005Metric"
		(layer "B.Cu")
		(at 148.681866 92.485117 90)
		(descr "Resistor SMD 0402")
		(tags "resistor SMD 0402")
		(property "Reference" "R142"
			(at -10.814884 18.718134 270)
			(layer "B.SilkS")
			(effects
				(font
					(size 0.7 0.7)
					(thickness 0.15)
				)
				(justify mirror)
			)
		)
		(property "Value" "R_0R_0402"
			(at -1.011843 -1.772047 270)
			(layer "B.Fab")
			(effects
				(font
					(size 0.7 0.7)
					(thickness 0.15)
				)
				(justify left bottom mirror)
			)
		)
		(property "Datasheet" "https://industrial.panasonic.com/cdbs/www-data/pdf/RDA0000/AOA0000C301.pdf"
			(at 0 0 270)
			(layer "B.Fab")
			(hide yes)
			(effects
				(font
					(size 1.27 1.27)
					(thickness 0.15)
				)
				(justify mirror)
			)
		)
		(property "Description" "SMD Chip Resistor, Jumper, 0 ohm, 100 mW, 0402 [1005 Metric], Thick Film, General Purpose"
			(at 0 0 270)
			(layer "B.Fab")
			(hide yes)
			(effects
				(font
					(size 1.27 1.27)
					(thickness 0.15)
				)
				(justify mirror)
			)
		)
		(property "MPN" "ERJ2GE0R00X"
			(at 0 0 90)
			(unlocked yes)
			(layer "B.Fab")
			(hide yes)
			(effects
				(font
					(size 1 1)
					(thickness 0.15)
				)
				(justify mirror)
			)
		)
		(property "Manufacturer" "Panasonic"
			(at 0 0 90)
			(unlocked yes)
			(layer "B.Fab")
			(hide yes)
			(effects
				(font
					(size 1 1)
					(thickness 0.15)
				)
				(justify mirror)
			)
		)
		(property "License" "Apache-2.0"
			(at 0 0 90)
			(unlocked yes)
			(layer "B.Fab")
			(hide yes)
			(effects
				(font
					(size 1 1)
					(thickness 0.15)
				)
				(justify mirror)
			)
		)
		(property "Author" "Antmicro"
			(at 0 0 90)
			(unlocked yes)
			(layer "B.Fab")
			(hide yes)
			(effects
				(font
					(size 1 1)
					(thickness 0.15)
				)
				(justify mirror)
			)
		)
		(property "Val" "0R"
			(at 0 0 90)
			(unlocked yes)
			(layer "B.Fab")
			(hide yes)
			(effects
				(font
					(size 1 1)
					(thickness 0.15)
				)
				(justify mirror)
			)
		)
		(property "Tolerance" "~"
			(at 0 0 90)
			(unlocked yes)
			(layer "B.Fab")
			(hide yes)
			(effects
				(font
					(size 1 1)
					(thickness 0.15)
				)
				(justify mirror)
			)
		)
		(property "Current" "1A"
			(at 0 0 90)
			(unlocked yes)
			(layer "B.Fab")
			(hide yes)
			(effects
				(font
					(size 1 1)
					(thickness 0.15)
				)
				(justify mirror)
			)
		)
		(sheetname "/X710-AT2 Misc/")
		(sheetfile "x710-at2-mics.kicad_sch")
		(attr smd)
		(fp_rect
			(start -0.925 0.47)
			(end 0.925 -0.47)
			(stroke
				(width 0.05)
				(type default)
			)
			(fill no)
			(layer "B.CrtYd")
		)
		(fp_rect
			(start -0.5 0.25)
			(end 0.5 -0.25)
			(stroke
				(width 0.15)
				(type solid)
			)
			(fill no)
			(layer "B.Fab")
		)
		(fp_text user "License: Apache-2.0"
			(at -0.95 -5.169 270)
			(layer "B.Fab")
			(effects
				(font
					(size 0.7 0.7)
					(thickness 0.15)
				)
				(justify left bottom mirror)
			)
		)
		(fp_text user "Author: Antmicro"
			(at -0.95 -4.169 270)
			(layer "B.Fab")
			(effects
				(font
					(size 0.7 0.7)
					(thickness 0.15)
				)
				(justify left bottom mirror)
			)
		)
		(fp_text user "${REFERENCE}"
			(at -0.95 -3.168 270)
			(layer "B.Fab")
			(effects
				(font
					(size 0.7 0.7)
					(thickness 0.15)
				)
				(justify left bottom mirror)
			)
		)
		(pad "1" smd roundrect
			(at -0.48 0 90)
			(size 0.59 0.64)
			(layers "B.Cu" "B.Mask" "B.Paste")
			(roundrect_rratio 0.25)
			(net 82 "/X710-AT2 Misc/GPIO5_POR_BYPASS")
			(pintype "passive")
		)
		(pad "2" smd roundrect
			(at 0.48 0 90)
			(size 0.59 0.64)
			(layers "B.Cu" "B.Mask" "B.Paste")
			(roundrect_rratio 0.25)
			(net 35 "/X710-AT2 Misc/POR_BYPASS")
			(pintype "passive")
		)
	)
	(footprint "antmicro-footprints:C_0402_1005Metric"
		(layer "B.Cu")
		(at 157.961866 84.055117 180)
		(descr "Capacitor SMD 0402")
		(tags "capacitor SMD 0402")
		(property "Reference" "C198"
			(at -20.793134 -9.464883 0)
			(layer "B.SilkS")
			(effects
				(font
					(size 0.7 0.7)
					(thickness 0.15)
				)
				(justify mirror)
			)
		)
		(property "Value" "C_1u_25V_0402"
			(at -1.022927 -2.155213 0)
			(layer "B.Fab")
			(effects
				(font
					(size 0.7 0.7)
					(thickness 0.15)
				)
				(justify left bottom mirror)
			)
		)
		(property "Datasheet" "https://www.murata.com/products/productdetail?partno=GRM155R61E105KE11%23"
			(at 0 0 0)
			(layer "B.Fab")
			(hide yes)
			(effects
				(font
					(size 1.27 1.27)
					(thickness 0.15)
				)
				(justify mirror)
			)
		)
		(property "Description" "SMD Multilayer Ceramic Capacitor, 1 µF, 25 V, 0402 [1005 Metric], ± 10%, X5R, GRM Series"
			(at 0 0 0)
			(layer "B.Fab")
			(hide yes)
			(effects
				(font
					(size 1.27 1.27)
					(thickness 0.15)
				)
				(justify mirror)
			)
		)
		(property "MPN" "GRM155R61E105KE11J"
			(at 0 0 180)
			(unlocked yes)
			(layer "B.Fab")
			(hide yes)
			(effects
				(font
					(size 1 1)
					(thickness 0.15)
				)
				(justify mirror)
			)
		)
		(property "Manufacturer" "Murata"
			(at 0 0 180)
			(unlocked yes)
			(layer "B.Fab")
			(hide yes)
			(effects
				(font
					(size 1 1)
					(thickness 0.15)
				)
				(justify mirror)
			)
		)
		(property "License" "Apache-2.0"
			(at 0 0 180)
			(unlocked yes)
			(layer "B.Fab")
			(hide yes)
			(effects
				(font
					(size 1 1)
					(thickness 0.15)
				)
				(justify mirror)
			)
		)
		(property "Author" "Antmicro"
			(at 0 0 180)
			(unlocked yes)
			(layer "B.Fab")
			(hide yes)
			(effects
				(font
					(size 1 1)
					(thickness 0.15)
				)
				(justify mirror)
			)
		)
		(property "Val" "1u"
			(at 0 0 180)
			(unlocked yes)
			(layer "B.Fab")
			(hide yes)
			(effects
				(font
					(size 1 1)
					(thickness 0.15)
				)
				(justify mirror)
			)
		)
		(property "Voltage" "25V"
			(at 0 0 180)
			(unlocked yes)
			(layer "B.Fab")
			(hide yes)
			(effects
				(font
					(size 1 1)
					(thickness 0.15)
				)
				(justify mirror)
			)
		)
		(property "Dielectric" "X5R"
			(at 0 0 180)
			(unlocked yes)
			(layer "B.Fab")
			(hide yes)
			(effects
				(font
					(size 1 1)
					(thickness 0.15)
				)
				(justify mirror)
			)
		)
		(sheetname "/X710-AT2 power/")
		(sheetfile "x710-at2-power.kicad_sch")
		(attr smd)
		(fp_rect
			(start -0.925 0.47)
			(end 0.925 -0.47)
			(stroke
				(width 0.05)
				(type default)
			)
			(fill no)
			(layer "B.CrtYd")
		)
		(fp_line
			(start 0.504 0.25)
			(end 0.504 -0.248)
			(stroke
				(width 0.15)
				(type solid)
			)
			(layer "B.Fab")
		)
		(fp_line
			(start 0.504 -0.248)
			(end -0.494 -0.248)
			(stroke
				(width 0.15)
				(type solid)
			)
			(layer "B.Fab")
		)
		(fp_line
			(start -0.494 0.25)
			(end 0.504 0.25)
			(stroke
				(width 0.15)
				(type solid)
			)
			(layer "B.Fab")
		)
		(fp_line
			(start -0.494 -0.248)
			(end -0.494 0.25)
			(stroke
				(width 0.15)
				(type solid)
			)
			(layer "B.Fab")
		)
		(fp_text user "Author: Antmicro"
			(at -0.939 -3.399 0)
			(layer "B.Fab")
			(effects
				(font
					(size 0.7 0.7)
					(thickness 0.15)
				)
				(justify left bottom mirror)
			)
		)
		(fp_text user "License: Apache-2.0"
			(at -0.939 -5.799 0)
			(layer "B.Fab")
			(effects
				(font
					(size 0.7 0.7)
					(thickness 0.15)
				)
				(justify left bottom mirror)
			)
		)
		(fp_text user "${REFERENCE}"
			(at -0.939 -4.599 0)
			(layer "B.Fab")
			(effects
				(font
					(size 0.7 0.7)
					(thickness 0.15)
				)
				(justify left bottom mirror)
			)
		)
		(pad "1" smd roundrect
			(at -0.48 0 180)
			(size 0.59 0.64)
			(layers "B.Cu" "B.Mask" "B.Paste")
			(roundrect_rratio 0.25)
			(net 23 "GND")
			(pintype "passive")
		)
		(pad "2" smd roundrect
			(at 0.48 0 180)
			(size 0.59 0.64)
			(layers "B.Cu" "B.Mask" "B.Paste")
			(roundrect_rratio 0.25)
			(net 10 "AVDDH")
			(pintype "passive")
		)
	)
	(footprint "antmicro-footprints:C_0402_1005Metric"
		(layer "B.Cu")
		(at 128.1 129.3)
		(descr "Capacitor SMD 0402")
		(tags "capacitor SMD 0402")
		(property "Reference" "C95"
			(at 21.6 -7.7 180)
			(layer "B.SilkS")
			(effects
				(font
					(size 0.7 0.7)
					(thickness 0.15)
				)
				(justify mirror)
			)
		)
		(property "Value" "C_10u_0402"
			(at -1.022927 -2.155213 180)
			(layer "B.Fab")
			(effects
				(font
					(size 0.7 0.7)
					(thickness 0.15)
				)
				(justify left bottom mirror)
			)
		)
		(property "Datasheet" "https://www.yageo.com/en/Chart/Download/pdf/CC0402MRX5R5BB106"
			(at 0 0 180)
			(layer "B.Fab")
			(hide yes)
			(effects
				(font
					(size 1.27 1.27)
					(thickness 0.15)
				)
				(justify mirror)
			)
		)
		(property "Description" "SMD Multilayer Ceramic Capacitor, 10 µF, 6.3 V, 0402 [1005 Metric], ± 20%, X5R, CC Series"
			(at 0 0 180)
			(layer "B.Fab")
			(hide yes)
			(effects
				(font
					(size 1.27 1.27)
					(thickness 0.15)
				)
				(justify mirror)
			)
		)
		(property "MPN" "CC0402MRX5R5BB106"
			(at 0 0 0)
			(unlocked yes)
			(layer "B.Fab")
			(hide yes)
			(effects
				(font
					(size 1 1)
					(thickness 0.15)
				)
				(justify mirror)
			)
		)
		(property "Manufacturer" "YAGEO"
			(at 0 0 0)
			(unlocked yes)
			(layer "B.Fab")
			(hide yes)
			(effects
				(font
					(size 1 1)
					(thickness 0.15)
				)
				(justify mirror)
			)
		)
		(property "License" "Apache-2.0"
			(at 0 0 0)
			(unlocked yes)
			(layer "B.Fab")
			(hide yes)
			(effects
				(font
					(size 1 1)
					(thickness 0.15)
				)
				(justify mirror)
			)
		)
		(property "Val" "10u"
			(at 0 0 0)
			(unlocked yes)
			(layer "B.Fab")
			(hide yes)
			(effects
				(font
					(size 1 1)
					(thickness 0.15)
				)
				(justify mirror)
			)
		)
		(property "Voltage" ""
			(at 0 0 0)
			(unlocked yes)
			(layer "B.Fab")
			(hide yes)
			(effects
				(font
					(size 1 1)
					(thickness 0.15)
				)
				(justify mirror)
			)
		)
		(property "Dielectric" ""
			(at 0 0 0)
			(unlocked yes)
			(layer "B.Fab")
			(hide yes)
			(effects
				(font
					(size 1 1)
					(thickness 0.15)
				)
				(justify mirror)
			)
		)
		(property "Author" "Antmicro"
			(at 0 0 0)
			(unlocked yes)
			(layer "B.Fab")
			(hide yes)
			(effects
				(font
					(size 1 1)
					(thickness 0.15)
				)
				(justify mirror)
			)
		)
		(sheetname "/TB Controller - Power/")
		(sheetfile "tb-power.kicad_sch")
		(attr smd)
		(fp_rect
			(start -0.925 0.47)
			(end 0.925 -0.47)
			(stroke
				(width 0.05)
				(type default)
			)
			(fill no)
			(layer "B.CrtYd")
		)
		(fp_line
			(start -0.494 -0.248)
			(end -0.494 0.25)
			(stroke
				(width 0.15)
				(type solid)
			)
			(layer "B.Fab")
		)
		(fp_line
			(start -0.494 0.25)
			(end 0.504 0.25)
			(stroke
				(width 0.15)
				(type solid)
			)
			(layer "B.Fab")
		)
		(fp_line
			(start 0.504 -0.248)
			(end -0.494 -0.248)
			(stroke
				(width 0.15)
				(type solid)
			)
			(layer "B.Fab")
		)
		(fp_line
			(start 0.504 0.25)
			(end 0.504 -0.248)
			(stroke
				(width 0.15)
				(type solid)
			)
			(layer "B.Fab")
		)
		(fp_text user "${REFERENCE}"
			(at -0.939 -4.599 180)
			(layer "B.Fab")
			(effects
				(font
					(size 0.7 0.7)
					(thickness 0.15)
				)
				(justify left bottom mirror)
			)
		)
		(fp_text user "License: Apache-2.0"
			(at -0.939 -5.799 180)
			(layer "B.Fab")
			(effects
				(font
					(size 0.7 0.7)
					(thickness 0.15)
				)
				(justify left bottom mirror)
			)
		)
		(fp_text user "Author: Antmicro"
			(at -0.939 -3.399 180)
			(layer "B.Fab")
			(effects
				(font
					(size 0.7 0.7)
					(thickness 0.15)
				)
				(justify left bottom mirror)
			)
		)
		(pad "1" smd roundrect
			(at -0.48 0)
			(size 0.59 0.64)
			(layers "B.Cu" "B.Mask" "B.Paste")
			(roundrect_rratio 0.25)
			(net 23 "GND")
			(pintype "passive")
		)
		(pad "2" smd roundrect
			(at 0.48 0)
			(size 0.59 0.64)
			(layers "B.Cu" "B.Mask" "B.Paste")
			(roundrect_rratio 0.25)
			(net 180 "Net-(U4A-VCC0P9_LVR_SENSE)")
			(pintype "passive")
		)
	)
	(footprint "antmicro-footprints:L_0603_1608Metric"
		(layer "B.Cu")
		(at 126.309999 117.589999 -90)
		(property "Reference" "L3"
			(at -7.700002 -21.900002 90)
			(layer "B.SilkS")
			(effects
				(font
					(size 0.7 0.7)
					(thickness 0.15)
				)
				(justify mirror)
			)
		)
		(property "Value" "L_1u_1.8A_0603"
			(at 0 -2 90)
			(layer "B.Fab")
			(effects
				(font
					(size 0.7 0.7)
					(thickness 0.15)
				)
				(justify left bottom mirror)
			)
		)
		(property "Datasheet" "https://search.murata.co.jp/Ceramy/image/img/P02/JETE243A-0041.pdf"
			(at 0 0 90)
			(layer "B.Fab")
			(hide yes)
			(effects
				(font
					(size 1.27 1.27)
					(thickness 0.15)
				)
				(justify mirror)
			)
		)
		(property "Description" "Power Inductor (SMT), 1 µH, 1.8 A, Shielded, 1.9 A, DFE Series, 0603 [1608 Metric]"
			(at 0 0 90)
			(layer "B.Fab")
			(hide yes)
			(effects
				(font
					(size 1.27 1.27)
					(thickness 0.15)
				)
				(justify mirror)
			)
		)
		(property "Val" "1u/1.8A"
			(at 0 0 270)
			(unlocked yes)
			(layer "B.Fab")
			(hide yes)
			(effects
				(font
					(size 1 1)
					(thickness 0.15)
				)
				(justify mirror)
			)
		)
		(property "Manufacturer" "Murata"
			(at 0 0 270)
			(unlocked yes)
			(layer "B.Fab")
			(hide yes)
			(effects
				(font
					(size 1 1)
					(thickness 0.15)
				)
				(justify mirror)
			)
		)
		(property "MPN" "DFE18SBN1R0ME0L"
			(at 0 0 270)
			(unlocked yes)
			(layer "B.Fab")
			(hide yes)
			(effects
				(font
					(size 1 1)
					(thickness 0.15)
				)
				(justify mirror)
			)
		)
		(property "ISat" "1.9A"
			(at 0 0 270)
			(unlocked yes)
			(layer "B.Fab")
			(hide yes)
			(effects
				(font
					(size 1 1)
					(thickness 0.15)
				)
				(justify mirror)
			)
		)
		(property "IMax" "1.8A"
			(at 0 0 270)
			(unlocked yes)
			(layer "B.Fab")
			(hide yes)
			(effects
				(font
					(size 1 1)
					(thickness 0.15)
				)
				(justify mirror)
			)
		)
		(property "Size" "1.6x0.8"
			(at 0 0 270)
			(unlocked yes)
			(layer "B.Fab")
			(hide yes)
			(effects
				(font
					(size 1 1)
					(thickness 0.15)
				)
				(justify mirror)
			)
		)
		(property "License" "Apache-2.0"
			(at 0 0 270)
			(unlocked yes)
			(layer "B.Fab")
			(hide yes)
			(effects
				(font
					(size 1 1)
					(thickness 0.15)
				)
				(justify mirror)
			)
		)
		(property "Author" "Antmicro"
			(at 0 0 270)
			(unlocked yes)
			(layer "B.Fab")
			(hide yes)
			(effects
				(font
					(size 1 1)
					(thickness 0.15)
				)
				(justify mirror)
			)
		)
		(sheetname "/TB Controller - Power/")
		(sheetfile "tb-power.kicad_sch")
		(attr smd)
		(fp_line
			(start -0.15 0.4)
			(end 0.15 0.4)
			(stroke
				(width 0.15)
				(type solid)
			)
			(layer "B.SilkS")
		)
		(fp_line
			(start -0.15 -0.4)
			(end 0.15 -0.4)
			(stroke
				(width 0.15)
				(type solid)
			)
			(layer "B.SilkS")
		)
		(fp_rect
			(start -1.25 0.65)
			(end 1.25 -0.65)
			(stroke
				(width 0.05)
				(type solid)
			)
			(fill no)
			(layer "B.CrtYd")
		)
		(fp_rect
			(start -0.8 0.4)
			(end 0.8 -0.4)
			(stroke
				(width 0.1)
				(type solid)
			)
			(fill no)
			(layer "B.Fab")
		)
		(fp_text user "${REFERENCE}"
			(at -1.9 -3.1 90)
			(layer "B.Fab")
			(effects
				(font
					(size 0.7 0.7)
					(thickness 0.15)
				)
				(justify left bottom mirror)
			)
		)
		(fp_text user "License: Apache-2.0"
			(at -1.9 -5.75 90)
			(layer "B.Fab")
			(effects
				(font
					(size 0.7 0.7)
					(thickness 0.15)
				)
				(justify left bottom mirror)
			)
		)
		(fp_text user "Author: Antmicro"
			(at -1.9 -4.4 90)
			(layer "B.Fab")
			(effects
				(font
					(size 0.7 0.7)
					(thickness 0.15)
				)
				(justify left bottom mirror)
			)
		)
		(pad "1" smd roundrect
			(at -0.7 0 270)
			(size 0.8 1)
			(layers "B.Cu" "B.Mask" "B.Paste")
			(roundrect_rratio 0.2)
			(net 181 "Net-(U4A-VCC3P3_S0)")
			(pintype "passive")
		)
		(pad "2" smd roundrect
			(at 0.7 0 270)
			(size 0.8 1)
			(layers "B.Cu" "B.Mask" "B.Paste")
			(roundrect_rratio 0.2)
			(net 57 "+3V3_TB")
			(pintype "passive")
		)
	)
	(footprint "antmicro-footprints:R_0402_1005Metric"
		(layer "B.Cu")
		(at 153.031866 82.235117 180)
		(descr "Resistor SMD 0402")
		(tags "resistor SMD 0402")
		(property "Reference" "R129"
			(at -20.368136 -9.464883 0)
			(layer "B.SilkS")
			(effects
				(font
					(size 0.7 0.7)
					(thickness 0.15)
				)
				(justify mirror)
			)
		)
		(property "Value" "R_1k_0402"
			(at -1.011843 -1.772047 0)
			(layer "B.Fab")
			(effects
				(font
					(size 0.7 0.7)
					(thickness 0.15)
				)
				(justify left bottom mirror)
			)
		)
		(property "Datasheet" "https://www.bourns.com/docs/product-datasheets/cr.pdf"
			(at 0 0 0)
			(layer "B.Fab")
			(hide yes)
			(effects
				(font
					(size 1.27 1.27)
					(thickness 0.15)
				)
				(justify mirror)
			)
		)
		(property "Description" "SMD Chip Resistor, 1 kohm, ± 1%, 63 mW, 0402 [1005 Metric], Thick Film, General Purpose"
			(at 0 0 0)
			(layer "B.Fab")
			(hide yes)
			(effects
				(font
					(size 1.27 1.27)
					(thickness 0.15)
				)
				(justify mirror)
			)
		)
		(property "MPN" "CR0402-FX-1001GLF"
			(at 0 0 180)
			(unlocked yes)
			(layer "B.Fab")
			(hide yes)
			(effects
				(font
					(size 1 1)
					(thickness 0.15)
				)
				(justify mirror)
			)
		)
		(property "Manufacturer" "Bourns"
			(at 0 0 180)
			(unlocked yes)
			(layer "B.Fab")
			(hide yes)
			(effects
				(font
					(size 1 1)
					(thickness 0.15)
				)
				(justify mirror)
			)
		)
		(property "License" "Apache-2.0"
			(at 0 0 180)
			(unlocked yes)
			(layer "B.Fab")
			(hide yes)
			(effects
				(font
					(size 1 1)
					(thickness 0.15)
				)
				(justify mirror)
			)
		)
		(property "Author" "Antmicro"
			(at 0 0 180)
			(unlocked yes)
			(layer "B.Fab")
			(hide yes)
			(effects
				(font
					(size 1 1)
					(thickness 0.15)
				)
				(justify mirror)
			)
		)
		(property "Val" "1k"
			(at 0 0 180)
			(unlocked yes)
			(layer "B.Fab")
			(hide yes)
			(effects
				(font
					(size 1 1)
					(thickness 0.15)
				)
				(justify mirror)
			)
		)
		(property "Tolerance" "1%"
			(at 0 0 180)
			(unlocked yes)
			(layer "B.Fab")
			(hide yes)
			(effects
				(font
					(size 1 1)
					(thickness 0.15)
				)
				(justify mirror)
			)
		)
		(sheetname "/X710-AT2 RSVD/")
		(sheetfile "x710-at2-rsvd.kicad_sch")
		(attr smd)
		(fp_rect
			(start -0.925 0.47)
			(end 0.925 -0.47)
			(stroke
				(width 0.05)
				(type default)
			)
			(fill no)
			(layer "B.CrtYd")
		)
		(fp_rect
			(start -0.5 0.25)
			(end 0.5 -0.25)
			(stroke
				(width 0.15)
				(type solid)
			)
			(fill no)
			(layer "B.Fab")
		)
		(fp_text user "${REFERENCE}"
			(at -0.95 -3.168 0)
			(layer "B.Fab")
			(effects
				(font
					(size 0.7 0.7)
					(thickness 0.15)
				)
				(justify left bottom mirror)
			)
		)
		(fp_text user "License: Apache-2.0"
			(at -0.95 -5.169 0)
			(layer "B.Fab")
			(effects
				(font
					(size 0.7 0.7)
					(thickness 0.15)
				)
				(justify left bottom mirror)
			)
		)
		(fp_text user "Author: Antmicro"
			(at -0.95 -4.169 0)
			(layer "B.Fab")
			(effects
				(font
					(size 0.7 0.7)
					(thickness 0.15)
				)
				(justify left bottom mirror)
			)
		)
		(pad "1" smd roundrect
			(at -0.48 0 180)
			(size 0.59 0.64)
			(layers "B.Cu" "B.Mask" "B.Paste")
			(roundrect_rratio 0.25)
			(net 129 "/X710-AT2 RSVD/RSVDE19_1P88V")
			(pintype "passive")
		)
		(pad "2" smd roundrect
			(at 0.48 0 180)
			(size 0.59 0.64)
			(layers "B.Cu" "B.Mask" "B.Paste")
			(roundrect_rratio 0.25)
			(net 18 "+1V88")
			(pintype "passive")
		)
	)
	(footprint "antmicro-footprints:C_Pol_EIA-A"
		(layer "B.Cu")
		(at 143.2 99.5 90)
		(property "Reference" "C157"
			(at 0 1.2 90)
			(layer "B.SilkS")
			(effects
				(font
					(size 0.7 0.7)
					(thickness 0.15)
				)
				(justify right top mirror)
			)
		)
		(property "Value" "C_Pol_100u_6V_KEMET-T490-A"
			(at 0 -2 90)
			(layer "B.Fab")
			(effects
				(font
					(size 0.7 0.7)
					(thickness 0.15)
				)
				(justify right top mirror)
			)
		)
		(property "Datasheet" "https://www.kemet.com/en/us/capacitors/product/T490A107M006ATE800.html"
			(at 0 0 90)
			(layer "B.Fab")
			(hide yes)
			(effects
				(font
					(size 1.27 1.27)
					(thickness 0.15)
				)
				(justify mirror)
			)
		)
		(property "Description" "Surface Mount Tantalum Capacitor,  Solid SMD 6V 100uF 1206 20% ESR=800mOhms"
			(at 0 0 90)
			(layer "B.Fab")
			(hide yes)
			(effects
				(font
					(size 1.27 1.27)
					(thickness 0.15)
				)
				(justify mirror)
			)
		)
		(property "Val" "100u"
			(at 0 0 90)
			(unlocked yes)
			(layer "B.Fab")
			(hide yes)
			(effects
				(font
					(size 1 1)
					(thickness 0.15)
				)
				(justify mirror)
			)
		)
		(property "MPN" "T490A107M006ATE800"
			(at 0 0 90)
			(unlocked yes)
			(layer "B.Fab")
			(hide yes)
			(effects
				(font
					(size 1 1)
					(thickness 0.15)
				)
				(justify mirror)
			)
		)
		(property "Manufacturer" "KEMET"
			(at 0 0 90)
			(unlocked yes)
			(layer "B.Fab")
			(hide yes)
			(effects
				(font
					(size 1 1)
					(thickness 0.15)
				)
				(justify mirror)
			)
		)
		(property "License" "Apache-2.0"
			(at 0 0 90)
			(unlocked yes)
			(layer "B.Fab")
			(hide yes)
			(effects
				(font
					(size 1 1)
					(thickness 0.15)
				)
				(justify mirror)
			)
		)
		(property "Author" "Antmicro"
			(at 0 0 90)
			(unlocked yes)
			(layer "B.Fab")
			(hide yes)
			(effects
				(font
					(size 1 1)
					(thickness 0.15)
				)
				(justify mirror)
			)
		)
		(property "Voltage" "6V"
			(at 0 0 90)
			(unlocked yes)
			(layer "B.Fab")
			(hide yes)
			(effects
				(font
					(size 1 1)
					(thickness 0.15)
				)
				(justify mirror)
			)
		)
		(property "Dielectric" "template_dielectric"
			(at 0 0 90)
			(unlocked yes)
			(layer "B.Fab")
			(hide yes)
			(effects
				(font
					(size 1 1)
					(thickness 0.15)
				)
				(justify mirror)
			)
		)
		(sheetname "/X710-AT2 power/")
		(sheetfile "x710-at2-power.kicad_sch")
		(attr smd)
		(fp_line
			(start 1.5 -0.85)
			(end -1.5 -0.85)
			(stroke
				(width 0.12)
				(type solid)
			)
			(layer "B.SilkS")
		)
		(fp_line
			(start 1.5 -0.75)
			(end 1.5 -0.85)
			(stroke
				(width 0.12)
				(type solid)
			)
			(layer "B.SilkS")
		)
		(fp_line
			(start -1.5 -0.75)
			(end -1.5 -0.85)
			(stroke
				(width 0.12)
				(type solid)
			)
			(layer "B.SilkS")
		)
		(fp_line
			(start 1.5 0.75)
			(end 1.5 0.85)
			(stroke
				(width 0.12)
				(type solid)
			)
			(layer "B.SilkS")
		)
		(fp_line
			(start -1.5 0.75)
			(end -1.5 0.85)
			(stroke
				(width 0.12)
				(type solid)
			)
			(layer "B.SilkS")
		)
		(fp_line
			(start -1.5 0.85)
			(end 1.5 0.85)
			(stroke
				(width 0.12)
				(type solid)
			)
			(layer "B.SilkS")
		)
		(fp_line
			(start -2.1 1.1)
			(end -1.8 1.1)
			(stroke
				(width 0.12)
				(type solid)
			)
			(layer "B.SilkS")
		)
		(fp_line
			(start -1.95 1.25)
			(end -1.95 0.95)
			(stroke
				(width 0.12)
				(type solid)
			)
			(layer "B.SilkS")
		)
		(fp_line
			(start 1.7 -1.05)
			(end -1.7 -1.05)
			(stroke
				(width 0.05)
				(type solid)
			)
			(layer "B.CrtYd")
		)
		(fp_line
			(start 1.7 -1.05)
			(end 1.7 -0.85)
			(stroke
				(width 0.05)
				(type solid)
			)
			(layer "B.CrtYd")
		)
		(fp_line
			(start -1.7 -1.05)
			(end -1.7 -0.85)
			(stroke
				(width 0.05)
				(type solid)
			)
			(layer "B.CrtYd")
		)
		(fp_line
			(start 2.05 -0.85)
			(end 1.7 -0.85)
			(stroke
				(width 0.05)
				(type solid)
			)
			(layer "B.CrtYd")
		)
		(fp_line
			(start -1.7 -0.85)
			(end -2.05 -0.85)
			(stroke
				(width 0.05)
				(type solid)
			)
			(layer "B.CrtYd")
		)
		(fp_line
			(start 2.05 0.85)
			(end 2.05 -0.85)
			(stroke
				(width 0.05)
				(type solid)
			)
			(layer "B.CrtYd")
		)
		(fp_line
			(start 2.05 0.85)
			(end 1.7 0.85)
			(stroke
				(width 0.05)
				(type solid)
			)
			(layer "B.CrtYd")
		)
		(fp_line
			(start 1.7 0.85)
			(end 1.7 1.05)
			(stroke
				(width 0.05)
				(type solid)
			)
			(layer "B.CrtYd")
		)
		(fp_line
			(start -1.7 0.85)
			(end -2.05 0.85)
			(stroke
				(width 0.05)
				(type solid)
			)
			(layer "B.CrtYd")
		)
		(fp_line
			(start -1.7 0.85)
			(end -1.7 1.05)
			(stroke
				(width 0.05)
				(type solid)
			)
			(layer "B.CrtYd")
		)
		(fp_line
			(start -2.05 0.85)
			(end -2.05 -0.85)
			(stroke
				(width 0.05)
				(type solid)
			)
			(layer "B.CrtYd")
		)
		(fp_line
			(start 1.7 1.05)
			(end -1.7 1.05)
			(stroke
				(width 0.05)
				(type solid)
			)
			(layer "B.CrtYd")
		)
		(fp_rect
			(start -1.601 0.802)
			(end 1.6 -0.8)
			(stroke
				(width 0.1)
				(type solid)
			)
			(fill no)
			(layer "B.Fab")
		)
		(fp_text user "License: Apache-2.0"
			(at -2.1 -5.198 90)
			(layer "B.Fab")
			(effects
				(font
					(size 0.7 0.7)
					(thickness 0.15)
				)
				(justify right top mirror)
			)
		)
		(fp_text user "${REFERENCE}"
			(at -2.1 -4.198 90)
			(layer "B.Fab")
			(effects
				(font
					(size 0.7 0.7)
					(thickness 0.15)
				)
				(justify right top mirror)
			)
		)
		(fp_text user "Author: Antmicro"
			(at -2.1 -6.198 90)
			(layer "B.Fab")
			(effects
				(font
					(size 0.7 0.7)
					(thickness 0.15)
				)
				(justify right top mirror)
			)
		)
		(pad "1" smd roundrect
			(at -1.2 0 90)
			(size 1.2 1.2)
			(layers "B.Cu" "B.Mask" "B.Paste")
			(roundrect_rratio 0.1)
			(net 6 "DVDD")
			(pintype "passive")
		)
		(pad "2" smd roundrect
			(at 1.2 0 90)
			(size 1.2 1.2)
			(layers "B.Cu" "B.Mask" "B.Paste")
			(roundrect_rratio 0.1)
			(net 23 "GND")
			(pintype "passive")
		)
	)
	(footprint "antmicro-footprints:TP_SMD_0.75mm"
		(layer "B.Cu")
		(at 138.25 57.75 90)
		(property "Reference" "TP38"
			(at 3.15 0.45 270)
			(layer "B.SilkS")
			(effects
				(font
					(size 0.7 0.7)
					(thickness 0.15)
				)
				(justify left bottom mirror)
			)
		)
		(property "Value" "TP_0.75mm_SMD"
			(at 0 -1.2 270)
			(layer "B.Fab")
			(effects
				(font
					(size 0.7 0.7)
					(thickness 0.15)
				)
				(justify left bottom mirror)
			)
		)
		(property "Description" "SMT test point"
			(at 0 0 270)
			(layer "B.Fab")
			(hide yes)
			(effects
				(font
					(size 1.27 1.27)
					(thickness 0.15)
				)
				(justify mirror)
			)
		)
		(property "MPN" ""
			(at 0 0 90)
			(unlocked yes)
			(layer "B.Fab")
			(hide yes)
			(effects
				(font
					(size 1 1)
					(thickness 0.15)
				)
				(justify mirror)
			)
		)
		(property "Manufacturer" ""
			(at 0 0 90)
			(unlocked yes)
			(layer "B.Fab")
			(hide yes)
			(effects
				(font
					(size 1 1)
					(thickness 0.15)
				)
				(justify mirror)
			)
		)
		(property "Author" "Antmicro"
			(at 0 0 90)
			(unlocked yes)
			(layer "B.Fab")
			(hide yes)
			(effects
				(font
					(size 1 1)
					(thickness 0.15)
				)
				(justify mirror)
			)
		)
		(property "License" "Apache-2.0"
			(at 0 0 90)
			(unlocked yes)
			(layer "B.Fab")
			(hide yes)
			(effects
				(font
					(size 1 1)
					(thickness 0.15)
				)
				(justify mirror)
			)
		)
		(sheetname "/Power input/")
		(sheetfile "power_input.kicad_sch")
		(attr exclude_from_pos_files exclude_from_bom)
		(fp_circle
			(center 0 0)
			(end 0.475 0)
			(stroke
				(width 0.05)
				(type default)
			)
			(fill no)
			(layer "B.CrtYd")
		)
		(fp_text user "${REFERENCE}"
			(at -0.4 -2.7 270)
			(layer "B.Fab")
			(effects
				(font
					(size 0.7 0.7)
					(thickness 0.15)
				)
				(justify left bottom mirror)
			)
		)
		(fp_text user "License: Apache-2.0"
			(at -0.4 -5.101 270)
			(layer "B.Fab")
			(effects
				(font
					(size 0.7 0.7)
					(thickness 0.15)
				)
				(justify left bottom mirror)
			)
		)
		(fp_text user "Author: Antmicro"
			(at -0.4 -3.901 270)
			(layer "B.Fab")
			(effects
				(font
					(size 0.7 0.7)
					(thickness 0.15)
				)
				(justify left bottom mirror)
			)
		)
		(pad "1" smd circle
			(at 0 0 90)
			(size 0.75 0.75)
			(layers "B.Cu" "B.Mask")
			(net 53 "+5V_USB")
			(pinfunction "1")
			(pintype "passive")
		)
	)
	(footprint "antmicro-footprints:C_0603_1608Metric_EIA"
		(layer "B.Cu")
		(at 163.25 130.5 180)
		(descr "Capacitor SMD 0603, IPC-7351 Density Level A")
		(tags "Capacitor 0603")
		(property "Reference" "C289"
			(at -4.5 2 0)
			(layer "B.SilkS")
			(effects
				(font
					(size 0.7 0.7)
					(thickness 0.15)
				)
				(justify left bottom mirror)
			)
		)
		(property "Value" "C_22u_16V_0603"
			(at -1.42757 -1.770288 0)
			(layer "B.Fab")
			(effects
				(font
					(size 0.7 0.7)
					(thickness 0.15)
				)
				(justify left bottom mirror)
			)
		)
		(property "Datasheet" "https://product.samsungsem.com/mlcc/CL10A226MO7JZN.do"
			(at 0 0 0)
			(layer "B.Fab")
			(hide yes)
			(effects
				(font
					(size 1.27 1.27)
					(thickness 0.15)
				)
				(justify mirror)
			)
		)
		(property "Description" "SMD Multilayer Ceramic Capacitor"
			(at 0 0 0)
			(layer "B.Fab")
			(hide yes)
			(effects
				(font
					(size 1.27 1.27)
					(thickness 0.15)
				)
				(justify mirror)
			)
		)
		(property "MPN" "CL10A226MO7JZNC"
			(at 0 0 180)
			(unlocked yes)
			(layer "B.Fab")
			(hide yes)
			(effects
				(font
					(size 1 1)
					(thickness 0.15)
				)
				(justify mirror)
			)
		)
		(property "Manufacturer" "Samsung Electro-Mechanics"
			(at 0 0 180)
			(unlocked yes)
			(layer "B.Fab")
			(hide yes)
			(effects
				(font
					(size 1 1)
					(thickness 0.15)
				)
				(justify mirror)
			)
		)
		(property "License" "Apache-2.0"
			(at 0 0 180)
			(unlocked yes)
			(layer "B.Fab")
			(hide yes)
			(effects
				(font
					(size 1 1)
					(thickness 0.15)
				)
				(justify mirror)
			)
		)
		(property "Author" "Antmicro"
			(at 0 0 180)
			(unlocked yes)
			(layer "B.Fab")
			(hide yes)
			(effects
				(font
					(size 1 1)
					(thickness 0.15)
				)
				(justify mirror)
			)
		)
		(property "Val" "22u"
			(at 0 0 180)
			(unlocked yes)
			(layer "B.Fab")
			(hide yes)
			(effects
				(font
					(size 1 1)
					(thickness 0.15)
				)
				(justify mirror)
			)
		)
		(property "Voltage" "16V"
			(at 0 0 180)
			(unlocked yes)
			(layer "B.Fab")
			(hide yes)
			(effects
				(font
					(size 1 1)
					(thickness 0.15)
				)
				(justify mirror)
			)
		)
		(property "Dielectric" ""
			(at 0 0 180)
			(unlocked yes)
			(layer "B.Fab")
			(hide yes)
			(effects
				(font
					(size 1 1)
					(thickness 0.15)
				)
				(justify mirror)
			)
		)
		(sheetname "/2xRJ45/")
		(sheetfile "2xrj45.kicad_sch")
		(attr smd)
		(fp_line
			(start -0.15 0.55)
			(end 0.15 0.55)
			(stroke
				(width 0.15)
				(type solid)
			)
			(layer "B.SilkS")
		)
		(fp_line
			(start -0.15 -0.55)
			(end 0.15 -0.55)
			(stroke
				(width 0.15)
				(type solid)
			)
			(layer "B.SilkS")
		)
		(fp_rect
			(start -1.25 0.65)
			(end 1.25 -0.65)
			(stroke
				(width 0.05)
				(type solid)
			)
			(fill no)
			(layer "B.CrtYd")
		)
		(fp_rect
			(start -0.8 0.45)
			(end 0.8 -0.45)
			(stroke
				(width 0.15)
				(type solid)
			)
			(fill no)
			(layer "B.Fab")
		)
		(fp_text user "${REFERENCE}"
			(at -1.682 -3.895 0)
			(layer "B.Fab")
			(effects
				(font
					(size 0.7 0.7)
					(thickness 0.15)
				)
				(justify left bottom mirror)
			)
		)
		(fp_text user "Author: Antmicro"
			(at -1.682 -4.894 0)
			(layer "B.Fab")
			(effects
				(font
					(size 0.7 0.7)
					(thickness 0.15)
				)
				(justify left bottom mirror)
			)
		)
		(fp_text user "License: Apache-2.0"
			(at -1.682 -5.895 0)
			(layer "B.Fab")
			(effects
				(font
					(size 0.7 0.7)
					(thickness 0.15)
				)
				(justify left bottom mirror)
			)
		)
		(pad "1" smd roundrect
			(at -0.7 0 180)
			(size 0.8 1.1)
			(layers "B.Cu" "B.Mask" "B.Paste")
			(roundrect_rratio 0.2)
			(net 23 "GND")
			(pintype "passive")
		)
		(pad "2" smd roundrect
			(at 0.7 0 180)
			(size 0.8 1.1)
			(layers "B.Cu" "B.Mask" "B.Paste")
			(roundrect_rratio 0.2)
			(net 18 "+1V88")
			(pintype "passive")
		)
	)
	(footprint "antmicro-footprints:TP_SMD_0.75mm"
		(layer "B.Cu")
		(at 158.231866 62.935117 180)
		(property "Reference" "TP26"
			(at -0.368134 3.135117 90)
			(layer "B.SilkS")
			(effects
				(font
					(size 0.7 0.7)
					(thickness 0.15)
				)
				(justify left bottom mirror)
			)
		)
		(property "Value" "TP_0.75mm_SMD"
			(at 0 -1.2 0)
			(layer "B.Fab")
			(effects
				(font
					(size 0.7 0.7)
					(thickness 0.15)
				)
				(justify left bottom mirror)
			)
		)
		(property "Description" "SMT test point"
			(at 0 0 0)
			(layer "B.Fab")
			(hide yes)
			(effects
				(font
					(size 1.27 1.27)
					(thickness 0.15)
				)
				(justify mirror)
			)
		)
		(property "MPN" ""
			(at 0 0 180)
			(unlocked yes)
			(layer "B.Fab")
			(hide yes)
			(effects
				(font
					(size 1 1)
					(thickness 0.15)
				)
				(justify mirror)
			)
		)
		(property "Manufacturer" ""
			(at 0 0 180)
			(unlocked yes)
			(layer "B.Fab")
			(hide yes)
			(effects
				(font
					(size 1 1)
					(thickness 0.15)
				)
				(justify mirror)
			)
		)
		(property "Author" "Antmicro"
			(at 0 0 180)
			(unlocked yes)
			(layer "B.Fab")
			(hide yes)
			(effects
				(font
					(size 1 1)
					(thickness 0.15)
				)
				(justify mirror)
			)
		)
		(property "License" "Apache-2.0"
			(at 0 0 180)
			(unlocked yes)
			(layer "B.Fab")
			(hide yes)
			(effects
				(font
					(size 1 1)
					(thickness 0.15)
				)
				(justify mirror)
			)
		)
		(sheetname "/X710-AT2 Misc/")
		(sheetfile "x710-at2-mics.kicad_sch")
		(attr exclude_from_pos_files exclude_from_bom)
		(fp_circle
			(center 0 0)
			(end 0.475 0)
			(stroke
				(width 0.05)
				(type default)
			)
			(fill no)
			(layer "B.CrtYd")
		)
		(fp_text user "${REFERENCE}"
			(at -0.4 -2.7 0)
			(layer "B.Fab")
			(effects
				(font
					(size 0.7 0.7)
					(thickness 0.15)
				)
				(justify left bottom mirror)
			)
		)
		(fp_text user "License: Apache-2.0"
			(at -0.4 -5.101 0)
			(layer "B.Fab")
			(effects
				(font
					(size 0.7 0.7)
					(thickness 0.15)
				)
				(justify left bottom mirror)
			)
		)
		(fp_text user "Author: Antmicro"
			(at -0.4 -3.901 0)
			(layer "B.Fab")
			(effects
				(font
					(size 0.7 0.7)
					(thickness 0.15)
				)
				(justify left bottom mirror)
			)
		)
		(pad "1" smd circle
			(at 0 0 180)
			(size 0.75 0.75)
			(layers "B.Cu" "B.Mask")
			(net 140 "/X710-AT2 Misc/NCSI.TXD_0")
			(pinfunction "1")
			(pintype "passive")
		)
	)
	(footprint "antmicro-footprints:Fiducial_1mm_Mask2mm"
		(layer "B.Cu")
		(at 179 129 180)
		(descr "Circular Fiducial, 1mm bare copper, 3mm soldermask opening")
		(tags "fiducial")
		(property "Reference" "FD6"
			(at -3.5 -0.5 0)
			(layer "B.SilkS")
			(effects
				(font
					(size 0.7 0.7)
					(thickness 0.15)
				)
				(justify left bottom mirror)
			)
		)
		(property "Value" "Fiducial_1mm_Mask2mm"
			(at 0 -2.2 0)
			(layer "B.Fab")
			(effects
				(font
					(size 0.7 0.7)
					(thickness 0.15)
				)
				(justify left bottom mirror)
			)
		)
		(property "Description" "Fiducial mask"
			(at 0 0 0)
			(layer "B.Fab")
			(hide yes)
			(effects
				(font
					(size 1.27 1.27)
					(thickness 0.15)
				)
				(justify mirror)
			)
		)
		(property "Author" "Antmicro"
			(at 0 0 180)
			(unlocked yes)
			(layer "B.Fab")
			(hide yes)
			(effects
				(font
					(size 1 1)
					(thickness 0.15)
				)
				(justify mirror)
			)
		)
		(property "License" "Apache-2.0"
			(at 0 0 180)
			(unlocked yes)
			(layer "B.Fab")
			(hide yes)
			(effects
				(font
					(size 1 1)
					(thickness 0.15)
				)
				(justify mirror)
			)
		)
		(sheetname "/")
		(sheetfile "thunderbolt-to-10gbe-adapter.kicad_sch")
		(attr exclude_from_pos_files exclude_from_bom)
		(fp_circle
			(center 0 0)
			(end 1.24 0)
			(stroke
				(width 0.05)
				(type solid)
			)
			(fill no)
			(layer "B.CrtYd")
		)
		(fp_circle
			(center 0 0)
			(end 0.999 0)
			(stroke
				(width 0.15)
				(type solid)
			)
			(fill no)
			(layer "B.Fab")
		)
		(fp_text user "License: Apache-2.0"
			(at -1.25 -7.003 0)
			(layer "B.Fab")
			(effects
				(font
					(size 0.7 0.7)
					(thickness 0.15)
				)
				(justify left bottom mirror)
			)
		)
		(fp_text user "${REFERENCE}"
			(at -1.25 -4.603 0)
			(layer "B.Fab")
			(effects
				(font
					(size 0.7 0.7)
					(thickness 0.15)
				)
				(justify left bottom mirror)
			)
		)
		(fp_text user "Author: Antmicro"
			(at -1.25 -5.803 0)
			(layer "B.Fab")
			(effects
				(font
					(size 0.7 0.7)
					(thickness 0.15)
				)
				(justify left bottom mirror)
			)
		)
		(pad "" smd circle
			(at 0 0 180)
			(size 1 1)
			(layers "B.Cu" "B.Mask")
			(solder_mask_margin 0.5)
			(clearance 0.5)
		)
	)
	(footprint "antmicro-footprints:TP_SMD_0.75mm"
		(layer "B.Cu")
		(at 183.75 80.25 90)
		(property "Reference" "TP16"
			(at -9.75 0.75 270)
			(layer "B.SilkS")
			(effects
				(font
					(size 0.7 0.7)
					(thickness 0.15)
				)
				(justify left bottom mirror)
			)
		)
		(property "Value" "TP_0.75mm_SMD"
			(at 0 -1.2 270)
			(layer "B.Fab")
			(effects
				(font
					(size 0.7 0.7)
					(thickness 0.15)
				)
				(justify left bottom mirror)
			)
		)
		(property "Description" "SMT test point"
			(at 0 0 270)
			(layer "B.Fab")
			(hide yes)
			(effects
				(font
					(size 1.27 1.27)
					(thickness 0.15)
				)
				(justify mirror)
			)
		)
		(property "MPN" ""
			(at 0 0 90)
			(unlocked yes)
			(layer "B.Fab")
			(hide yes)
			(effects
				(font
					(size 1 1)
					(thickness 0.15)
				)
				(justify mirror)
			)
		)
		(property "Manufacturer" ""
			(at 0 0 90)
			(unlocked yes)
			(layer "B.Fab")
			(hide yes)
			(effects
				(font
					(size 1 1)
					(thickness 0.15)
				)
				(justify mirror)
			)
		)
		(property "Author" "Antmicro"
			(at 0 0 90)
			(unlocked yes)
			(layer "B.Fab")
			(hide yes)
			(effects
				(font
					(size 1 1)
					(thickness 0.15)
				)
				(justify mirror)
			)
		)
		(property "License" "Apache-2.0"
			(at 0 0 90)
			(unlocked yes)
			(layer "B.Fab")
			(hide yes)
			(effects
				(font
					(size 1 1)
					(thickness 0.15)
				)
				(justify mirror)
			)
		)
		(sheetname "/X710 DCDC converters/")
		(sheetfile "DCDC_converters_X710.kicad_sch")
		(attr exclude_from_pos_files exclude_from_bom)
		(fp_circle
			(center 0 0)
			(end 0.475 0)
			(stroke
				(width 0.05)
				(type default)
			)
			(fill no)
			(layer "B.CrtYd")
		)
		(fp_text user "License: Apache-2.0"
			(at -0.4 -5.101 270)
			(layer "B.Fab")
			(effects
				(font
					(size 0.7 0.7)
					(thickness 0.15)
				)
				(justify left bottom mirror)
			)
		)
		(fp_text user "Author: Antmicro"
			(at -0.4 -3.901 270)
			(layer "B.Fab")
			(effects
				(font
					(size 0.7 0.7)
					(thickness 0.15)
				)
				(justify left bottom mirror)
			)
		)
		(fp_text user "${REFERENCE}"
			(at -0.4 -2.7 270)
			(layer "B.Fab")
			(effects
				(font
					(size 0.7 0.7)
					(thickness 0.15)
				)
				(justify left bottom mirror)
			)
		)
		(pad "1" smd circle
			(at 0 0 90)
			(size 0.75 0.75)
			(layers "B.Cu" "B.Mask")
			(net 9 "VCCD")
			(pinfunction "1")
			(pintype "passive")
		)
	)
	(footprint "antmicro-footprints:C_0402_1005Metric"
		(layer "B.Cu")
		(at 158.931866 89.755117)
		(descr "Capacitor SMD 0402")
		(tags "capacitor SMD 0402")
		(property "Reference" "C193"
			(at 20.068133 10.984883 180)
			(layer "B.SilkS")
			(effects
				(font
					(size 0.7 0.7)
					(thickness 0.15)
				)
				(justify mirror)
			)
		)
		(property "Value" "C_1u_25V_0402"
			(at -1.022927 -2.155213 180)
			(layer "B.Fab")
			(effects
				(font
					(size 0.7 0.7)
					(thickness 0.15)
				)
				(justify left bottom mirror)
			)
		)
		(property "Datasheet" "https://www.murata.com/products/productdetail?partno=GRM155R61E105KE11%23"
			(at 0 0 180)
			(layer "B.Fab")
			(hide yes)
			(effects
				(font
					(size 1.27 1.27)
					(thickness 0.15)
				)
				(justify mirror)
			)
		)
		(property "Description" "SMD Multilayer Ceramic Capacitor, 1 µF, 25 V, 0402 [1005 Metric], ± 10%, X5R, GRM Series"
			(at 0 0 180)
			(layer "B.Fab")
			(hide yes)
			(effects
				(font
					(size 1.27 1.27)
					(thickness 0.15)
				)
				(justify mirror)
			)
		)
		(property "MPN" "GRM155R61E105KE11J"
			(at 0 0 0)
			(unlocked yes)
			(layer "B.Fab")
			(hide yes)
			(effects
				(font
					(size 1 1)
					(thickness 0.15)
				)
				(justify mirror)
			)
		)
		(property "Manufacturer" "Murata"
			(at 0 0 0)
			(unlocked yes)
			(layer "B.Fab")
			(hide yes)
			(effects
				(font
					(size 1 1)
					(thickness 0.15)
				)
				(justify mirror)
			)
		)
		(property "License" "Apache-2.0"
			(at 0 0 0)
			(unlocked yes)
			(layer "B.Fab")
			(hide yes)
			(effects
				(font
					(size 1 1)
					(thickness 0.15)
				)
				(justify mirror)
			)
		)
		(property "Author" "Antmicro"
			(at 0 0 0)
			(unlocked yes)
			(layer "B.Fab")
			(hide yes)
			(effects
				(font
					(size 1 1)
					(thickness 0.15)
				)
				(justify mirror)
			)
		)
		(property "Val" "1u"
			(at 0 0 0)
			(unlocked yes)
			(layer "B.Fab")
			(hide yes)
			(effects
				(font
					(size 1 1)
					(thickness 0.15)
				)
				(justify mirror)
			)
		)
		(property "Voltage" "25V"
			(at 0 0 0)
			(unlocked yes)
			(layer "B.Fab")
			(hide yes)
			(effects
				(font
					(size 1 1)
					(thickness 0.15)
				)
				(justify mirror)
			)
		)
		(property "Dielectric" "X5R"
			(at 0 0 0)
			(unlocked yes)
			(layer "B.Fab")
			(hide yes)
			(effects
				(font
					(size 1 1)
					(thickness 0.15)
				)
				(justify mirror)
			)
		)
		(sheetname "/X710-AT2 power/")
		(sheetfile "x710-at2-power.kicad_sch")
		(attr smd)
		(fp_rect
			(start -0.925 0.47)
			(end 0.925 -0.47)
			(stroke
				(width 0.05)
				(type default)
			)
			(fill no)
			(layer "B.CrtYd")
		)
		(fp_line
			(start -0.494 -0.248)
			(end -0.494 0.25)
			(stroke
				(width 0.15)
				(type solid)
			)
			(layer "B.Fab")
		)
		(fp_line
			(start -0.494 0.25)
			(end 0.504 0.25)
			(stroke
				(width 0.15)
				(type solid)
			)
			(layer "B.Fab")
		)
		(fp_line
			(start 0.504 -0.248)
			(end -0.494 -0.248)
			(stroke
				(width 0.15)
				(type solid)
			)
			(layer "B.Fab")
		)
		(fp_line
			(start 0.504 0.25)
			(end 0.504 -0.248)
			(stroke
				(width 0.15)
				(type solid)
			)
			(layer "B.Fab")
		)
		(fp_text user "Author: Antmicro"
			(at -0.939 -3.399 180)
			(layer "B.Fab")
			(effects
				(font
					(size 0.7 0.7)
					(thickness 0.15)
				)
				(justify left bottom mirror)
			)
		)
		(fp_text user "License: Apache-2.0"
			(at -0.939 -5.799 180)
			(layer "B.Fab")
			(effects
				(font
					(size 0.7 0.7)
					(thickness 0.15)
				)
				(justify left bottom mirror)
			)
		)
		(fp_text user "${REFERENCE}"
			(at -0.939 -4.599 180)
			(layer "B.Fab")
			(effects
				(font
					(size 0.7 0.7)
					(thickness 0.15)
				)
				(justify left bottom mirror)
			)
		)
		(pad "1" smd roundrect
			(at -0.48 0)
			(size 0.59 0.64)
			(layers "B.Cu" "B.Mask" "B.Paste")
			(roundrect_rratio 0.25)
			(net 23 "GND")
			(pintype "passive")
		)
		(pad "2" smd roundrect
			(at 0.48 0)
			(size 0.59 0.64)
			(layers "B.Cu" "B.Mask" "B.Paste")
			(roundrect_rratio 0.25)
			(net 5 "P0_AVDDL")
			(pintype "passive")
		)
	)
	(footprint "antmicro-footprints:C_0402_1005Metric"
		(layer "B.Cu")
		(at 123.5 145.1 -90)
		(descr "Capacitor SMD 0402")
		(tags "capacitor SMD 0402")
		(property "Reference" "C1"
			(at -2.35 -0.3 90)
			(layer "B.SilkS")
			(effects
				(font
					(size 0.7 0.7)
					(thickness 0.15)
				)
				(justify left bottom mirror)
			)
		)
		(property "Value" "C_100n_0402"
			(at -1.022927 -2.155213 90)
			(layer "B.Fab")
			(effects
				(font
					(size 0.7 0.7)
					(thickness 0.15)
				)
				(justify left bottom mirror)
			)
		)
		(property "Datasheet" "https://www.murata.com/products/productdetail?partno=GRM155R61H104KE14%23"
			(at 0 0 90)
			(layer "B.Fab")
			(hide yes)
			(effects
				(font
					(size 1.27 1.27)
					(thickness 0.15)
				)
				(justify mirror)
			)
		)
		(property "Description" "SMD Multilayer Ceramic Capacitor, 0.1 µF, 50 V, 0402 [1005 Metric], ± 10%, X5R, GRM Series"
			(at 0 0 90)
			(layer "B.Fab")
			(hide yes)
			(effects
				(font
					(size 1.27 1.27)
					(thickness 0.15)
				)
				(justify mirror)
			)
		)
		(property "MPN" "GRM155R61H104KE14D"
			(at 0 0 270)
			(unlocked yes)
			(layer "B.Fab")
			(hide yes)
			(effects
				(font
					(size 1 1)
					(thickness 0.15)
				)
				(justify mirror)
			)
		)
		(property "Manufacturer" "Murata"
			(at 0 0 270)
			(unlocked yes)
			(layer "B.Fab")
			(hide yes)
			(effects
				(font
					(size 1 1)
					(thickness 0.15)
				)
				(justify mirror)
			)
		)
		(property "License" "Apache-2.0"
			(at 0 0 270)
			(unlocked yes)
			(layer "B.Fab")
			(hide yes)
			(effects
				(font
					(size 1 1)
					(thickness 0.15)
				)
				(justify mirror)
			)
		)
		(property "Author" "Antmicro"
			(at 0 0 270)
			(unlocked yes)
			(layer "B.Fab")
			(hide yes)
			(effects
				(font
					(size 1 1)
					(thickness 0.15)
				)
				(justify mirror)
			)
		)
		(property "Val" "100n"
			(at 0 0 270)
			(unlocked yes)
			(layer "B.Fab")
			(hide yes)
			(effects
				(font
					(size 1 1)
					(thickness 0.15)
				)
				(justify mirror)
			)
		)
		(property "Voltage" "50V"
			(at 0 0 270)
			(unlocked yes)
			(layer "B.Fab")
			(hide yes)
			(effects
				(font
					(size 1 1)
					(thickness 0.15)
				)
				(justify mirror)
			)
		)
		(property "Dielectric" "X5R"
			(at 0 0 270)
			(unlocked yes)
			(layer "B.Fab")
			(hide yes)
			(effects
				(font
					(size 1 1)
					(thickness 0.15)
				)
				(justify mirror)
			)
		)
		(sheetname "/USB-C connector/")
		(sheetfile "USB-C_connector.kicad_sch")
		(attr smd)
		(fp_rect
			(start -0.925 0.47)
			(end 0.925 -0.47)
			(stroke
				(width 0.05)
				(type default)
			)
			(fill no)
			(layer "B.CrtYd")
		)
		(fp_line
			(start -0.494 0.25)
			(end 0.504 0.25)
			(stroke
				(width 0.15)
				(type solid)
			)
			(layer "B.Fab")
		)
		(fp_line
			(start 0.504 0.25)
			(end 0.504 -0.248)
			(stroke
				(width 0.15)
				(type solid)
			)
			(layer "B.Fab")
		)
		(fp_line
			(start -0.494 -0.248)
			(end -0.494 0.25)
			(stroke
				(width 0.15)
				(type solid)
			)
			(layer "B.Fab")
		)
		(fp_line
			(start 0.504 -0.248)
			(end -0.494 -0.248)
			(stroke
				(width 0.15)
				(type solid)
			)
			(layer "B.Fab")
		)
		(fp_text user "${REFERENCE}"
			(at -0.939 -4.599 90)
			(layer "B.Fab")
			(effects
				(font
					(size 0.7 0.7)
					(thickness 0.15)
				)
				(justify left bottom mirror)
			)
		)
		(fp_text user "Author: Antmicro"
			(at -0.939 -3.399 90)
			(layer "B.Fab")
			(effects
				(font
					(size 0.7 0.7)
					(thickness 0.15)
				)
				(justify left bottom mirror)
			)
		)
		(fp_text user "License: Apache-2.0"
			(at -0.939 -5.799 90)
			(layer "B.Fab")
			(effects
				(font
					(size 0.7 0.7)
					(thickness 0.15)
				)
				(justify left bottom mirror)
			)
		)
		(pad "1" smd roundrect
			(at -0.48 0 270)
			(size 0.59 0.64)
			(layers "B.Cu" "B.Mask" "B.Paste")
			(roundrect_rratio 0.25)
			(net 23 "GND")
			(pintype "passive")
		)
		(pad "2" smd roundrect
			(at 0.48 0 270)
			(size 0.59 0.64)
			(layers "B.Cu" "B.Mask" "B.Paste")
			(roundrect_rratio 0.25)
			(net 215 "/USB-C connector/VBUS")
			(pintype "passive")
		)
	)
	(footprint "antmicro-footprints:C_0402_1005Metric"
		(layer "B.Cu")
		(at 133.739999 117 180)
		(descr "Capacitor SMD 0402")
		(tags "capacitor SMD 0402")
		(property "Reference" "C38"
			(at -19.525001 7.450001 0)
			(layer "B.SilkS")
			(effects
				(font
					(size 0.7 0.7)
					(thickness 0.15)
				)
				(justify mirror)
			)
		)
		(property "Value" "C_100n_0402"
			(at -1.022927 -2.155213 0)
			(layer "B.Fab")
			(effects
				(font
					(size 0.7 0.7)
					(thickness 0.15)
				)
				(justify left bottom mirror)
			)
		)
		(property "Datasheet" "https://www.murata.com/products/productdetail?partno=GRM155R61H104KE14%23"
			(at 0 0 0)
			(layer "B.Fab")
			(hide yes)
			(effects
				(font
					(size 1.27 1.27)
					(thickness 0.15)
				)
				(justify mirror)
			)
		)
		(property "Description" "SMD Multilayer Ceramic Capacitor, 0.1 µF, 50 V, 0402 [1005 Metric], ± 10%, X5R, GRM Series"
			(at 0 0 0)
			(layer "B.Fab")
			(hide yes)
			(effects
				(font
					(size 1.27 1.27)
					(thickness 0.15)
				)
				(justify mirror)
			)
		)
		(property "MPN" "GRM155R61H104KE14D"
			(at 0 0 180)
			(unlocked yes)
			(layer "B.Fab")
			(hide yes)
			(effects
				(font
					(size 1 1)
					(thickness 0.15)
				)
				(justify mirror)
			)
		)
		(property "Manufacturer" "Murata"
			(at 0 0 180)
			(unlocked yes)
			(layer "B.Fab")
			(hide yes)
			(effects
				(font
					(size 1 1)
					(thickness 0.15)
				)
				(justify mirror)
			)
		)
		(property "License" "Apache-2.0"
			(at 0 0 180)
			(unlocked yes)
			(layer "B.Fab")
			(hide yes)
			(effects
				(font
					(size 1 1)
					(thickness 0.15)
				)
				(justify mirror)
			)
		)
		(property "Val" "100n"
			(at 0 0 180)
			(unlocked yes)
			(layer "B.Fab")
			(hide yes)
			(effects
				(font
					(size 1 1)
					(thickness 0.15)
				)
				(justify mirror)
			)
		)
		(property "Voltage" "50V"
			(at 0 0 180)
			(unlocked yes)
			(layer "B.Fab")
			(hide yes)
			(effects
				(font
					(size 1 1)
					(thickness 0.15)
				)
				(justify mirror)
			)
		)
		(property "Dielectric" "X5R"
			(at 0 0 180)
			(unlocked yes)
			(layer "B.Fab")
			(hide yes)
			(effects
				(font
					(size 1 1)
					(thickness 0.15)
				)
				(justify mirror)
			)
		)
		(property "Author" "Antmicro"
			(at 0 0 180)
			(unlocked yes)
			(layer "B.Fab")
			(hide yes)
			(effects
				(font
					(size 1 1)
					(thickness 0.15)
				)
				(justify mirror)
			)
		)
		(sheetname "/TB Controller/")
		(sheetfile "tb.kicad_sch")
		(attr smd)
		(fp_rect
			(start -0.925 0.47)
			(end 0.925 -0.47)
			(stroke
				(width 0.05)
				(type default)
			)
			(fill no)
			(layer "B.CrtYd")
		)
		(fp_line
			(start 0.504 0.25)
			(end 0.504 -0.248)
			(stroke
				(width 0.15)
				(type solid)
			)
			(layer "B.Fab")
		)
		(fp_line
			(start 0.504 -0.248)
			(end -0.494 -0.248)
			(stroke
				(width 0.15)
				(type solid)
			)
			(layer "B.Fab")
		)
		(fp_line
			(start -0.494 0.25)
			(end 0.504 0.25)
			(stroke
				(width 0.15)
				(type solid)
			)
			(layer "B.Fab")
		)
		(fp_line
			(start -0.494 -0.248)
			(end -0.494 0.25)
			(stroke
				(width 0.15)
				(type solid)
			)
			(layer "B.Fab")
		)
		(fp_text user "License: Apache-2.0"
			(at -0.939 -5.799 0)
			(layer "B.Fab")
			(effects
				(font
					(size 0.7 0.7)
					(thickness 0.15)
				)
				(justify left bottom mirror)
			)
		)
		(fp_text user "Author: Antmicro"
			(at -0.939 -3.399 0)
			(layer "B.Fab")
			(effects
				(font
					(size 0.7 0.7)
					(thickness 0.15)
				)
				(justify left bottom mirror)
			)
		)
		(fp_text user "${REFERENCE}"
			(at -0.939 -4.599 0)
			(layer "B.Fab")
			(effects
				(font
					(size 0.7 0.7)
					(thickness 0.15)
				)
				(justify left bottom mirror)
			)
		)
		(pad "1" smd roundrect
			(at -0.48 0 180)
			(size 0.59 0.64)
			(layers "B.Cu" "B.Mask" "B.Paste")
			(roundrect_rratio 0.25)
			(net 79 "/PD and TB DC-DC/AUX.-")
			(pintype "passive")
		)
		(pad "2" smd roundrect
			(at 0.48 0 180)
			(size 0.59 0.64)
			(layers "B.Cu" "B.Mask" "B.Paste")
			(roundrect_rratio 0.25)
			(net 240 "/TB Controller/PA_AUX_N")
			(pintype "passive")
		)
	)
	(footprint "antmicro-footprints:R_0402_1005Metric"
		(layer "B.Cu")
		(at 147.531866 70.535117)
		(descr "Resistor SMD 0402")
		(tags "resistor SMD 0402")
		(property "Reference" "R159"
			(at 19.068134 9.464883 180)
			(layer "B.SilkS")
			(effects
				(font
					(size 0.7 0.7)
					(thickness 0.15)
				)
				(justify mirror)
			)
		)
		(property "Value" "R_10k_0402"
			(at -1.011843 -1.772047 180)
			(layer "B.Fab")
			(effects
				(font
					(size 0.7 0.7)
					(thickness 0.15)
				)
				(justify left bottom mirror)
			)
		)
		(property "Datasheet" "https://www.bourns.com/docs/product-datasheets/cr.pdf"
			(at 0 0 180)
			(layer "B.Fab")
			(hide yes)
			(effects
				(font
					(size 1.27 1.27)
					(thickness 0.15)
				)
				(justify mirror)
			)
		)
		(property "Description" "SMD Chip Resistor, 10 kohm, ± 1%, 62.5 mW, 0402 [1005 Metric], Thick Film, General Purpose"
			(at 0 0 180)
			(layer "B.Fab")
			(hide yes)
			(effects
				(font
					(size 1.27 1.27)
					(thickness 0.15)
				)
				(justify mirror)
			)
		)
		(property "MPN" "CR0402-FX-1002GLF"
			(at 0 0 0)
			(unlocked yes)
			(layer "B.Fab")
			(hide yes)
			(effects
				(font
					(size 1 1)
					(thickness 0.15)
				)
				(justify mirror)
			)
		)
		(property "Manufacturer" "Bourns"
			(at 0 0 0)
			(unlocked yes)
			(layer "B.Fab")
			(hide yes)
			(effects
				(font
					(size 1 1)
					(thickness 0.15)
				)
				(justify mirror)
			)
		)
		(property "License" "Apache-2.0"
			(at 0 0 0)
			(unlocked yes)
			(layer "B.Fab")
			(hide yes)
			(effects
				(font
					(size 1 1)
					(thickness 0.15)
				)
				(justify mirror)
			)
		)
		(property "Author" "Antmicro"
			(at 0 0 0)
			(unlocked yes)
			(layer "B.Fab")
			(hide yes)
			(effects
				(font
					(size 1 1)
					(thickness 0.15)
				)
				(justify mirror)
			)
		)
		(property "Val" "10k"
			(at 0 0 0)
			(unlocked yes)
			(layer "B.Fab")
			(hide yes)
			(effects
				(font
					(size 1 1)
					(thickness 0.15)
				)
				(justify mirror)
			)
		)
		(property "Tolerance" "1%"
			(at 0 0 0)
			(unlocked yes)
			(layer "B.Fab")
			(hide yes)
			(effects
				(font
					(size 1 1)
					(thickness 0.15)
				)
				(justify mirror)
			)
		)
		(sheetname "/X710-AT2 Misc/")
		(sheetfile "x710-at2-mics.kicad_sch")
		(attr smd)
		(fp_rect
			(start -0.925 0.47)
			(end 0.925 -0.47)
			(stroke
				(width 0.05)
				(type default)
			)
			(fill no)
			(layer "B.CrtYd")
		)
		(fp_rect
			(start -0.5 0.25)
			(end 0.5 -0.25)
			(stroke
				(width 0.15)
				(type solid)
			)
			(fill no)
			(layer "B.Fab")
		)
		(fp_text user "License: Apache-2.0"
			(at -0.95 -5.169 180)
			(layer "B.Fab")
			(effects
				(font
					(size 0.7 0.7)
					(thickness 0.15)
				)
				(justify left bottom mirror)
			)
		)
		(fp_text user "${REFERENCE}"
			(at -0.95 -3.168 180)
			(layer "B.Fab")
			(effects
				(font
					(size 0.7 0.7)
					(thickness 0.15)
				)
				(justify left bottom mirror)
			)
		)
		(fp_text user "Author: Antmicro"
			(at -0.95 -4.169 180)
			(layer "B.Fab")
			(effects
				(font
					(size 0.7 0.7)
					(thickness 0.15)
				)
				(justify left bottom mirror)
			)
		)
		(pad "1" smd roundrect
			(at -0.48 0)
			(size 0.59 0.64)
			(layers "B.Cu" "B.Mask" "B.Paste")
			(roundrect_rratio 0.25)
			(net 126 "/X710-AT2 Misc/~{PCI_DIS}")
			(pintype "passive")
		)
		(pad "2" smd roundrect
			(at 0.48 0)
			(size 0.59 0.64)
			(layers "B.Cu" "B.Mask" "B.Paste")
			(roundrect_rratio 0.25)
			(net 7 "+3V3")
			(pintype "passive")
		)
	)
	(footprint "antmicro-footprints:TP_SMD_0.75mm"
		(layer "B.Cu")
		(at 183.75 84.75 90)
		(property "Reference" "TP19"
			(at -13.25 0.75 270)
			(layer "B.SilkS")
			(effects
				(font
					(size 0.7 0.7)
					(thickness 0.15)
				)
				(justify left bottom mirror)
			)
		)
		(property "Value" "TP_0.75mm_SMD"
			(at 0 -1.2 270)
			(layer "B.Fab")
			(effects
				(font
					(size 0.7 0.7)
					(thickness 0.15)
				)
				(justify left bottom mirror)
			)
		)
		(property "Description" "SMT test point"
			(at 0 0 270)
			(layer "B.Fab")
			(hide yes)
			(effects
				(font
					(size 1.27 1.27)
					(thickness 0.15)
				)
				(justify mirror)
			)
		)
		(property "MPN" ""
			(at 0 0 90)
			(unlocked yes)
			(layer "B.Fab")
			(hide yes)
			(effects
				(font
					(size 1 1)
					(thickness 0.15)
				)
				(justify mirror)
			)
		)
		(property "Manufacturer" ""
			(at 0 0 90)
			(unlocked yes)
			(layer "B.Fab")
			(hide yes)
			(effects
				(font
					(size 1 1)
					(thickness 0.15)
				)
				(justify mirror)
			)
		)
		(property "Author" "Antmicro"
			(at 0 0 90)
			(unlocked yes)
			(layer "B.Fab")
			(hide yes)
			(effects
				(font
					(size 1 1)
					(thickness 0.15)
				)
				(justify mirror)
			)
		)
		(property "License" "Apache-2.0"
			(at 0 0 90)
			(unlocked yes)
			(layer "B.Fab")
			(hide yes)
			(effects
				(font
					(size 1 1)
					(thickness 0.15)
				)
				(justify mirror)
			)
		)
		(sheetname "/X710 DCDC converters/")
		(sheetfile "DCDC_converters_X710.kicad_sch")
		(attr exclude_from_pos_files exclude_from_bom)
		(fp_circle
			(center 0 0)
			(end 0.475 0)
			(stroke
				(width 0.05)
				(type default)
			)
			(fill no)
			(layer "B.CrtYd")
		)
		(fp_text user "${REFERENCE}"
			(at -0.4 -2.7 270)
			(layer "B.Fab")
			(effects
				(font
					(size 0.7 0.7)
					(thickness 0.15)
				)
				(justify left bottom mirror)
			)
		)
		(fp_text user "License: Apache-2.0"
			(at -0.4 -5.101 270)
			(layer "B.Fab")
			(effects
				(font
					(size 0.7 0.7)
					(thickness 0.15)
				)
				(justify left bottom mirror)
			)
		)
		(fp_text user "Author: Antmicro"
			(at -0.4 -3.901 270)
			(layer "B.Fab")
			(effects
				(font
					(size 0.7 0.7)
					(thickness 0.15)
				)
				(justify left bottom mirror)
			)
		)
		(pad "1" smd circle
			(at 0 0 90)
			(size 0.75 0.75)
			(layers "B.Cu" "B.Mask")
			(net 6 "DVDD")
			(pinfunction "1")
			(pintype "passive")
		)
	)
	(footprint "antmicro-footprints:C_0402_1005Metric"
		(layer "B.Cu")
		(at 153.031866 74.235118 180)
		(descr "Capacitor SMD 0402")
		(tags "capacitor SMD 0402")
		(property "Reference" "C248"
			(at -21.168135 -9.464883 0)
			(layer "B.SilkS")
			(effects
				(font
					(size 0.7 0.7)
					(thickness 0.15)
				)
				(justify mirror)
			)
		)
		(property "Value" "C_1u_25V_0402"
			(at -1.022927 -2.155213 0)
			(layer "B.Fab")
			(effects
				(font
					(size 0.7 0.7)
					(thickness 0.15)
				)
				(justify left bottom mirror)
			)
		)
		(property "Datasheet" "https://www.murata.com/products/productdetail?partno=GRM155R61E105KE11%23"
			(at 0 0 0)
			(layer "B.Fab")
			(hide yes)
			(effects
				(font
					(size 1.27 1.27)
					(thickness 0.15)
				)
				(justify mirror)
			)
		)
		(property "Description" "SMD Multilayer Ceramic Capacitor, 1 µF, 25 V, 0402 [1005 Metric], ± 10%, X5R, GRM Series"
			(at 0 0 0)
			(layer "B.Fab")
			(hide yes)
			(effects
				(font
					(size 1.27 1.27)
					(thickness 0.15)
				)
				(justify mirror)
			)
		)
		(property "MPN" "GRM155R61E105KE11J"
			(at 0 0 180)
			(unlocked yes)
			(layer "B.Fab")
			(hide yes)
			(effects
				(font
					(size 1 1)
					(thickness 0.15)
				)
				(justify mirror)
			)
		)
		(property "Manufacturer" "Murata"
			(at 0 0 180)
			(unlocked yes)
			(layer "B.Fab")
			(hide yes)
			(effects
				(font
					(size 1 1)
					(thickness 0.15)
				)
				(justify mirror)
			)
		)
		(property "License" "Apache-2.0"
			(at 0 0 180)
			(unlocked yes)
			(layer "B.Fab")
			(hide yes)
			(effects
				(font
					(size 1 1)
					(thickness 0.15)
				)
				(justify mirror)
			)
		)
		(property "Author" "Antmicro"
			(at 0 0 180)
			(unlocked yes)
			(layer "B.Fab")
			(hide yes)
			(effects
				(font
					(size 1 1)
					(thickness 0.15)
				)
				(justify mirror)
			)
		)
		(property "Val" "1u"
			(at 0 0 180)
			(unlocked yes)
			(layer "B.Fab")
			(hide yes)
			(effects
				(font
					(size 1 1)
					(thickness 0.15)
				)
				(justify mirror)
			)
		)
		(property "Voltage" "25V"
			(at 0 0 180)
			(unlocked yes)
			(layer "B.Fab")
			(hide yes)
			(effects
				(font
					(size 1 1)
					(thickness 0.15)
				)
				(justify mirror)
			)
		)
		(property "Dielectric" "X5R"
			(at 0 0 180)
			(unlocked yes)
			(layer "B.Fab")
			(hide yes)
			(effects
				(font
					(size 1 1)
					(thickness 0.15)
				)
				(justify mirror)
			)
		)
		(sheetname "/X710-AT2 power/")
		(sheetfile "x710-at2-power.kicad_sch")
		(attr smd)
		(fp_rect
			(start -0.925 0.47)
			(end 0.925 -0.47)
			(stroke
				(width 0.05)
				(type default)
			)
			(fill no)
			(layer "B.CrtYd")
		)
		(fp_line
			(start 0.504 0.25)
			(end 0.504 -0.248)
			(stroke
				(width 0.15)
				(type solid)
			)
			(layer "B.Fab")
		)
		(fp_line
			(start 0.504 -0.248)
			(end -0.494 -0.248)
			(stroke
				(width 0.15)
				(type solid)
			)
			(layer "B.Fab")
		)
		(fp_line
			(start -0.494 0.25)
			(end 0.504 0.25)
			(stroke
				(width 0.15)
				(type solid)
			)
			(layer "B.Fab")
		)
		(fp_line
			(start -0.494 -0.248)
			(end -0.494 0.25)
			(stroke
				(width 0.15)
				(type solid)
			)
			(layer "B.Fab")
		)
		(fp_text user "Author: Antmicro"
			(at -0.939 -3.399 0)
			(layer "B.Fab")
			(effects
				(font
					(size 0.7 0.7)
					(thickness 0.15)
				)
				(justify left bottom mirror)
			)
		)
		(fp_text user "${REFERENCE}"
			(at -0.939 -4.599 0)
			(layer "B.Fab")
			(effects
				(font
					(size 0.7 0.7)
					(thickness 0.15)
				)
				(justify left bottom mirror)
			)
		)
		(fp_text user "License: Apache-2.0"
			(at -0.939 -5.799 0)
			(layer "B.Fab")
			(effects
				(font
					(size 0.7 0.7)
					(thickness 0.15)
				)
				(justify left bottom mirror)
			)
		)
		(pad "1" smd roundrect
			(at -0.48 0 180)
			(size 0.59 0.64)
			(layers "B.Cu" "B.Mask" "B.Paste")
			(roundrect_rratio 0.25)
			(net 23 "GND")
			(pintype "passive")
		)
		(pad "2" smd roundrect
			(at 0.48 0 180)
			(size 0.59 0.64)
			(layers "B.Cu" "B.Mask" "B.Paste")
			(roundrect_rratio 0.25)
			(net 7 "+3V3")
			(pintype "passive")
		)
	)
	(footprint "antmicro-footprints:SOT-416"
		(layer "B.Cu")
		(at 178.5 75.55 -90)
		(descr "SOT-416")
		(tags "SOT-416")
		(property "Reference" "Q5"
			(at -0.75 1.3 90)
			(layer "B.SilkS")
			(effects
				(font
					(size 0.7 0.7)
					(thickness 0.15)
				)
				(justify left bottom mirror)
			)
		)
		(property "Value" "DTC014T_SOT-416"
			(at 0 -2 90)
			(layer "B.Fab")
			(effects
				(font
					(size 0.7 0.7)
					(thickness 0.15)
				)
				(justify left bottom mirror)
			)
		)
		(property "Datasheet" "https://www.rohm.com/datasheet?p=DTC014TEB&dist=Mouser&media=referral&source=mouser.com&campaign=Mouser"
			(at 0 0 90)
			(layer "B.Fab")
			(hide yes)
			(effects
				(font
					(size 1.27 1.27)
					(thickness 0.15)
				)
				(justify mirror)
			)
		)
		(property "Description" "Bipolar (BJT) Single Transistor with built-in base resistor, NPN, 50V, 100mA, 150mW, SOT-416FL, Surface Mount"
			(at 0 0 90)
			(layer "B.Fab")
			(hide yes)
			(effects
				(font
					(size 1.27 1.27)
					(thickness 0.15)
				)
				(justify mirror)
			)
		)
		(property "Manufacturer" "ROHM Semiconductor"
			(at 0 0 270)
			(unlocked yes)
			(layer "B.Fab")
			(hide yes)
			(effects
				(font
					(size 1 1)
					(thickness 0.15)
				)
				(justify mirror)
			)
		)
		(property "MPN" "DTC014TEBTL"
			(at 0 0 270)
			(unlocked yes)
			(layer "B.Fab")
			(hide yes)
			(effects
				(font
					(size 1 1)
					(thickness 0.15)
				)
				(justify mirror)
			)
		)
		(property "Author" "Antmicro"
			(at 0 0 270)
			(unlocked yes)
			(layer "B.Fab")
			(hide yes)
			(effects
				(font
					(size 1 1)
					(thickness 0.15)
				)
				(justify mirror)
			)
		)
		(property "License" "Apache-2.0"
			(at 0 0 270)
			(unlocked yes)
			(layer "B.Fab")
			(hide yes)
			(effects
				(font
					(size 1 1)
					(thickness 0.15)
				)
				(justify mirror)
			)
		)
		(sheetname "/X710 DCDC converters/")
		(sheetfile "DCDC_converters_X710.kicad_sch")
		(attr smd)
		(fp_line
			(start 0.508 0.9)
			(end -0.5 0.9)
			(stroke
				(width 0.15)
				(type solid)
			)
			(layer "B.SilkS")
		)
		(fp_line
			(start 0.508 0.9)
			(end 0.508 0.592)
			(stroke
				(width 0.15)
				(type solid)
			)
			(layer "B.SilkS")
		)
		(fp_line
			(start -0.5 0.15)
			(end -0.5 -0.15)
			(stroke
				(width 0.15)
				(type solid)
			)
			(layer "B.SilkS")
		)
		(fp_line
			(start 0.5 -0.9)
			(end 0.5 -0.7)
			(stroke
				(width 0.15)
				(type solid)
			)
			(layer "B.SilkS")
		)
		(fp_line
			(start 0.5 -0.9)
			(end -0.5 -0.9)
			(stroke
				(width 0.15)
				(type solid)
			)
			(layer "B.SilkS")
		)
		(fp_rect
			(start -1 1.05)
			(end 1 -1.05)
			(stroke
				(width 0.05)
				(type solid)
			)
			(fill no)
			(layer "B.CrtYd")
		)
		(fp_line
			(start -0.05 0.9)
			(end -0.45 0.5)
			(stroke
				(width 0.15)
				(type solid)
			)
			(layer "B.Fab")
		)
		(fp_rect
			(start 0.45 -0.9)
			(end -0.45 0.9)
			(stroke
				(width 0.15)
				(type solid)
			)
			(fill no)
			(layer "B.Fab")
		)
		(fp_text user "Author: Antmicro"
			(at -1 -4.602 90)
			(layer "B.Fab")
			(effects
				(font
					(size 0.7 0.7)
					(thickness 0.15)
				)
				(justify left bottom mirror)
			)
		)
		(fp_text user "License: Apache-2.0"
			(at -1 -5.802 90)
			(layer "B.Fab")
			(effects
				(font
					(size 0.7 0.7)
					(thickness 0.15)
				)
				(justify left bottom mirror)
			)
		)
		(fp_text user "${REFERENCE}"
			(at -1 -3.4 90)
			(layer "B.Fab")
			(effects
				(font
					(size 0.7 0.7)
					(thickness 0.15)
				)
				(justify left bottom mirror)
			)
		)
		(pad "1" smd rect
			(at -0.652 0.5 270)
			(size 0.6 0.5)
			(layers "B.Cu" "B.Mask" "B.Paste")
			(net 341 "/X710 DCDC converters/+DVDD_OUT")
			(pinfunction "B")
			(pintype "input")
		)
		(pad "2" smd rect
			(at -0.652 -0.498 270)
			(size 0.6 0.5)
			(layers "B.Cu" "B.Mask" "B.Paste")
			(net 23 "GND")
			(pinfunction "E")
			(pintype "passive")
		)
		(pad "3" smd rect
			(at 0.65 0 270)
			(size 0.6 0.5)
			(layers "B.Cu" "B.Mask" "B.Paste")
			(net 431 "Net-(Q5-C)")
			(pinfunction "C")
			(pintype "passive")
		)
	)
	(footprint "antmicro-footprints:TP_SMD_0.75mm"
		(layer "B.Cu")
		(at 183.75 81.75 90)
		(property "Reference" "TP17"
			(at -10.75 0.75 270)
			(layer "B.SilkS")
			(effects
				(font
					(size 0.7 0.7)
					(thickness 0.15)
				)
				(justify left bottom mirror)
			)
		)
		(property "Value" "TP_0.75mm_SMD"
			(at 0 -1.2 270)
			(layer "B.Fab")
			(effects
				(font
					(size 0.7 0.7)
					(thickness 0.15)
				)
				(justify left bottom mirror)
			)
		)
		(property "Description" "SMT test point"
			(at 0 0 270)
			(layer "B.Fab")
			(hide yes)
			(effects
				(font
					(size 1.27 1.27)
					(thickness 0.15)
				)
				(justify mirror)
			)
		)
		(property "MPN" ""
			(at 0 0 90)
			(unlocked yes)
			(layer "B.Fab")
			(hide yes)
			(effects
				(font
					(size 1 1)
					(thickness 0.15)
				)
				(justify mirror)
			)
		)
		(property "Manufacturer" ""
			(at 0 0 90)
			(unlocked yes)
			(layer "B.Fab")
			(hide yes)
			(effects
				(font
					(size 1 1)
					(thickness 0.15)
				)
				(justify mirror)
			)
		)
		(property "Author" "Antmicro"
			(at 0 0 90)
			(unlocked yes)
			(layer "B.Fab")
			(hide yes)
			(effects
				(font
					(size 1 1)
					(thickness 0.15)
				)
				(justify mirror)
			)
		)
		(property "License" "Apache-2.0"
			(at 0 0 90)
			(unlocked yes)
			(layer "B.Fab")
			(hide yes)
			(effects
				(font
					(size 1 1)
					(thickness 0.15)
				)
				(justify mirror)
			)
		)
		(sheetname "/X710 DCDC converters/")
		(sheetfile "DCDC_converters_X710.kicad_sch")
		(attr exclude_from_pos_files exclude_from_bom)
		(fp_circle
			(center 0 0)
			(end 0.475 0)
			(stroke
				(width 0.05)
				(type default)
			)
			(fill no)
			(layer "B.CrtYd")
		)
		(fp_text user "${REFERENCE}"
			(at -0.4 -2.7 270)
			(layer "B.Fab")
			(effects
				(font
					(size 0.7 0.7)
					(thickness 0.15)
				)
				(justify left bottom mirror)
			)
		)
		(fp_text user "License: Apache-2.0"
			(at -0.4 -5.101 270)
			(layer "B.Fab")
			(effects
				(font
					(size 0.7 0.7)
					(thickness 0.15)
				)
				(justify left bottom mirror)
			)
		)
		(fp_text user "Author: Antmicro"
			(at -0.4 -3.901 270)
			(layer "B.Fab")
			(effects
				(font
					(size 0.7 0.7)
					(thickness 0.15)
				)
				(justify left bottom mirror)
			)
		)
		(pad "1" smd circle
			(at 0 0 90)
			(size 0.75 0.75)
			(layers "B.Cu" "B.Mask")
			(net 18 "+1V88")
			(pinfunction "1")
			(pintype "passive")
		)
	)
	(footprint "antmicro-footprints:C_0402_1005Metric"
		(layer "B.Cu")
		(at 128.009999 116.655001 180)
		(descr "Capacitor SMD 0402")
		(tags "capacitor SMD 0402")
		(property "Reference" "C97"
			(at -21.900002 7.700002 0)
			(layer "B.SilkS")
			(effects
				(font
					(size 0.7 0.7)
					(thickness 0.15)
				)
				(justify mirror)
			)
		)
		(property "Value" "C_10u_0402"
			(at -1.022927 -2.155213 0)
			(layer "B.Fab")
			(effects
				(font
					(size 0.7 0.7)
					(thickness 0.15)
				)
				(justify left bottom mirror)
			)
		)
		(property "Datasheet" "https://www.yageo.com/en/Chart/Download/pdf/CC0402MRX5R5BB106"
			(at 0 0 0)
			(layer "B.Fab")
			(hide yes)
			(effects
				(font
					(size 1.27 1.27)
					(thickness 0.15)
				)
				(justify mirror)
			)
		)
		(property "Description" "SMD Multilayer Ceramic Capacitor, 10 µF, 6.3 V, 0402 [1005 Metric], ± 20%, X5R, CC Series"
			(at 0 0 0)
			(layer "B.Fab")
			(hide yes)
			(effects
				(font
					(size 1.27 1.27)
					(thickness 0.15)
				)
				(justify mirror)
			)
		)
		(property "MPN" "CC0402MRX5R5BB106"
			(at 0 0 180)
			(unlocked yes)
			(layer "B.Fab")
			(hide yes)
			(effects
				(font
					(size 1 1)
					(thickness 0.15)
				)
				(justify mirror)
			)
		)
		(property "Manufacturer" "YAGEO"
			(at 0 0 180)
			(unlocked yes)
			(layer "B.Fab")
			(hide yes)
			(effects
				(font
					(size 1 1)
					(thickness 0.15)
				)
				(justify mirror)
			)
		)
		(property "License" "Apache-2.0"
			(at 0 0 180)
			(unlocked yes)
			(layer "B.Fab")
			(hide yes)
			(effects
				(font
					(size 1 1)
					(thickness 0.15)
				)
				(justify mirror)
			)
		)
		(property "Val" "10u"
			(at 0 0 180)
			(unlocked yes)
			(layer "B.Fab")
			(hide yes)
			(effects
				(font
					(size 1 1)
					(thickness 0.15)
				)
				(justify mirror)
			)
		)
		(property "Voltage" ""
			(at 0 0 180)
			(unlocked yes)
			(layer "B.Fab")
			(hide yes)
			(effects
				(font
					(size 1 1)
					(thickness 0.15)
				)
				(justify mirror)
			)
		)
		(property "Dielectric" ""
			(at 0 0 180)
			(unlocked yes)
			(layer "B.Fab")
			(hide yes)
			(effects
				(font
					(size 1 1)
					(thickness 0.15)
				)
				(justify mirror)
			)
		)
		(property "Author" "Antmicro"
			(at 0 0 180)
			(unlocked yes)
			(layer "B.Fab")
			(hide yes)
			(effects
				(font
					(size 1 1)
					(thickness 0.15)
				)
				(justify mirror)
			)
		)
		(sheetname "/TB Controller - Power/")
		(sheetfile "tb-power.kicad_sch")
		(attr smd)
		(fp_rect
			(start -0.925 0.47)
			(end 0.925 -0.47)
			(stroke
				(width 0.05)
				(type default)
			)
			(fill no)
			(layer "B.CrtYd")
		)
		(fp_line
			(start 0.504 0.25)
			(end 0.504 -0.248)
			(stroke
				(width 0.15)
				(type solid)
			)
			(layer "B.Fab")
		)
		(fp_line
			(start 0.504 -0.248)
			(end -0.494 -0.248)
			(stroke
				(width 0.15)
				(type solid)
			)
			(layer "B.Fab")
		)
		(fp_line
			(start -0.494 0.25)
			(end 0.504 0.25)
			(stroke
				(width 0.15)
				(type solid)
			)
			(layer "B.Fab")
		)
		(fp_line
			(start -0.494 -0.248)
			(end -0.494 0.25)
			(stroke
				(width 0.15)
				(type solid)
			)
			(layer "B.Fab")
		)
		(fp_text user "Author: Antmicro"
			(at -0.939 -3.399 0)
			(layer "B.Fab")
			(effects
				(font
					(size 0.7 0.7)
					(thickness 0.15)
				)
				(justify left bottom mirror)
			)
		)
		(fp_text user "${REFERENCE}"
			(at -0.939 -4.599 0)
			(layer "B.Fab")
			(effects
				(font
					(size 0.7 0.7)
					(thickness 0.15)
				)
				(justify left bottom mirror)
			)
		)
		(fp_text user "License: Apache-2.0"
			(at -0.939 -5.799 0)
			(layer "B.Fab")
			(effects
				(font
					(size 0.7 0.7)
					(thickness 0.15)
				)
				(justify left bottom mirror)
			)
		)
		(pad "1" smd roundrect
			(at -0.48 0 180)
			(size 0.59 0.64)
			(layers "B.Cu" "B.Mask" "B.Paste")
			(roundrect_rratio 0.25)
			(net 23 "GND")
			(pintype "passive")
		)
		(pad "2" smd roundrect
			(at 0.48 0 180)
			(size 0.59 0.64)
			(layers "B.Cu" "B.Mask" "B.Paste")
			(roundrect_rratio 0.25)
			(net 181 "Net-(U4A-VCC3P3_S0)")
			(pintype "passive")
		)
	)
	(footprint "antmicro-footprints:TP_SMD_0.75mm"
		(layer "B.Cu")
		(at 156.731866 62.935117 180)
		(property "Reference" "TP28"
			(at -0.268134 3.135117 270)
			(layer "B.SilkS")
			(effects
				(font
					(size 0.7 0.7)
					(thickness 0.15)
				)
				(justify left bottom mirror)
			)
		)
		(property "Value" "TP_0.75mm_SMD"
			(at 0 -1.2 0)
			(layer "B.Fab")
			(effects
				(font
					(size 0.7 0.7)
					(thickness 0.15)
				)
				(justify left bottom mirror)
			)
		)
		(property "Description" "SMT test point"
			(at 0 0 0)
			(layer "B.Fab")
			(hide yes)
			(effects
				(font
					(size 1.27 1.27)
					(thickness 0.15)
				)
				(justify mirror)
			)
		)
		(property "MPN" ""
			(at 0 0 180)
			(unlocked yes)
			(layer "B.Fab")
			(hide yes)
			(effects
				(font
					(size 1 1)
					(thickness 0.15)
				)
				(justify mirror)
			)
		)
		(property "Manufacturer" ""
			(at 0 0 180)
			(unlocked yes)
			(layer "B.Fab")
			(hide yes)
			(effects
				(font
					(size 1 1)
					(thickness 0.15)
				)
				(justify mirror)
			)
		)
		(property "Author" "Antmicro"
			(at 0 0 180)
			(unlocked yes)
			(layer "B.Fab")
			(hide yes)
			(effects
				(font
					(size 1 1)
					(thickness 0.15)
				)
				(justify mirror)
			)
		)
		(property "License" "Apache-2.0"
			(at 0 0 180)
			(unlocked yes)
			(layer "B.Fab")
			(hide yes)
			(effects
				(font
					(size 1 1)
					(thickness 0.15)
				)
				(justify mirror)
			)
		)
		(sheetname "/X710-AT2 Misc/")
		(sheetfile "x710-at2-mics.kicad_sch")
		(attr exclude_from_pos_files exclude_from_bom)
		(fp_circle
			(center 0 0)
			(end 0.475 0)
			(stroke
				(width 0.05)
				(type default)
			)
			(fill no)
			(layer "B.CrtYd")
		)
		(fp_text user "${REFERENCE}"
			(at -0.4 -2.7 0)
			(layer "B.Fab")
			(effects
				(font
					(size 0.7 0.7)
					(thickness 0.15)
				)
				(justify left bottom mirror)
			)
		)
		(fp_text user "Author: Antmicro"
			(at -0.4 -3.901 0)
			(layer "B.Fab")
			(effects
				(font
					(size 0.7 0.7)
					(thickness 0.15)
				)
				(justify left bottom mirror)
			)
		)
		(fp_text user "License: Apache-2.0"
			(at -0.4 -5.101 0)
			(layer "B.Fab")
			(effects
				(font
					(size 0.7 0.7)
					(thickness 0.15)
				)
				(justify left bottom mirror)
			)
		)
		(pad "1" smd circle
			(at 0 0 180)
			(size 0.75 0.75)
			(layers "B.Cu" "B.Mask")
			(net 138 "/X710-AT2 Misc/NCSI.TXD_1")
			(pinfunction "1")
			(pintype "passive")
		)
	)
	(footprint "antmicro-footprints:C_0402_1005Metric"
		(layer "B.Cu")
		(at 154.261866 87.265117 180)
		(descr "Capacitor SMD 0402")
		(tags "capacitor SMD 0402")
		(property "Reference" "C208"
			(at -17.938134 -9.464883 0)
			(layer "B.SilkS")
			(effects
				(font
					(size 0.7 0.7)
					(thickness 0.15)
				)
				(justify mirror)
			)
		)
		(property "Value" "C_1u_25V_0402"
			(at -1.022927 -2.155213 0)
			(layer "B.Fab")
			(effects
				(font
					(size 0.7 0.7)
					(thickness 0.15)
				)
				(justify left bottom mirror)
			)
		)
		(property "Datasheet" "https://www.murata.com/products/productdetail?partno=GRM155R61E105KE11%23"
			(at 0 0 0)
			(layer "B.Fab")
			(hide yes)
			(effects
				(font
					(size 1.27 1.27)
					(thickness 0.15)
				)
				(justify mirror)
			)
		)
		(property "Description" "SMD Multilayer Ceramic Capacitor, 1 µF, 25 V, 0402 [1005 Metric], ± 10%, X5R, GRM Series"
			(at 0 0 0)
			(layer "B.Fab")
			(hide yes)
			(effects
				(font
					(size 1.27 1.27)
					(thickness 0.15)
				)
				(justify mirror)
			)
		)
		(property "MPN" "GRM155R61E105KE11J"
			(at 0 0 180)
			(unlocked yes)
			(layer "B.Fab")
			(hide yes)
			(effects
				(font
					(size 1 1)
					(thickness 0.15)
				)
				(justify mirror)
			)
		)
		(property "Manufacturer" "Murata"
			(at 0 0 180)
			(unlocked yes)
			(layer "B.Fab")
			(hide yes)
			(effects
				(font
					(size 1 1)
					(thickness 0.15)
				)
				(justify mirror)
			)
		)
		(property "License" "Apache-2.0"
			(at 0 0 180)
			(unlocked yes)
			(layer "B.Fab")
			(hide yes)
			(effects
				(font
					(size 1 1)
					(thickness 0.15)
				)
				(justify mirror)
			)
		)
		(property "Author" "Antmicro"
			(at 0 0 180)
			(unlocked yes)
			(layer "B.Fab")
			(hide yes)
			(effects
				(font
					(size 1 1)
					(thickness 0.15)
				)
				(justify mirror)
			)
		)
		(property "Val" "1u"
			(at 0 0 180)
			(unlocked yes)
			(layer "B.Fab")
			(hide yes)
			(effects
				(font
					(size 1 1)
					(thickness 0.15)
				)
				(justify mirror)
			)
		)
		(property "Voltage" "25V"
			(at 0 0 180)
			(unlocked yes)
			(layer "B.Fab")
			(hide yes)
			(effects
				(font
					(size 1 1)
					(thickness 0.15)
				)
				(justify mirror)
			)
		)
		(property "Dielectric" "X5R"
			(at 0 0 180)
			(unlocked yes)
			(layer "B.Fab")
			(hide yes)
			(effects
				(font
					(size 1 1)
					(thickness 0.15)
				)
				(justify mirror)
			)
		)
		(sheetname "/X710-AT2 power/")
		(sheetfile "x710-at2-power.kicad_sch")
		(attr smd)
		(fp_rect
			(start -0.925 0.47)
			(end 0.925 -0.47)
			(stroke
				(width 0.05)
				(type default)
			)
			(fill no)
			(layer "B.CrtYd")
		)
		(fp_line
			(start 0.504 0.25)
			(end 0.504 -0.248)
			(stroke
				(width 0.15)
				(type solid)
			)
			(layer "B.Fab")
		)
		(fp_line
			(start 0.504 -0.248)
			(end -0.494 -0.248)
			(stroke
				(width 0.15)
				(type solid)
			)
			(layer "B.Fab")
		)
		(fp_line
			(start -0.494 0.25)
			(end 0.504 0.25)
			(stroke
				(width 0.15)
				(type solid)
			)
			(layer "B.Fab")
		)
		(fp_line
			(start -0.494 -0.248)
			(end -0.494 0.25)
			(stroke
				(width 0.15)
				(type solid)
			)
			(layer "B.Fab")
		)
		(fp_text user "${REFERENCE}"
			(at -0.939 -4.599 0)
			(layer "B.Fab")
			(effects
				(font
					(size 0.7 0.7)
					(thickness 0.15)
				)
				(justify left bottom mirror)
			)
		)
		(fp_text user "License: Apache-2.0"
			(at -0.939 -5.799 0)
			(layer "B.Fab")
			(effects
				(font
					(size 0.7 0.7)
					(thickness 0.15)
				)
				(justify left bottom mirror)
			)
		)
		(fp_text user "Author: Antmicro"
			(at -0.939 -3.399 0)
			(layer "B.Fab")
			(effects
				(font
					(size 0.7 0.7)
					(thickness 0.15)
				)
				(justify left bottom mirror)
			)
		)
		(pad "1" smd roundrect
			(at -0.48 0 180)
			(size 0.59 0.64)
			(layers "B.Cu" "B.Mask" "B.Paste")
			(roundrect_rratio 0.25)
			(net 23 "GND")
			(pintype "passive")
		)
		(pad "2" smd roundrect
			(at 0.48 0 180)
			(size 0.59 0.64)
			(layers "B.Cu" "B.Mask" "B.Paste")
			(roundrect_rratio 0.25)
			(net 21 "XFI_PVDD")
			(pintype "passive")
		)
	)
	(footprint "antmicro-footprints:C_0402_1005Metric"
		(layer "B.Cu")
		(at 158.451866 87.415117 -90)
		(descr "Capacitor SMD 0402")
		(tags "capacitor SMD 0402")
		(property "Reference" "C168"
			(at 9.984883 -20.453133 90)
			(layer "B.SilkS")
			(effects
				(font
					(size 0.7 0.7)
					(thickness 0.15)
				)
				(justify mirror)
			)
		)
		(property "Value" "C_1u_25V_0402"
			(at -1.022927 -2.155213 90)
			(layer "B.Fab")
			(effects
				(font
					(size 0.7 0.7)
					(thickness 0.15)
				)
				(justify left bottom mirror)
			)
		)
		(property "Datasheet" "https://www.murata.com/products/productdetail?partno=GRM155R61E105KE11%23"
			(at 0 0 90)
			(layer "B.Fab")
			(hide yes)
			(effects
				(font
					(size 1.27 1.27)
					(thickness 0.15)
				)
				(justify mirror)
			)
		)
		(property "Description" "SMD Multilayer Ceramic Capacitor, 1 µF, 25 V, 0402 [1005 Metric], ± 10%, X5R, GRM Series"
			(at 0 0 90)
			(layer "B.Fab")
			(hide yes)
			(effects
				(font
					(size 1.27 1.27)
					(thickness 0.15)
				)
				(justify mirror)
			)
		)
		(property "MPN" "GRM155R61E105KE11J"
			(at 0 0 270)
			(unlocked yes)
			(layer "B.Fab")
			(hide yes)
			(effects
				(font
					(size 1 1)
					(thickness 0.15)
				)
				(justify mirror)
			)
		)
		(property "Manufacturer" "Murata"
			(at 0 0 270)
			(unlocked yes)
			(layer "B.Fab")
			(hide yes)
			(effects
				(font
					(size 1 1)
					(thickness 0.15)
				)
				(justify mirror)
			)
		)
		(property "License" "Apache-2.0"
			(at 0 0 270)
			(unlocked yes)
			(layer "B.Fab")
			(hide yes)
			(effects
				(font
					(size 1 1)
					(thickness 0.15)
				)
				(justify mirror)
			)
		)
		(property "Author" "Antmicro"
			(at 0 0 270)
			(unlocked yes)
			(layer "B.Fab")
			(hide yes)
			(effects
				(font
					(size 1 1)
					(thickness 0.15)
				)
				(justify mirror)
			)
		)
		(property "Val" "1u"
			(at 0 0 270)
			(unlocked yes)
			(layer "B.Fab")
			(hide yes)
			(effects
				(font
					(size 1 1)
					(thickness 0.15)
				)
				(justify mirror)
			)
		)
		(property "Voltage" "25V"
			(at 0 0 270)
			(unlocked yes)
			(layer "B.Fab")
			(hide yes)
			(effects
				(font
					(size 1 1)
					(thickness 0.15)
				)
				(justify mirror)
			)
		)
		(property "Dielectric" "X5R"
			(at 0 0 270)
			(unlocked yes)
			(layer "B.Fab")
			(hide yes)
			(effects
				(font
					(size 1 1)
					(thickness 0.15)
				)
				(justify mirror)
			)
		)
		(sheetname "/X710-AT2 power/")
		(sheetfile "x710-at2-power.kicad_sch")
		(attr smd)
		(fp_rect
			(start -0.925 0.47)
			(end 0.925 -0.47)
			(stroke
				(width 0.05)
				(type default)
			)
			(fill no)
			(layer "B.CrtYd")
		)
		(fp_line
			(start -0.494 0.25)
			(end 0.504 0.25)
			(stroke
				(width 0.15)
				(type solid)
			)
			(layer "B.Fab")
		)
		(fp_line
			(start 0.504 0.25)
			(end 0.504 -0.248)
			(stroke
				(width 0.15)
				(type solid)
			)
			(layer "B.Fab")
		)
		(fp_line
			(start -0.494 -0.248)
			(end -0.494 0.25)
			(stroke
				(width 0.15)
				(type solid)
			)
			(layer "B.Fab")
		)
		(fp_line
			(start 0.504 -0.248)
			(end -0.494 -0.248)
			(stroke
				(width 0.15)
				(type solid)
			)
			(layer "B.Fab")
		)
		(fp_text user "Author: Antmicro"
			(at -0.939 -3.399 90)
			(layer "B.Fab")
			(effects
				(font
					(size 0.7 0.7)
					(thickness 0.15)
				)
				(justify left bottom mirror)
			)
		)
		(fp_text user "${REFERENCE}"
			(at -0.939 -4.599 90)
			(layer "B.Fab")
			(effects
				(font
					(size 0.7 0.7)
					(thickness 0.15)
				)
				(justify left bottom mirror)
			)
		)
		(fp_text user "License: Apache-2.0"
			(at -0.939 -5.799 90)
			(layer "B.Fab")
			(effects
				(font
					(size 0.7 0.7)
					(thickness 0.15)
				)
				(justify left bottom mirror)
			)
		)
		(pad "1" smd roundrect
			(at -0.48 0 270)
			(size 0.59 0.64)
			(layers "B.Cu" "B.Mask" "B.Paste")
			(roundrect_rratio 0.25)
			(net 23 "GND")
			(pintype "passive")
		)
		(pad "2" smd roundrect
			(at 0.48 0 270)
			(size 0.59 0.64)
			(layers "B.Cu" "B.Mask" "B.Paste")
			(roundrect_rratio 0.25)
			(net 20 "XGB_AVDDH")
			(pintype "passive")
		)
	)
	(footprint "antmicro-footprints:C_0402_1005Metric"
		(layer "B.Cu")
		(at 153.031867 78.260117 180)
		(descr "Capacitor SMD 0402")
		(tags "capacitor SMD 0402")
		(property "Reference" "C222"
			(at -21.168135 -9.464883 0)
			(layer "B.SilkS")
			(effects
				(font
					(size 0.7 0.7)
					(thickness 0.15)
				)
				(justify mirror)
			)
		)
		(property "Value" "C_1u_25V_0402"
			(at -1.022927 -2.155213 0)
			(layer "B.Fab")
			(effects
				(font
					(size 0.7 0.7)
					(thickness 0.15)
				)
				(justify left bottom mirror)
			)
		)
		(property "Datasheet" "https://www.murata.com/products/productdetail?partno=GRM155R61E105KE11%23"
			(at 0 0 0)
			(layer "B.Fab")
			(hide yes)
			(effects
				(font
					(size 1.27 1.27)
					(thickness 0.15)
				)
				(justify mirror)
			)
		)
		(property "Description" "SMD Multilayer Ceramic Capacitor, 1 µF, 25 V, 0402 [1005 Metric], ± 10%, X5R, GRM Series"
			(at 0 0 0)
			(layer "B.Fab")
			(hide yes)
			(effects
				(font
					(size 1.27 1.27)
					(thickness 0.15)
				)
				(justify mirror)
			)
		)
		(property "MPN" "GRM155R61E105KE11J"
			(at 0 0 180)
			(unlocked yes)
			(layer "B.Fab")
			(hide yes)
			(effects
				(font
					(size 1 1)
					(thickness 0.15)
				)
				(justify mirror)
			)
		)
		(property "Manufacturer" "Murata"
			(at 0 0 180)
			(unlocked yes)
			(layer "B.Fab")
			(hide yes)
			(effects
				(font
					(size 1 1)
					(thickness 0.15)
				)
				(justify mirror)
			)
		)
		(property "License" "Apache-2.0"
			(at 0 0 180)
			(unlocked yes)
			(layer "B.Fab")
			(hide yes)
			(effects
				(font
					(size 1 1)
					(thickness 0.15)
				)
				(justify mirror)
			)
		)
		(property "Author" "Antmicro"
			(at 0 0 180)
			(unlocked yes)
			(layer "B.Fab")
			(hide yes)
			(effects
				(font
					(size 1 1)
					(thickness 0.15)
				)
				(justify mirror)
			)
		)
		(property "Val" "1u"
			(at 0 0 180)
			(unlocked yes)
			(layer "B.Fab")
			(hide yes)
			(effects
				(font
					(size 1 1)
					(thickness 0.15)
				)
				(justify mirror)
			)
		)
		(property "Voltage" "25V"
			(at 0 0 180)
			(unlocked yes)
			(layer "B.Fab")
			(hide yes)
			(effects
				(font
					(size 1 1)
					(thickness 0.15)
				)
				(justify mirror)
			)
		)
		(property "Dielectric" "X5R"
			(at 0 0 180)
			(unlocked yes)
			(layer "B.Fab")
			(hide yes)
			(effects
				(font
					(size 1 1)
					(thickness 0.15)
				)
				(justify mirror)
			)
		)
		(sheetname "/X710-AT2 power/")
		(sheetfile "x710-at2-power.kicad_sch")
		(attr smd)
		(fp_rect
			(start -0.925 0.47)
			(end 0.925 -0.47)
			(stroke
				(width 0.05)
				(type default)
			)
			(fill no)
			(layer "B.CrtYd")
		)
		(fp_line
			(start 0.504 0.25)
			(end 0.504 -0.248)
			(stroke
				(width 0.15)
				(type solid)
			)
			(layer "B.Fab")
		)
		(fp_line
			(start 0.504 -0.248)
			(end -0.494 -0.248)
			(stroke
				(width 0.15)
				(type solid)
			)
			(layer "B.Fab")
		)
		(fp_line
			(start -0.494 0.25)
			(end 0.504 0.25)
			(stroke
				(width 0.15)
				(type solid)
			)
			(layer "B.Fab")
		)
		(fp_line
			(start -0.494 -0.248)
			(end -0.494 0.25)
			(stroke
				(width 0.15)
				(type solid)
			)
			(layer "B.Fab")
		)
		(fp_text user "${REFERENCE}"
			(at -0.939 -4.599 0)
			(layer "B.Fab")
			(effects
				(font
					(size 0.7 0.7)
					(thickness 0.15)
				)
				(justify left bottom mirror)
			)
		)
		(fp_text user "License: Apache-2.0"
			(at -0.939 -5.799 0)
			(layer "B.Fab")
			(effects
				(font
					(size 0.7 0.7)
					(thickness 0.15)
				)
				(justify left bottom mirror)
			)
		)
		(fp_text user "Author: Antmicro"
			(at -0.939 -3.399 0)
			(layer "B.Fab")
			(effects
				(font
					(size 0.7 0.7)
					(thickness 0.15)
				)
				(justify left bottom mirror)
			)
		)
		(pad "1" smd roundrect
			(at -0.48 0 180)
			(size 0.59 0.64)
			(layers "B.Cu" "B.Mask" "B.Paste")
			(roundrect_rratio 0.25)
			(net 23 "GND")
			(pintype "passive")
		)
		(pad "2" smd roundrect
			(at 0.48 0 180)
			(size 0.59 0.64)
			(layers "B.Cu" "B.Mask" "B.Paste")
			(roundrect_rratio 0.25)
			(net 1 "VCCA")
			(pintype "passive")
		)
	)
	(footprint "antmicro-footprints:C_0402_1005Metric"
		(layer "B.Cu")
		(at 158.926866 82.110117)
		(descr "Capacitor SMD 0402")
		(tags "capacitor SMD 0402")
		(property "Reference" "C200"
			(at 19.873134 9.464883 180)
			(layer "B.SilkS")
			(effects
				(font
					(size 0.7 0.7)
					(thickness 0.15)
				)
				(justify mirror)
			)
		)
		(property "Value" "C_1u_25V_0402"
			(at -1.022927 -2.155213 180)
			(layer "B.Fab")
			(effects
				(font
					(size 0.7 0.7)
					(thickness 0.15)
				)
				(justify left bottom mirror)
			)
		)
		(property "Datasheet" "https://www.murata.com/products/productdetail?partno=GRM155R61E105KE11%23"
			(at 0 0 180)
			(layer "B.Fab")
			(hide yes)
			(effects
				(font
					(size 1.27 1.27)
					(thickness 0.15)
				)
				(justify mirror)
			)
		)
		(property "Description" "SMD Multilayer Ceramic Capacitor, 1 µF, 25 V, 0402 [1005 Metric], ± 10%, X5R, GRM Series"
			(at 0 0 180)
			(layer "B.Fab")
			(hide yes)
			(effects
				(font
					(size 1.27 1.27)
					(thickness 0.15)
				)
				(justify mirror)
			)
		)
		(property "MPN" "GRM155R61E105KE11J"
			(at 0 0 0)
			(unlocked yes)
			(layer "B.Fab")
			(hide yes)
			(effects
				(font
					(size 1 1)
					(thickness 0.15)
				)
				(justify mirror)
			)
		)
		(property "Manufacturer" "Murata"
			(at 0 0 0)
			(unlocked yes)
			(layer "B.Fab")
			(hide yes)
			(effects
				(font
					(size 1 1)
					(thickness 0.15)
				)
				(justify mirror)
			)
		)
		(property "License" "Apache-2.0"
			(at 0 0 0)
			(unlocked yes)
			(layer "B.Fab")
			(hide yes)
			(effects
				(font
					(size 1 1)
					(thickness 0.15)
				)
				(justify mirror)
			)
		)
		(property "Author" "Antmicro"
			(at 0 0 0)
			(unlocked yes)
			(layer "B.Fab")
			(hide yes)
			(effects
				(font
					(size 1 1)
					(thickness 0.15)
				)
				(justify mirror)
			)
		)
		(property "Val" "1u"
			(at 0 0 0)
			(unlocked yes)
			(layer "B.Fab")
			(hide yes)
			(effects
				(font
					(size 1 1)
					(thickness 0.15)
				)
				(justify mirror)
			)
		)
		(property "Voltage" "25V"
			(at 0 0 0)
			(unlocked yes)
			(layer "B.Fab")
			(hide yes)
			(effects
				(font
					(size 1 1)
					(thickness 0.15)
				)
				(justify mirror)
			)
		)
		(property "Dielectric" "X5R"
			(at 0 0 0)
			(unlocked yes)
			(layer "B.Fab")
			(hide yes)
			(effects
				(font
					(size 1 1)
					(thickness 0.15)
				)
				(justify mirror)
			)
		)
		(sheetname "/X710-AT2 power/")
		(sheetfile "x710-at2-power.kicad_sch")
		(attr smd)
		(fp_rect
			(start -0.925 0.47)
			(end 0.925 -0.47)
			(stroke
				(width 0.05)
				(type default)
			)
			(fill no)
			(layer "B.CrtYd")
		)
		(fp_line
			(start -0.494 -0.248)
			(end -0.494 0.25)
			(stroke
				(width 0.15)
				(type solid)
			)
			(layer "B.Fab")
		)
		(fp_line
			(start -0.494 0.25)
			(end 0.504 0.25)
			(stroke
				(width 0.15)
				(type solid)
			)
			(layer "B.Fab")
		)
		(fp_line
			(start 0.504 -0.248)
			(end -0.494 -0.248)
			(stroke
				(width 0.15)
				(type solid)
			)
			(layer "B.Fab")
		)
		(fp_line
			(start 0.504 0.25)
			(end 0.504 -0.248)
			(stroke
				(width 0.15)
				(type solid)
			)
			(layer "B.Fab")
		)
		(fp_text user "License: Apache-2.0"
			(at -0.939 -5.799 180)
			(layer "B.Fab")
			(effects
				(font
					(size 0.7 0.7)
					(thickness 0.15)
				)
				(justify left bottom mirror)
			)
		)
		(fp_text user "Author: Antmicro"
			(at -0.939 -3.399 180)
			(layer "B.Fab")
			(effects
				(font
					(size 0.7 0.7)
					(thickness 0.15)
				)
				(justify left bottom mirror)
			)
		)
		(fp_text user "${REFERENCE}"
			(at -0.939 -4.599 180)
			(layer "B.Fab")
			(effects
				(font
					(size 0.7 0.7)
					(thickness 0.15)
				)
				(justify left bottom mirror)
			)
		)
		(pad "1" smd roundrect
			(at -0.48 0)
			(size 0.59 0.64)
			(layers "B.Cu" "B.Mask" "B.Paste")
			(roundrect_rratio 0.25)
			(net 23 "GND")
			(pintype "passive")
		)
		(pad "2" smd roundrect
			(at 0.48 0)
			(size 0.59 0.64)
			(layers "B.Cu" "B.Mask" "B.Paste")
			(roundrect_rratio 0.25)
			(net 14 "P1_AVDDL")
			(pintype "passive")
		)
	)
	(footprint "antmicro-footprints:R_0402_1005Metric"
		(layer "B.Cu")
		(at 145.631866 82.260117 180)
		(descr "Resistor SMD 0402")
		(tags "resistor SMD 0402")
		(property "Reference" "R122"
			(at -17.768134 -9.464883 0)
			(layer "B.SilkS")
			(effects
				(font
					(size 0.7 0.7)
					(thickness 0.15)
				)
				(justify mirror)
			)
		)
		(property "Value" "R_100R_0402"
			(at -1.011843 -1.772047 0)
			(layer "B.Fab")
			(effects
				(font
					(size 0.7 0.7)
					(thickness 0.15)
				)
				(justify left bottom mirror)
			)
		)
		(property "Datasheet" "https://www.bourns.com/docs/product-datasheets/cr.pdf"
			(at 0 0 0)
			(layer "B.Fab")
			(hide yes)
			(effects
				(font
					(size 1.27 1.27)
					(thickness 0.15)
				)
				(justify mirror)
			)
		)
		(property "Description" "SMD Chip Resistor, 100 ohm, ± 1%, 62.5 mW, 0402 [1005 Metric], Thick Film, General Purpose"
			(at 0 0 0)
			(layer "B.Fab")
			(hide yes)
			(effects
				(font
					(size 1.27 1.27)
					(thickness 0.15)
				)
				(justify mirror)
			)
		)
		(property "MPN" "CR0402-FX-1000GLF"
			(at 0 0 180)
			(unlocked yes)
			(layer "B.Fab")
			(hide yes)
			(effects
				(font
					(size 1 1)
					(thickness 0.15)
				)
				(justify mirror)
			)
		)
		(property "Manufacturer" "Bourns"
			(at 0 0 180)
			(unlocked yes)
			(layer "B.Fab")
			(hide yes)
			(effects
				(font
					(size 1 1)
					(thickness 0.15)
				)
				(justify mirror)
			)
		)
		(property "License" "Apache-2.0"
			(at 0 0 180)
			(unlocked yes)
			(layer "B.Fab")
			(hide yes)
			(effects
				(font
					(size 1 1)
					(thickness 0.15)
				)
				(justify mirror)
			)
		)
		(property "Author" "Antmicro"
			(at 0 0 180)
			(unlocked yes)
			(layer "B.Fab")
			(hide yes)
			(effects
				(font
					(size 1 1)
					(thickness 0.15)
				)
				(justify mirror)
			)
		)
		(property "Val" "100R"
			(at 0 0 180)
			(unlocked yes)
			(layer "B.Fab")
			(hide yes)
			(effects
				(font
					(size 1 1)
					(thickness 0.15)
				)
				(justify mirror)
			)
		)
		(property "Tolerance" "1%"
			(at 0 0 180)
			(unlocked yes)
			(layer "B.Fab")
			(hide yes)
			(effects
				(font
					(size 1 1)
					(thickness 0.15)
				)
				(justify mirror)
			)
		)
		(sheetname "/X710-AT2 RSVD/")
		(sheetfile "x710-at2-rsvd.kicad_sch")
		(attr smd)
		(fp_rect
			(start -0.925 0.47)
			(end 0.925 -0.47)
			(stroke
				(width 0.05)
				(type default)
			)
			(fill no)
			(layer "B.CrtYd")
		)
		(fp_rect
			(start -0.5 0.25)
			(end 0.5 -0.25)
			(stroke
				(width 0.15)
				(type solid)
			)
			(fill no)
			(layer "B.Fab")
		)
		(fp_text user "Author: Antmicro"
			(at -0.95 -4.169 0)
			(layer "B.Fab")
			(effects
				(font
					(size 0.7 0.7)
					(thickness 0.15)
				)
				(justify left bottom mirror)
			)
		)
		(fp_text user "License: Apache-2.0"
			(at -0.95 -5.169 0)
			(layer "B.Fab")
			(effects
				(font
					(size 0.7 0.7)
					(thickness 0.15)
				)
				(justify left bottom mirror)
			)
		)
		(fp_text user "${REFERENCE}"
			(at -0.95 -3.168 0)
			(layer "B.Fab")
			(effects
				(font
					(size 0.7 0.7)
					(thickness 0.15)
				)
				(justify left bottom mirror)
			)
		)
		(pad "1" smd roundrect
			(at -0.48 0 180)
			(size 0.59 0.64)
			(layers "B.Cu" "B.Mask" "B.Paste")
			(roundrect_rratio 0.25)
			(net 23 "GND")
			(pintype "passive")
		)
		(pad "2" smd roundrect
			(at 0.48 0 180)
			(size 0.59 0.64)
			(layers "B.Cu" "B.Mask" "B.Paste")
			(roundrect_rratio 0.25)
			(net 93 "/X710-AT2 RSVD/RSVDY22_VSS")
			(pintype "passive")
		)
	)
	(footprint "antmicro-footprints:R_0402_1005Metric"
		(layer "B.Cu")
		(at 162.381866 74.485117)
		(descr "Resistor SMD 0402")
		(tags "resistor SMD 0402")
		(property "Reference" "R197"
			(at 2.368134 0.014883 180)
			(layer "B.SilkS")
			(effects
				(font
					(size 0.7 0.7)
					(thickness 0.15)
				)
				(justify mirror)
			)
		)
		(property "Value" "R_0R_0402"
			(at -1.011843 -1.772047 180)
			(layer "B.Fab")
			(effects
				(font
					(size 0.7 0.7)
					(thickness 0.15)
				)
				(justify left bottom mirror)
			)
		)
		(property "Datasheet" "https://industrial.panasonic.com/cdbs/www-data/pdf/RDA0000/AOA0000C301.pdf"
			(at 0 0 180)
			(layer "B.Fab")
			(hide yes)
			(effects
				(font
					(size 1.27 1.27)
					(thickness 0.15)
				)
				(justify mirror)
			)
		)
		(property "Description" "SMD Chip Resistor, Jumper, 0 ohm, 100 mW, 0402 [1005 Metric], Thick Film, General Purpose"
			(at 0 0 180)
			(layer "B.Fab")
			(hide yes)
			(effects
				(font
					(size 1.27 1.27)
					(thickness 0.15)
				)
				(justify mirror)
			)
		)
		(property "MPN" "ERJ2GE0R00X"
			(at 0 0 0)
			(unlocked yes)
			(layer "B.Fab")
			(hide yes)
			(effects
				(font
					(size 1 1)
					(thickness 0.15)
				)
				(justify mirror)
			)
		)
		(property "Manufacturer" "Panasonic"
			(at 0 0 0)
			(unlocked yes)
			(layer "B.Fab")
			(hide yes)
			(effects
				(font
					(size 1 1)
					(thickness 0.15)
				)
				(justify mirror)
			)
		)
		(property "License" "Apache-2.0"
			(at 0 0 0)
			(unlocked yes)
			(layer "B.Fab")
			(hide yes)
			(effects
				(font
					(size 1 1)
					(thickness 0.15)
				)
				(justify mirror)
			)
		)
		(property "Author" "Antmicro"
			(at 0 0 0)
			(unlocked yes)
			(layer "B.Fab")
			(hide yes)
			(effects
				(font
					(size 1 1)
					(thickness 0.15)
				)
				(justify mirror)
			)
		)
		(property "Val" "0R"
			(at 0 0 0)
			(unlocked yes)
			(layer "B.Fab")
			(hide yes)
			(effects
				(font
					(size 1 1)
					(thickness 0.15)
				)
				(justify mirror)
			)
		)
		(property "Tolerance" "~"
			(at 0 0 0)
			(unlocked yes)
			(layer "B.Fab")
			(hide yes)
			(effects
				(font
					(size 1 1)
					(thickness 0.15)
				)
				(justify mirror)
			)
		)
		(property "Current" "1A"
			(at 0 0 0)
			(unlocked yes)
			(layer "B.Fab")
			(hide yes)
			(effects
				(font
					(size 1 1)
					(thickness 0.15)
				)
				(justify mirror)
			)
		)
		(sheetname "/X710-AT2 10GbE/")
		(sheetfile "x710-at2-10gbe.kicad_sch")
		(attr smd)
		(fp_rect
			(start -0.925 0.47)
			(end 0.925 -0.47)
			(stroke
				(width 0.05)
				(type default)
			)
			(fill no)
			(layer "B.CrtYd")
		)
		(fp_rect
			(start -0.5 0.25)
			(end 0.5 -0.25)
			(stroke
				(width 0.15)
				(type solid)
			)
			(fill no)
			(layer "B.Fab")
		)
		(fp_text user "${REFERENCE}"
			(at -0.95 -3.168 180)
			(layer "B.Fab")
			(effects
				(font
					(size 0.7 0.7)
					(thickness 0.15)
				)
				(justify left bottom mirror)
			)
		)
		(fp_text user "License: Apache-2.0"
			(at -0.95 -5.169 180)
			(layer "B.Fab")
			(effects
				(font
					(size 0.7 0.7)
					(thickness 0.15)
				)
				(justify left bottom mirror)
			)
		)
		(fp_text user "Author: Antmicro"
			(at -0.95 -4.169 180)
			(layer "B.Fab")
			(effects
				(font
					(size 0.7 0.7)
					(thickness 0.15)
				)
				(justify left bottom mirror)
			)
		)
		(pad "1" smd roundrect
			(at -0.48 0)
			(size 0.59 0.64)
			(layers "B.Cu" "B.Mask" "B.Paste")
			(roundrect_rratio 0.25)
			(net 111 "/X710-AT2 10GbE/~{P0_INT}")
			(pintype "passive")
		)
		(pad "2" smd roundrect
			(at 0.48 0)
			(size 0.59 0.64)
			(layers "B.Cu" "B.Mask" "B.Paste")
			(roundrect_rratio 0.25)
			(net 121 "/X710-AT2 10GbE/~{P0_INT_R}")
			(pintype "passive")
		)
	)
	(footprint "antmicro-footprints:C_0402_1005Metric"
		(layer "B.Cu")
		(at 130.449999 127.85 90)
		(descr "Capacitor SMD 0402")
		(tags "capacitor SMD 0402")
		(property "Reference" "C75"
			(at 7.700002 21.900002 270)
			(layer "B.SilkS")
			(effects
				(font
					(size 0.7 0.7)
					(thickness 0.15)
				)
				(justify mirror)
			)
		)
		(property "Value" "C_1u_0402"
			(at -1.022927 -2.155213 270)
			(layer "B.Fab")
			(effects
				(font
					(size 0.7 0.7)
					(thickness 0.15)
				)
				(justify left bottom mirror)
			)
		)
		(property "Datasheet" "https://product.tdk.com/en/search/capacitor/ceramic/mlcc/info?part_no=C1005X6S1A105K050BC"
			(at 0 0 270)
			(layer "B.Fab")
			(hide yes)
			(effects
				(font
					(size 1.27 1.27)
					(thickness 0.15)
				)
				(justify mirror)
			)
		)
		(property "Description" "SMD Multilayer Ceramic Capacitor, 1 µF, 10 V, 0402 [1005 Metric], ± 10%, X6S, C"
			(at 0 0 270)
			(layer "B.Fab")
			(hide yes)
			(effects
				(font
					(size 1.27 1.27)
					(thickness 0.15)
				)
				(justify mirror)
			)
		)
		(property "MPN" "C1005X6S1A105K050BC"
			(at 0 0 90)
			(unlocked yes)
			(layer "B.Fab")
			(hide yes)
			(effects
				(font
					(size 1 1)
					(thickness 0.15)
				)
				(justify mirror)
			)
		)
		(property "Manufacturer" "TDK"
			(at 0 0 90)
			(unlocked yes)
			(layer "B.Fab")
			(hide yes)
			(effects
				(font
					(size 1 1)
					(thickness 0.15)
				)
				(justify mirror)
			)
		)
		(property "License" "Apache-2.0"
			(at 0 0 90)
			(unlocked yes)
			(layer "B.Fab")
			(hide yes)
			(effects
				(font
					(size 1 1)
					(thickness 0.15)
				)
				(justify mirror)
			)
		)
		(property "Val" "1u"
			(at 0 0 90)
			(unlocked yes)
			(layer "B.Fab")
			(hide yes)
			(effects
				(font
					(size 1 1)
					(thickness 0.15)
				)
				(justify mirror)
			)
		)
		(property "Voltage" ""
			(at 0 0 90)
			(unlocked yes)
			(layer "B.Fab")
			(hide yes)
			(effects
				(font
					(size 1 1)
					(thickness 0.15)
				)
				(justify mirror)
			)
		)
		(property "Dielectric" ""
			(at 0 0 90)
			(unlocked yes)
			(layer "B.Fab")
			(hide yes)
			(effects
				(font
					(size 1 1)
					(thickness 0.15)
				)
				(justify mirror)
			)
		)
		(property "Author" "Antmicro"
			(at 0 0 90)
			(unlocked yes)
			(layer "B.Fab")
			(hide yes)
			(effects
				(font
					(size 1 1)
					(thickness 0.15)
				)
				(justify mirror)
			)
		)
		(sheetname "/TB Controller - Power/")
		(sheetfile "tb-power.kicad_sch")
		(attr smd)
		(fp_rect
			(start -0.925 0.47)
			(end 0.925 -0.47)
			(stroke
				(width 0.05)
				(type default)
			)
			(fill no)
			(layer "B.CrtYd")
		)
		(fp_line
			(start 0.504 -0.248)
			(end -0.494 -0.248)
			(stroke
				(width 0.15)
				(type solid)
			)
			(layer "B.Fab")
		)
		(fp_line
			(start -0.494 -0.248)
			(end -0.494 0.25)
			(stroke
				(width 0.15)
				(type solid)
			)
			(layer "B.Fab")
		)
		(fp_line
			(start 0.504 0.25)
			(end 0.504 -0.248)
			(stroke
				(width 0.15)
				(type solid)
			)
			(layer "B.Fab")
		)
		(fp_line
			(start -0.494 0.25)
			(end 0.504 0.25)
			(stroke
				(width 0.15)
				(type solid)
			)
			(layer "B.Fab")
		)
		(fp_text user "Author: Antmicro"
			(at -0.939 -3.399 270)
			(layer "B.Fab")
			(effects
				(font
					(size 0.7 0.7)
					(thickness 0.15)
				)
				(justify left bottom mirror)
			)
		)
		(fp_text user "${REFERENCE}"
			(at -0.939 -4.599 270)
			(layer "B.Fab")
			(effects
				(font
					(size 0.7 0.7)
					(thickness 0.15)
				)
				(justify left bottom mirror)
			)
		)
		(fp_text user "License: Apache-2.0"
			(at -0.939 -5.799 270)
			(layer "B.Fab")
			(effects
				(font
					(size 0.7 0.7)
					(thickness 0.15)
				)
				(justify left bottom mirror)
			)
		)
		(pad "1" smd roundrect
			(at -0.48 0 90)
			(size 0.59 0.64)
			(layers "B.Cu" "B.Mask" "B.Paste")
			(roundrect_rratio 0.25)
			(net 23 "GND")
			(pintype "passive")
		)
		(pad "2" smd roundrect
			(at 0.48 0 90)
			(size 0.59 0.64)
			(layers "B.Cu" "B.Mask" "B.Paste")
			(roundrect_rratio 0.25)
			(net 57 "+3V3_TB")
			(pintype "passive")
		)
	)
	(footprint "antmicro-footprints:R_0402_1005Metric"
		(layer "B.Cu")
		(at 125.222 119.951 -90)
		(descr "Resistor SMD 0402")
		(tags "resistor SMD 0402")
		(property "Reference" "R40"
			(at -7.700002 -21.900002 90)
			(layer "B.SilkS")
			(effects
				(font
					(size 0.7 0.7)
					(thickness 0.15)
				)
				(justify mirror)
			)
		)
		(property "Value" "R_14k_0402"
			(at -1.011843 -1.772047 90)
			(layer "B.Fab")
			(effects
				(font
					(size 0.7 0.7)
					(thickness 0.15)
				)
				(justify left bottom mirror)
			)
		)
		(property "Datasheet" "https://www.bourns.com/docs/product-datasheets/cr.pdf"
			(at 0 0 90)
			(layer "B.Fab")
			(hide yes)
			(effects
				(font
					(size 1.27 1.27)
					(thickness 0.15)
				)
				(justify mirror)
			)
		)
		(property "Description" "SMD Chip Resistor, 14 kohm, ± 1%, 100 mW, 0402 [1005 Metric], Thick Film, Precision"
			(at 0 0 90)
			(layer "B.Fab")
			(hide yes)
			(effects
				(font
					(size 1.27 1.27)
					(thickness 0.15)
				)
				(justify mirror)
			)
		)
		(property "MPN" "CR0402-FX-1402GLF"
			(at 0 0 270)
			(unlocked yes)
			(layer "B.Fab")
			(hide yes)
			(effects
				(font
					(size 1 1)
					(thickness 0.15)
				)
				(justify mirror)
			)
		)
		(property "Manufacturer" "Bourns"
			(at 0 0 270)
			(unlocked yes)
			(layer "B.Fab")
			(hide yes)
			(effects
				(font
					(size 1 1)
					(thickness 0.15)
				)
				(justify mirror)
			)
		)
		(property "License" "Apache-2.0"
			(at 0 0 270)
			(unlocked yes)
			(layer "B.Fab")
			(hide yes)
			(effects
				(font
					(size 1 1)
					(thickness 0.15)
				)
				(justify mirror)
			)
		)
		(property "Val" "14k"
			(at 0 0 270)
			(unlocked yes)
			(layer "B.Fab")
			(hide yes)
			(effects
				(font
					(size 1 1)
					(thickness 0.15)
				)
				(justify mirror)
			)
		)
		(property "Tolerance" "1%"
			(at 0 0 270)
			(unlocked yes)
			(layer "B.Fab")
			(hide yes)
			(effects
				(font
					(size 1 1)
					(thickness 0.15)
				)
				(justify mirror)
			)
		)
		(property "Author" "Antmicro"
			(at 0 0 270)
			(unlocked yes)
			(layer "B.Fab")
			(hide yes)
			(effects
				(font
					(size 1 1)
					(thickness 0.15)
				)
				(justify mirror)
			)
		)
		(sheetname "/TB Controller/")
		(sheetfile "tb.kicad_sch")
		(attr smd dnp)
		(fp_rect
			(start -0.925 0.47)
			(end 0.925 -0.47)
			(stroke
				(width 0.05)
				(type default)
			)
			(fill no)
			(layer "B.CrtYd")
		)
		(fp_rect
			(start -0.5 0.25)
			(end 0.5 -0.25)
			(stroke
				(width 0.15)
				(type solid)
			)
			(fill no)
			(layer "B.Fab")
		)
		(fp_text user "${REFERENCE}"
			(at -0.95 -3.168 90)
			(layer "B.Fab")
			(effects
				(font
					(size 0.7 0.7)
					(thickness 0.15)
				)
				(justify left bottom mirror)
			)
		)
		(fp_text user "License: Apache-2.0"
			(at -0.95 -5.169 90)
			(layer "B.Fab")
			(effects
				(font
					(size 0.7 0.7)
					(thickness 0.15)
				)
				(justify left bottom mirror)
			)
		)
		(fp_text user "Author: Antmicro"
			(at -0.95 -4.169 90)
			(layer "B.Fab")
			(effects
				(font
					(size 0.7 0.7)
					(thickness 0.15)
				)
				(justify left bottom mirror)
			)
		)
		(pad "1" smd roundrect
			(at -0.48 0 270)
			(size 0.59 0.64)
			(layers "B.Cu" "B.Mask" "B.Paste")
			(roundrect_rratio 0.25)
			(net 23 "GND")
			(pintype "passive")
		)
		(pad "2" smd roundrect
			(at 0.48 0 270)
			(size 0.59 0.64)
			(layers "B.Cu" "B.Mask" "B.Paste")
			(roundrect_rratio 0.25)
			(net 223 "Net-(U4C-DPSNK_RBIAS)")
			(pintype "passive")
		)
	)
	(footprint "antmicro-footprints:R_0402_1005Metric"
		(layer "B.Cu")
		(at 154.481866 76.760116 90)
		(descr "Resistor SMD 0402")
		(tags "resistor SMD 0402")
		(property "Reference" "R153"
			(at -8.839884 21.618136 270)
			(layer "B.SilkS")
			(effects
				(font
					(size 0.7 0.7)
					(thickness 0.15)
				)
				(justify mirror)
			)
		)
		(property "Value" "R_1k_0402"
			(at -1.011843 -1.772047 270)
			(layer "B.Fab")
			(effects
				(font
					(size 0.7 0.7)
					(thickness 0.15)
				)
				(justify left bottom mirror)
			)
		)
		(property "Datasheet" "https://www.bourns.com/docs/product-datasheets/cr.pdf"
			(at 0 0 270)
			(layer "B.Fab")
			(hide yes)
			(effects
				(font
					(size 1.27 1.27)
					(thickness 0.15)
				)
				(justify mirror)
			)
		)
		(property "Description" "SMD Chip Resistor, 1 kohm, ± 1%, 63 mW, 0402 [1005 Metric], Thick Film, General Purpose"
			(at 0 0 270)
			(layer "B.Fab")
			(hide yes)
			(effects
				(font
					(size 1.27 1.27)
					(thickness 0.15)
				)
				(justify mirror)
			)
		)
		(property "MPN" "CR0402-FX-1001GLF"
			(at 0 0 90)
			(unlocked yes)
			(layer "B.Fab")
			(hide yes)
			(effects
				(font
					(size 1 1)
					(thickness 0.15)
				)
				(justify mirror)
			)
		)
		(property "Manufacturer" "Bourns"
			(at 0 0 90)
			(unlocked yes)
			(layer "B.Fab")
			(hide yes)
			(effects
				(font
					(size 1 1)
					(thickness 0.15)
				)
				(justify mirror)
			)
		)
		(property "License" "Apache-2.0"
			(at 0 0 90)
			(unlocked yes)
			(layer "B.Fab")
			(hide yes)
			(effects
				(font
					(size 1 1)
					(thickness 0.15)
				)
				(justify mirror)
			)
		)
		(property "Author" "Antmicro"
			(at 0 0 90)
			(unlocked yes)
			(layer "B.Fab")
			(hide yes)
			(effects
				(font
					(size 1 1)
					(thickness 0.15)
				)
				(justify mirror)
			)
		)
		(property "Val" "1k"
			(at 0 0 90)
			(unlocked yes)
			(layer "B.Fab")
			(hide yes)
			(effects
				(font
					(size 1 1)
					(thickness 0.15)
				)
				(justify mirror)
			)
		)
		(property "Tolerance" "1%"
			(at 0 0 90)
			(unlocked yes)
			(layer "B.Fab")
			(hide yes)
			(effects
				(font
					(size 1 1)
					(thickness 0.15)
				)
				(justify mirror)
			)
		)
		(sheetname "/X710-AT2 Misc/")
		(sheetfile "x710-at2-mics.kicad_sch")
		(attr smd)
		(fp_rect
			(start -0.925 0.47)
			(end 0.925 -0.47)
			(stroke
				(width 0.05)
				(type default)
			)
			(fill no)
			(layer "B.CrtYd")
		)
		(fp_rect
			(start -0.5 0.25)
			(end 0.5 -0.25)
			(stroke
				(width 0.15)
				(type solid)
			)
			(fill no)
			(layer "B.Fab")
		)
		(fp_text user "Author: Antmicro"
			(at -0.95 -4.169 270)
			(layer "B.Fab")
			(effects
				(font
					(size 0.7 0.7)
					(thickness 0.15)
				)
				(justify left bottom mirror)
			)
		)
		(fp_text user "${REFERENCE}"
			(at -0.95 -3.168 270)
			(layer "B.Fab")
			(effects
				(font
					(size 0.7 0.7)
					(thickness 0.15)
				)
				(justify left bottom mirror)
			)
		)
		(fp_text user "License: Apache-2.0"
			(at -0.95 -5.169 270)
			(layer "B.Fab")
			(effects
				(font
					(size 0.7 0.7)
					(thickness 0.15)
				)
				(justify left bottom mirror)
			)
		)
		(pad "1" smd roundrect
			(at -0.48 0 90)
			(size 0.59 0.64)
			(layers "B.Cu" "B.Mask" "B.Paste")
			(roundrect_rratio 0.25)
			(net 23 "GND")
			(pintype "passive")
		)
		(pad "2" smd roundrect
			(at 0.48 0 90)
			(size 0.59 0.64)
			(layers "B.Cu" "B.Mask" "B.Paste")
			(roundrect_rratio 0.25)
			(net 87 "/X710-AT2 Misc/RSVD_J11_VSS")
			(pintype "passive")
		)
	)
	(footprint "antmicro-footprints:C_0402_1005Metric"
		(layer "B.Cu")
		(at 138.35 137.599999 180)
		(descr "Capacitor SMD 0402")
		(tags "capacitor SMD 0402")
		(property "Reference" "C12"
			(at -19.525001 8.1 0)
			(layer "B.SilkS")
			(effects
				(font
					(size 0.7 0.7)
					(thickness 0.15)
				)
				(justify mirror)
			)
		)
		(property "Value" "C_4u7_25V_0402"
			(at -1.022927 -2.155213 0)
			(layer "B.Fab")
			(effects
				(font
					(size 0.7 0.7)
					(thickness 0.15)
				)
				(justify left bottom mirror)
			)
		)
		(property "Datasheet" "https://www.murata.com/products/productdetail?partno=GRM155C61E475ME15%23"
			(at 0 0 0)
			(layer "B.Fab")
			(hide yes)
			(effects
				(font
					(size 1.27 1.27)
					(thickness 0.15)
				)
				(justify mirror)
			)
		)
		(property "Description" "SMD Multilayer Ceramic Capacitor"
			(at 0 0 0)
			(layer "B.Fab")
			(hide yes)
			(effects
				(font
					(size 1.27 1.27)
					(thickness 0.15)
				)
				(justify mirror)
			)
		)
		(property "MPN" "GRM155C61E475ME15J"
			(at 0 0 180)
			(unlocked yes)
			(layer "B.Fab")
			(hide yes)
			(effects
				(font
					(size 1 1)
					(thickness 0.15)
				)
				(justify mirror)
			)
		)
		(property "Manufacturer" "Murata"
			(at 0 0 180)
			(unlocked yes)
			(layer "B.Fab")
			(hide yes)
			(effects
				(font
					(size 1 1)
					(thickness 0.15)
				)
				(justify mirror)
			)
		)
		(property "License" "Apache-2.0"
			(at 0 0 180)
			(unlocked yes)
			(layer "B.Fab")
			(hide yes)
			(effects
				(font
					(size 1 1)
					(thickness 0.15)
				)
				(justify mirror)
			)
		)
		(property "Val" "4u7"
			(at 0 0 180)
			(unlocked yes)
			(layer "B.Fab")
			(hide yes)
			(effects
				(font
					(size 1 1)
					(thickness 0.15)
				)
				(justify mirror)
			)
		)
		(property "Voltage" "25V"
			(at 0 0 180)
			(unlocked yes)
			(layer "B.Fab")
			(hide yes)
			(effects
				(font
					(size 1 1)
					(thickness 0.15)
				)
				(justify mirror)
			)
		)
		(property "Dielectric" "X5S"
			(at 0 0 180)
			(unlocked yes)
			(layer "B.Fab")
			(hide yes)
			(effects
				(font
					(size 1 1)
					(thickness 0.15)
				)
				(justify mirror)
			)
		)
		(property "Author" "Antmicro"
			(at 0 0 180)
			(unlocked yes)
			(layer "B.Fab")
			(hide yes)
			(effects
				(font
					(size 1 1)
					(thickness 0.15)
				)
				(justify mirror)
			)
		)
		(sheetname "/PD and TB DC-DC/")
		(sheetfile "PD_and_TB_DC_DC.kicad_sch")
		(attr smd)
		(fp_rect
			(start -0.925 0.47)
			(end 0.925 -0.47)
			(stroke
				(width 0.05)
				(type default)
			)
			(fill no)
			(layer "B.CrtYd")
		)
		(fp_line
			(start 0.504 0.25)
			(end 0.504 -0.248)
			(stroke
				(width 0.15)
				(type solid)
			)
			(layer "B.Fab")
		)
		(fp_line
			(start 0.504 -0.248)
			(end -0.494 -0.248)
			(stroke
				(width 0.15)
				(type solid)
			)
			(layer "B.Fab")
		)
		(fp_line
			(start -0.494 0.25)
			(end 0.504 0.25)
			(stroke
				(width 0.15)
				(type solid)
			)
			(layer "B.Fab")
		)
		(fp_line
			(start -0.494 -0.248)
			(end -0.494 0.25)
			(stroke
				(width 0.15)
				(type solid)
			)
			(layer "B.Fab")
		)
		(fp_text user "Author: Antmicro"
			(at -0.939 -3.399 0)
			(layer "B.Fab")
			(effects
				(font
					(size 0.7 0.7)
					(thickness 0.15)
				)
				(justify left bottom mirror)
			)
		)
		(fp_text user "${REFERENCE}"
			(at -0.939 -4.599 0)
			(layer "B.Fab")
			(effects
				(font
					(size 0.7 0.7)
					(thickness 0.15)
				)
				(justify left bottom mirror)
			)
		)
		(fp_text user "License: Apache-2.0"
			(at -0.939 -5.799 0)
			(layer "B.Fab")
			(effects
				(font
					(size 0.7 0.7)
					(thickness 0.15)
				)
				(justify left bottom mirror)
			)
		)
		(pad "1" smd roundrect
			(at -0.48 0 180)
			(size 0.59 0.64)
			(layers "B.Cu" "B.Mask" "B.Paste")
			(roundrect_rratio 0.25)
			(net 23 "GND")
			(pintype "passive")
		)
		(pad "2" smd roundrect
			(at 0.48 0 180)
			(size 0.59 0.64)
			(layers "B.Cu" "B.Mask" "B.Paste")
			(roundrect_rratio 0.25)
			(net 170 "PP_HV")
			(pintype "passive")
		)
	)
	(footprint "antmicro-footprints:R_0402_1005Metric"
		(layer "B.Cu")
		(at 140.6 117.149997)
		(descr "Resistor SMD 0402")
		(tags "resistor SMD 0402")
		(property "Reference" "R62"
			(at 19.525001 -7.450001 180)
			(layer "B.SilkS")
			(effects
				(font
					(size 0.7 0.7)
					(thickness 0.15)
				)
				(justify mirror)
			)
		)
		(property "Value" "R_10k_0402"
			(at -1.011843 -1.772047 180)
			(layer "B.Fab")
			(effects
				(font
					(size 0.7 0.7)
					(thickness 0.15)
				)
				(justify left bottom mirror)
			)
		)
		(property "Datasheet" "https://www.bourns.com/docs/product-datasheets/cr.pdf"
			(at 0 0 180)
			(layer "B.Fab")
			(hide yes)
			(effects
				(font
					(size 1.27 1.27)
					(thickness 0.15)
				)
				(justify mirror)
			)
		)
		(property "Description" "SMD Chip Resistor, 10 kohm, ± 1%, 62.5 mW, 0402 [1005 Metric], Thick Film, General Purpose"
			(at 0 0 180)
			(layer "B.Fab")
			(hide yes)
			(effects
				(font
					(size 1.27 1.27)
					(thickness 0.15)
				)
				(justify mirror)
			)
		)
		(property "MPN" "CR0402-FX-1002GLF"
			(at 0 0 0)
			(unlocked yes)
			(layer "B.Fab")
			(hide yes)
			(effects
				(font
					(size 1 1)
					(thickness 0.15)
				)
				(justify mirror)
			)
		)
		(property "Manufacturer" "Bourns"
			(at 0 0 0)
			(unlocked yes)
			(layer "B.Fab")
			(hide yes)
			(effects
				(font
					(size 1 1)
					(thickness 0.15)
				)
				(justify mirror)
			)
		)
		(property "License" "Apache-2.0"
			(at 0 0 0)
			(unlocked yes)
			(layer "B.Fab")
			(hide yes)
			(effects
				(font
					(size 1 1)
					(thickness 0.15)
				)
				(justify mirror)
			)
		)
		(property "Val" "10k"
			(at 0 0 0)
			(unlocked yes)
			(layer "B.Fab")
			(hide yes)
			(effects
				(font
					(size 1 1)
					(thickness 0.15)
				)
				(justify mirror)
			)
		)
		(property "Tolerance" "1%"
			(at 0 0 0)
			(unlocked yes)
			(layer "B.Fab")
			(hide yes)
			(effects
				(font
					(size 1 1)
					(thickness 0.15)
				)
				(justify mirror)
			)
		)
		(property "Author" "Antmicro"
			(at 0 0 0)
			(unlocked yes)
			(layer "B.Fab")
			(hide yes)
			(effects
				(font
					(size 1 1)
					(thickness 0.15)
				)
				(justify mirror)
			)
		)
		(sheetname "/TB Controller/")
		(sheetfile "tb.kicad_sch")
		(attr smd)
		(fp_rect
			(start -0.925 0.47)
			(end 0.925 -0.47)
			(stroke
				(width 0.05)
				(type default)
			)
			(fill no)
			(layer "B.CrtYd")
		)
		(fp_rect
			(start -0.5 0.25)
			(end 0.5 -0.25)
			(stroke
				(width 0.15)
				(type solid)
			)
			(fill no)
			(layer "B.Fab")
		)
		(fp_text user "${REFERENCE}"
			(at -0.95 -3.168 180)
			(layer "B.Fab")
			(effects
				(font
					(size 0.7 0.7)
					(thickness 0.15)
				)
				(justify left bottom mirror)
			)
		)
		(fp_text user "License: Apache-2.0"
			(at -0.95 -5.169 180)
			(layer "B.Fab")
			(effects
				(font
					(size 0.7 0.7)
					(thickness 0.15)
				)
				(justify left bottom mirror)
			)
		)
		(fp_text user "Author: Antmicro"
			(at -0.95 -4.169 180)
			(layer "B.Fab")
			(effects
				(font
					(size 0.7 0.7)
					(thickness 0.15)
				)
				(justify left bottom mirror)
			)
		)
		(pad "1" smd roundrect
			(at -0.48 0)
			(size 0.59 0.64)
			(layers "B.Cu" "B.Mask" "B.Paste")
			(roundrect_rratio 0.25)
			(net 57 "+3V3_TB")
			(pintype "passive")
		)
		(pad "2" smd roundrect
			(at 0.48 0)
			(size 0.59 0.64)
			(layers "B.Cu" "B.Mask" "B.Paste")
			(roundrect_rratio 0.25)
			(net 224 "Net-(U4D-TDI)")
			(pintype "passive")
		)
	)
	(footprint "antmicro-footprints:C_0402_1005Metric"
		(layer "B.Cu")
		(at 130.45 120.049999 -90)
		(descr "Capacitor SMD 0402")
		(tags "capacitor SMD 0402")
		(property "Reference" "C67"
			(at -7.700002 -21.900002 90)
			(layer "B.SilkS")
			(effects
				(font
					(size 0.7 0.7)
					(thickness 0.15)
				)
				(justify mirror)
			)
		)
		(property "Value" "C_1u_0402"
			(at -1.022927 -2.155213 90)
			(layer "B.Fab")
			(effects
				(font
					(size 0.7 0.7)
					(thickness 0.15)
				)
				(justify left bottom mirror)
			)
		)
		(property "Datasheet" "https://product.tdk.com/en/search/capacitor/ceramic/mlcc/info?part_no=C1005X6S1A105K050BC"
			(at 0 0 90)
			(layer "B.Fab")
			(hide yes)
			(effects
				(font
					(size 1.27 1.27)
					(thickness 0.15)
				)
				(justify mirror)
			)
		)
		(property "Description" "SMD Multilayer Ceramic Capacitor, 1 µF, 10 V, 0402 [1005 Metric], ± 10%, X6S, C"
			(at 0 0 90)
			(layer "B.Fab")
			(hide yes)
			(effects
				(font
					(size 1.27 1.27)
					(thickness 0.15)
				)
				(justify mirror)
			)
		)
		(property "MPN" "C1005X6S1A105K050BC"
			(at 0 0 270)
			(unlocked yes)
			(layer "B.Fab")
			(hide yes)
			(effects
				(font
					(size 1 1)
					(thickness 0.15)
				)
				(justify mirror)
			)
		)
		(property "Manufacturer" "TDK"
			(at 0 0 270)
			(unlocked yes)
			(layer "B.Fab")
			(hide yes)
			(effects
				(font
					(size 1 1)
					(thickness 0.15)
				)
				(justify mirror)
			)
		)
		(property "License" "Apache-2.0"
			(at 0 0 270)
			(unlocked yes)
			(layer "B.Fab")
			(hide yes)
			(effects
				(font
					(size 1 1)
					(thickness 0.15)
				)
				(justify mirror)
			)
		)
		(property "Val" "1u"
			(at 0 0 270)
			(unlocked yes)
			(layer "B.Fab")
			(hide yes)
			(effects
				(font
					(size 1 1)
					(thickness 0.15)
				)
				(justify mirror)
			)
		)
		(property "Voltage" ""
			(at 0 0 270)
			(unlocked yes)
			(layer "B.Fab")
			(hide yes)
			(effects
				(font
					(size 1 1)
					(thickness 0.15)
				)
				(justify mirror)
			)
		)
		(property "Dielectric" ""
			(at 0 0 270)
			(unlocked yes)
			(layer "B.Fab")
			(hide yes)
			(effects
				(font
					(size 1 1)
					(thickness 0.15)
				)
				(justify mirror)
			)
		)
		(property "Author" "Antmicro"
			(at 0 0 270)
			(unlocked yes)
			(layer "B.Fab")
			(hide yes)
			(effects
				(font
					(size 1 1)
					(thickness 0.15)
				)
				(justify mirror)
			)
		)
		(sheetname "/TB Controller - Power/")
		(sheetfile "tb-power.kicad_sch")
		(attr smd)
		(fp_rect
			(start -0.925 0.47)
			(end 0.925 -0.47)
			(stroke
				(width 0.05)
				(type default)
			)
			(fill no)
			(layer "B.CrtYd")
		)
		(fp_line
			(start -0.494 0.25)
			(end 0.504 0.25)
			(stroke
				(width 0.15)
				(type solid)
			)
			(layer "B.Fab")
		)
		(fp_line
			(start 0.504 0.25)
			(end 0.504 -0.248)
			(stroke
				(width 0.15)
				(type solid)
			)
			(layer "B.Fab")
		)
		(fp_line
			(start -0.494 -0.248)
			(end -0.494 0.25)
			(stroke
				(width 0.15)
				(type solid)
			)
			(layer "B.Fab")
		)
		(fp_line
			(start 0.504 -0.248)
			(end -0.494 -0.248)
			(stroke
				(width 0.15)
				(type solid)
			)
			(layer "B.Fab")
		)
		(fp_text user "${REFERENCE}"
			(at -0.939 -4.599 90)
			(layer "B.Fab")
			(effects
				(font
					(size 0.7 0.7)
					(thickness 0.15)
				)
				(justify left bottom mirror)
			)
		)
		(fp_text user "Author: Antmicro"
			(at -0.939 -3.399 90)
			(layer "B.Fab")
			(effects
				(font
					(size 0.7 0.7)
					(thickness 0.15)
				)
				(justify left bottom mirror)
			)
		)
		(fp_text user "License: Apache-2.0"
			(at -0.939 -5.799 90)
			(layer "B.Fab")
			(effects
				(font
					(size 0.7 0.7)
					(thickness 0.15)
				)
				(justify left bottom mirror)
			)
		)
		(pad "1" smd roundrect
			(at -0.48 0 270)
			(size 0.59 0.64)
			(layers "B.Cu" "B.Mask" "B.Paste")
			(roundrect_rratio 0.25)
			(net 23 "GND")
			(pintype "passive")
		)
		(pad "2" smd roundrect
			(at 0.48 0 270)
			(size 0.59 0.64)
			(layers "B.Cu" "B.Mask" "B.Paste")
			(roundrect_rratio 0.25)
			(net 404 "Net-(C58-Pad2)")
			(pintype "passive")
		)
	)
	(footprint "antmicro-footprints:C_0402_1005Metric"
		(layer "B.Cu")
		(at 149.331866 76.260117 180)
		(descr "Capacitor SMD 0402")
		(tags "capacitor SMD 0402")
		(property "Reference" "C230"
			(at -19.468135 -9.464883 0)
			(layer "B.SilkS")
			(effects
				(font
					(size 0.7 0.7)
					(thickness 0.15)
				)
				(justify mirror)
			)
		)
		(property "Value" "C_1u_25V_0402"
			(at -1.022927 -2.155213 0)
			(layer "B.Fab")
			(effects
				(font
					(size 0.7 0.7)
					(thickness 0.15)
				)
				(justify left bottom mirror)
			)
		)
		(property "Datasheet" "https://www.murata.com/products/productdetail?partno=GRM155R61E105KE11%23"
			(at 0 0 0)
			(layer "B.Fab")
			(hide yes)
			(effects
				(font
					(size 1.27 1.27)
					(thickness 0.15)
				)
				(justify mirror)
			)
		)
		(property "Description" "SMD Multilayer Ceramic Capacitor, 1 µF, 25 V, 0402 [1005 Metric], ± 10%, X5R, GRM Series"
			(at 0 0 0)
			(layer "B.Fab")
			(hide yes)
			(effects
				(font
					(size 1.27 1.27)
					(thickness 0.15)
				)
				(justify mirror)
			)
		)
		(property "MPN" "GRM155R61E105KE11J"
			(at 0 0 180)
			(unlocked yes)
			(layer "B.Fab")
			(hide yes)
			(effects
				(font
					(size 1 1)
					(thickness 0.15)
				)
				(justify mirror)
			)
		)
		(property "Manufacturer" "Murata"
			(at 0 0 180)
			(unlocked yes)
			(layer "B.Fab")
			(hide yes)
			(effects
				(font
					(size 1 1)
					(thickness 0.15)
				)
				(justify mirror)
			)
		)
		(property "License" "Apache-2.0"
			(at 0 0 180)
			(unlocked yes)
			(layer "B.Fab")
			(hide yes)
			(effects
				(font
					(size 1 1)
					(thickness 0.15)
				)
				(justify mirror)
			)
		)
		(property "Author" "Antmicro"
			(at 0 0 180)
			(unlocked yes)
			(layer "B.Fab")
			(hide yes)
			(effects
				(font
					(size 1 1)
					(thickness 0.15)
				)
				(justify mirror)
			)
		)
		(property "Val" "1u"
			(at 0 0 180)
			(unlocked yes)
			(layer "B.Fab")
			(hide yes)
			(effects
				(font
					(size 1 1)
					(thickness 0.15)
				)
				(justify mirror)
			)
		)
		(property "Voltage" "25V"
			(at 0 0 180)
			(unlocked yes)
			(layer "B.Fab")
			(hide yes)
			(effects
				(font
					(size 1 1)
					(thickness 0.15)
				)
				(justify mirror)
			)
		)
		(property "Dielectric" "X5R"
			(at 0 0 180)
			(unlocked yes)
			(layer "B.Fab")
			(hide yes)
			(effects
				(font
					(size 1 1)
					(thickness 0.15)
				)
				(justify mirror)
			)
		)
		(sheetname "/X710-AT2 power/")
		(sheetfile "x710-at2-power.kicad_sch")
		(attr smd)
		(fp_rect
			(start -0.925 0.47)
			(end 0.925 -0.47)
			(stroke
				(width 0.05)
				(type default)
			)
			(fill no)
			(layer "B.CrtYd")
		)
		(fp_line
			(start 0.504 0.25)
			(end 0.504 -0.248)
			(stroke
				(width 0.15)
				(type solid)
			)
			(layer "B.Fab")
		)
		(fp_line
			(start 0.504 -0.248)
			(end -0.494 -0.248)
			(stroke
				(width 0.15)
				(type solid)
			)
			(layer "B.Fab")
		)
		(fp_line
			(start -0.494 0.25)
			(end 0.504 0.25)
			(stroke
				(width 0.15)
				(type solid)
			)
			(layer "B.Fab")
		)
		(fp_line
			(start -0.494 -0.248)
			(end -0.494 0.25)
			(stroke
				(width 0.15)
				(type solid)
			)
			(layer "B.Fab")
		)
		(fp_text user "Author: Antmicro"
			(at -0.939 -3.399 0)
			(layer "B.Fab")
			(effects
				(font
					(size 0.7 0.7)
					(thickness 0.15)
				)
				(justify left bottom mirror)
			)
		)
		(fp_text user "License: Apache-2.0"
			(at -0.939 -5.799 0)
			(layer "B.Fab")
			(effects
				(font
					(size 0.7 0.7)
					(thickness 0.15)
				)
				(justify left bottom mirror)
			)
		)
		(fp_text user "${REFERENCE}"
			(at -0.939 -4.599 0)
			(layer "B.Fab")
			(effects
				(font
					(size 0.7 0.7)
					(thickness 0.15)
				)
				(justify left bottom mirror)
			)
		)
		(pad "1" smd roundrect
			(at -0.48 0 180)
			(size 0.59 0.64)
			(layers "B.Cu" "B.Mask" "B.Paste")
			(roundrect_rratio 0.25)
			(net 23 "GND")
			(pintype "passive")
		)
		(pad "2" smd roundrect
			(at 0.48 0 180)
			(size 0.59 0.64)
			(layers "B.Cu" "B.Mask" "B.Paste")
			(roundrect_rratio 0.25)
			(net 7 "+3V3")
			(pintype "passive")
		)
	)
	(footprint "antmicro-footprints:C_0402_1005Metric"
		(layer "B.Cu")
		(at 124.599999 122.475001)
		(descr "Capacitor SMD 0402")
		(tags "capacitor SMD 0402")
		(property "Reference" "C71"
			(at 21.900002 -7.700002 180)
			(layer "B.SilkS")
			(effects
				(font
					(size 0.7 0.7)
					(thickness 0.15)
				)
				(justify mirror)
			)
		)
		(property "Value" "C_1u_0402"
			(at -1.022927 -2.155213 180)
			(layer "B.Fab")
			(effects
				(font
					(size 0.7 0.7)
					(thickness 0.15)
				)
				(justify left bottom mirror)
			)
		)
		(property "Datasheet" "https://product.tdk.com/en/search/capacitor/ceramic/mlcc/info?part_no=C1005X6S1A105K050BC"
			(at 0 0 180)
			(layer "B.Fab")
			(hide yes)
			(effects
				(font
					(size 1.27 1.27)
					(thickness 0.15)
				)
				(justify mirror)
			)
		)
		(property "Description" "SMD Multilayer Ceramic Capacitor, 1 µF, 10 V, 0402 [1005 Metric], ± 10%, X6S, C"
			(at 0 0 180)
			(layer "B.Fab")
			(hide yes)
			(effects
				(font
					(size 1.27 1.27)
					(thickness 0.15)
				)
				(justify mirror)
			)
		)
		(property "MPN" "C1005X6S1A105K050BC"
			(at 0 0 0)
			(unlocked yes)
			(layer "B.Fab")
			(hide yes)
			(effects
				(font
					(size 1 1)
					(thickness 0.15)
				)
				(justify mirror)
			)
		)
		(property "Manufacturer" "TDK"
			(at 0 0 0)
			(unlocked yes)
			(layer "B.Fab")
			(hide yes)
			(effects
				(font
					(size 1 1)
					(thickness 0.15)
				)
				(justify mirror)
			)
		)
		(property "License" "Apache-2.0"
			(at 0 0 0)
			(unlocked yes)
			(layer "B.Fab")
			(hide yes)
			(effects
				(font
					(size 1 1)
					(thickness 0.15)
				)
				(justify mirror)
			)
		)
		(property "Val" "1u"
			(at 0 0 0)
			(unlocked yes)
			(layer "B.Fab")
			(hide yes)
			(effects
				(font
					(size 1 1)
					(thickness 0.15)
				)
				(justify mirror)
			)
		)
		(property "Voltage" ""
			(at 0 0 0)
			(unlocked yes)
			(layer "B.Fab")
			(hide yes)
			(effects
				(font
					(size 1 1)
					(thickness 0.15)
				)
				(justify mirror)
			)
		)
		(property "Dielectric" ""
			(at 0 0 0)
			(unlocked yes)
			(layer "B.Fab")
			(hide yes)
			(effects
				(font
					(size 1 1)
					(thickness 0.15)
				)
				(justify mirror)
			)
		)
		(property "Author" "Antmicro"
			(at 0 0 0)
			(unlocked yes)
			(layer "B.Fab")
			(hide yes)
			(effects
				(font
					(size 1 1)
					(thickness 0.15)
				)
				(justify mirror)
			)
		)
		(sheetname "/TB Controller - Power/")
		(sheetfile "tb-power.kicad_sch")
		(attr smd)
		(fp_rect
			(start -0.925 0.47)
			(end 0.925 -0.47)
			(stroke
				(width 0.05)
				(type default)
			)
			(fill no)
			(layer "B.CrtYd")
		)
		(fp_line
			(start -0.494 -0.248)
			(end -0.494 0.25)
			(stroke
				(width 0.15)
				(type solid)
			)
			(layer "B.Fab")
		)
		(fp_line
			(start -0.494 0.25)
			(end 0.504 0.25)
			(stroke
				(width 0.15)
				(type solid)
			)
			(layer "B.Fab")
		)
		(fp_line
			(start 0.504 -0.248)
			(end -0.494 -0.248)
			(stroke
				(width 0.15)
				(type solid)
			)
			(layer "B.Fab")
		)
		(fp_line
			(start 0.504 0.25)
			(end 0.504 -0.248)
			(stroke
				(width 0.15)
				(type solid)
			)
			(layer "B.Fab")
		)
		(fp_text user "Author: Antmicro"
			(at -0.939 -3.399 180)
			(layer "B.Fab")
			(effects
				(font
					(size 0.7 0.7)
					(thickness 0.15)
				)
				(justify left bottom mirror)
			)
		)
		(fp_text user "${REFERENCE}"
			(at -0.939 -4.599 180)
			(layer "B.Fab")
			(effects
				(font
					(size 0.7 0.7)
					(thickness 0.15)
				)
				(justify left bottom mirror)
			)
		)
		(fp_text user "License: Apache-2.0"
			(at -0.939 -5.799 180)
			(layer "B.Fab")
			(effects
				(font
					(size 0.7 0.7)
					(thickness 0.15)
				)
				(justify left bottom mirror)
			)
		)
		(pad "1" smd roundrect
			(at -0.48 0)
			(size 0.59 0.64)
			(layers "B.Cu" "B.Mask" "B.Paste")
			(roundrect_rratio 0.25)
			(net 23 "GND")
			(pintype "passive")
		)
		(pad "2" smd roundrect
			(at 0.48 0)
			(size 0.59 0.64)
			(layers "B.Cu" "B.Mask" "B.Paste")
			(roundrect_rratio 0.25)
			(net 405 "Net-(C66-Pad2)")
			(pintype "passive")
		)
	)
	(footprint "antmicro-footprints:R_0402_1005Metric"
		(layer "B.Cu")
		(at 162.991867 69.5 -90)
		(descr "Resistor SMD 0402")
		(tags "resistor SMD 0402")
		(property "Reference" "R141"
			(at 2.25 0 90)
			(layer "B.SilkS")
			(effects
				(font
					(size 0.7 0.7)
					(thickness 0.15)
				)
				(justify mirror)
			)
		)
		(property "Value" "R_100R_0402"
			(at -1.011843 -1.772047 90)
			(layer "B.Fab")
			(effects
				(font
					(size 0.7 0.7)
					(thickness 0.15)
				)
				(justify left bottom mirror)
			)
		)
		(property "Datasheet" "https://www.bourns.com/docs/product-datasheets/cr.pdf"
			(at 0 0 90)
			(layer "B.Fab")
			(hide yes)
			(effects
				(font
					(size 1.27 1.27)
					(thickness 0.15)
				)
				(justify mirror)
			)
		)
		(property "Description" "SMD Chip Resistor, 100 ohm, ± 1%, 62.5 mW, 0402 [1005 Metric], Thick Film, General Purpose"
			(at 0 0 90)
			(layer "B.Fab")
			(hide yes)
			(effects
				(font
					(size 1.27 1.27)
					(thickness 0.15)
				)
				(justify mirror)
			)
		)
		(property "MPN" "CR0402-FX-1000GLF"
			(at 0 0 270)
			(unlocked yes)
			(layer "B.Fab")
			(hide yes)
			(effects
				(font
					(size 1 1)
					(thickness 0.15)
				)
				(justify mirror)
			)
		)
		(property "Manufacturer" "Bourns"
			(at 0 0 270)
			(unlocked yes)
			(layer "B.Fab")
			(hide yes)
			(effects
				(font
					(size 1 1)
					(thickness 0.15)
				)
				(justify mirror)
			)
		)
		(property "License" "Apache-2.0"
			(at 0 0 270)
			(unlocked yes)
			(layer "B.Fab")
			(hide yes)
			(effects
				(font
					(size 1 1)
					(thickness 0.15)
				)
				(justify mirror)
			)
		)
		(property "Author" "Antmicro"
			(at 0 0 270)
			(unlocked yes)
			(layer "B.Fab")
			(hide yes)
			(effects
				(font
					(size 1 1)
					(thickness 0.15)
				)
				(justify mirror)
			)
		)
		(property "Val" "100R"
			(at 0 0 270)
			(unlocked yes)
			(layer "B.Fab")
			(hide yes)
			(effects
				(font
					(size 1 1)
					(thickness 0.15)
				)
				(justify mirror)
			)
		)
		(property "Tolerance" "1%"
			(at 0 0 270)
			(unlocked yes)
			(layer "B.Fab")
			(hide yes)
			(effects
				(font
					(size 1 1)
					(thickness 0.15)
				)
				(justify mirror)
			)
		)
		(sheetname "/X710-AT2 Misc/")
		(sheetfile "x710-at2-mics.kicad_sch")
		(attr smd)
		(fp_rect
			(start -0.925 0.47)
			(end 0.925 -0.47)
			(stroke
				(width 0.05)
				(type default)
			)
			(fill no)
			(layer "B.CrtYd")
		)
		(fp_rect
			(start -0.5 0.25)
			(end 0.5 -0.25)
			(stroke
				(width 0.15)
				(type solid)
			)
			(fill no)
			(layer "B.Fab")
		)
		(fp_text user "${REFERENCE}"
			(at -0.95 -3.168 90)
			(layer "B.Fab")
			(effects
				(font
					(size 0.7 0.7)
					(thickness 0.15)
				)
				(justify left bottom mirror)
			)
		)
		(fp_text user "License: Apache-2.0"
			(at -0.95 -5.169 90)
			(layer "B.Fab")
			(effects
				(font
					(size 0.7 0.7)
					(thickness 0.15)
				)
				(justify left bottom mirror)
			)
		)
		(fp_text user "Author: Antmicro"
			(at -0.95 -4.169 90)
			(layer "B.Fab")
			(effects
				(font
					(size 0.7 0.7)
					(thickness 0.15)
				)
				(justify left bottom mirror)
			)
		)
		(pad "1" smd roundrect
			(at -0.48 0 270)
			(size 0.59 0.64)
			(layers "B.Cu" "B.Mask" "B.Paste")
			(roundrect_rratio 0.25)
			(net 439 "Net-(U17-A_{2})")
			(pintype "passive")
		)
		(pad "2" smd roundrect
			(at 0.48 0 270)
			(size 0.59 0.64)
			(layers "B.Cu" "B.Mask" "B.Paste")
			(roundrect_rratio 0.25)
			(net 23 "GND")
			(pintype "passive")
		)
	)
	(footprint "antmicro-footprints:R_0402_1005Metric"
		(layer "B.Cu")
		(at 157.131866 70.035117 -90)
		(descr "Resistor SMD 0402")
		(tags "resistor SMD 0402")
		(property "Reference" "R167"
			(at 9.464883 -19.468134 90)
			(layer "B.SilkS")
			(effects
				(font
					(size 0.7 0.7)
					(thickness 0.15)
				)
				(justify mirror)
			)
		)
		(property "Value" "R_22R_0402"
			(at -1.011843 -1.772047 90)
			(layer "B.Fab")
			(effects
				(font
					(size 0.7 0.7)
					(thickness 0.15)
				)
				(justify left bottom mirror)
			)
		)
		(property "Datasheet" "https://www.bourns.com/docs/product-datasheets/cr.pdf"
			(at 0 0 90)
			(layer "B.Fab")
			(hide yes)
			(effects
				(font
					(size 1.27 1.27)
					(thickness 0.15)
				)
				(justify mirror)
			)
		)
		(property "Description" "SMD Chip Resistor, 22 ohm, ± 1%, 62.5 mW, 0402 [1005 Metric], Thick Film, General Purpose"
			(at 0 0 90)
			(layer "B.Fab")
			(hide yes)
			(effects
				(font
					(size 1.27 1.27)
					(thickness 0.15)
				)
				(justify mirror)
			)
		)
		(property "MPN" "CR0402-FX-22R0GLF"
			(at 0 0 270)
			(unlocked yes)
			(layer "B.Fab")
			(hide yes)
			(effects
				(font
					(size 1 1)
					(thickness 0.15)
				)
				(justify mirror)
			)
		)
		(property "Manufacturer" "Bourns"
			(at 0 0 270)
			(unlocked yes)
			(layer "B.Fab")
			(hide yes)
			(effects
				(font
					(size 1 1)
					(thickness 0.15)
				)
				(justify mirror)
			)
		)
		(property "License" "Apache-2.0"
			(at 0 0 270)
			(unlocked yes)
			(layer "B.Fab")
			(hide yes)
			(effects
				(font
					(size 1 1)
					(thickness 0.15)
				)
				(justify mirror)
			)
		)
		(property "Author" "Antmicro"
			(at 0 0 270)
			(unlocked yes)
			(layer "B.Fab")
			(hide yes)
			(effects
				(font
					(size 1 1)
					(thickness 0.15)
				)
				(justify mirror)
			)
		)
		(property "Val" "22R"
			(at 0 0 270)
			(unlocked yes)
			(layer "B.Fab")
			(hide yes)
			(effects
				(font
					(size 1 1)
					(thickness 0.15)
				)
				(justify mirror)
			)
		)
		(property "Tolerance" "1%"
			(at 0 0 270)
			(unlocked yes)
			(layer "B.Fab")
			(hide yes)
			(effects
				(font
					(size 1 1)
					(thickness 0.15)
				)
				(justify mirror)
			)
		)
		(sheetname "/X710-AT2 Misc/")
		(sheetfile "x710-at2-mics.kicad_sch")
		(attr smd)
		(fp_rect
			(start -0.925 0.47)
			(end 0.925 -0.47)
			(stroke
				(width 0.05)
				(type default)
			)
			(fill no)
			(layer "B.CrtYd")
		)
		(fp_rect
			(start -0.5 0.25)
			(end 0.5 -0.25)
			(stroke
				(width 0.15)
				(type solid)
			)
			(fill no)
			(layer "B.Fab")
		)
		(fp_text user "${REFERENCE}"
			(at -0.95 -3.168 90)
			(layer "B.Fab")
			(effects
				(font
					(size 0.7 0.7)
					(thickness 0.15)
				)
				(justify left bottom mirror)
			)
		)
		(fp_text user "Author: Antmicro"
			(at -0.95 -4.169 90)
			(layer "B.Fab")
			(effects
				(font
					(size 0.7 0.7)
					(thickness 0.15)
				)
				(justify left bottom mirror)
			)
		)
		(fp_text user "License: Apache-2.0"
			(at -0.95 -5.169 90)
			(layer "B.Fab")
			(effects
				(font
					(size 0.7 0.7)
					(thickness 0.15)
				)
				(justify left bottom mirror)
			)
		)
		(pad "1" smd roundrect
			(at -0.48 0 270)
			(size 0.59 0.64)
			(layers "B.Cu" "B.Mask" "B.Paste")
			(roundrect_rratio 0.25)
			(net 142 "/X710-AT2 Misc/NCSI.CRS_DV")
			(pintype "passive")
		)
		(pad "2" smd roundrect
			(at 0.48 0 270)
			(size 0.59 0.64)
			(layers "B.Cu" "B.Mask" "B.Paste")
			(roundrect_rratio 0.25)
			(net 441 "Net-(U14D-NCSI_CRS_DV)")
			(pintype "passive")
		)
	)
	(footprint "antmicro-footprints:R_0402_1005Metric"
		(layer "B.Cu")
		(at 137.350001 132.599999)
		(descr "Resistor SMD 0402")
		(tags "resistor SMD 0402")
		(property "Reference" "R15"
			(at 19.525001 -8.1 180)
			(layer "B.SilkS")
			(effects
				(font
					(size 0.7 0.7)
					(thickness 0.15)
				)
				(justify mirror)
			)
		)
		(property "Value" "R_10k_0402"
			(at -1.011843 -1.772047 180)
			(layer "B.Fab")
			(effects
				(font
					(size 0.7 0.7)
					(thickness 0.15)
				)
				(justify left bottom mirror)
			)
		)
		(property "Datasheet" "https://www.bourns.com/docs/product-datasheets/cr.pdf"
			(at 0 0 180)
			(layer "B.Fab")
			(hide yes)
			(effects
				(font
					(size 1.27 1.27)
					(thickness 0.15)
				)
				(justify mirror)
			)
		)
		(property "Description" "SMD Chip Resistor, 10 kohm, ± 1%, 62.5 mW, 0402 [1005 Metric], Thick Film, General Purpose"
			(at 0 0 180)
			(layer "B.Fab")
			(hide yes)
			(effects
				(font
					(size 1.27 1.27)
					(thickness 0.15)
				)
				(justify mirror)
			)
		)
		(property "MPN" "CR0402-FX-1002GLF"
			(at 0 0 0)
			(unlocked yes)
			(layer "B.Fab")
			(hide yes)
			(effects
				(font
					(size 1 1)
					(thickness 0.15)
				)
				(justify mirror)
			)
		)
		(property "Manufacturer" "Bourns"
			(at 0 0 0)
			(unlocked yes)
			(layer "B.Fab")
			(hide yes)
			(effects
				(font
					(size 1 1)
					(thickness 0.15)
				)
				(justify mirror)
			)
		)
		(property "License" "Apache-2.0"
			(at 0 0 0)
			(unlocked yes)
			(layer "B.Fab")
			(hide yes)
			(effects
				(font
					(size 1 1)
					(thickness 0.15)
				)
				(justify mirror)
			)
		)
		(property "Val" "10k"
			(at 0 0 0)
			(unlocked yes)
			(layer "B.Fab")
			(hide yes)
			(effects
				(font
					(size 1 1)
					(thickness 0.15)
				)
				(justify mirror)
			)
		)
		(property "Tolerance" "1%"
			(at 0 0 0)
			(unlocked yes)
			(layer "B.Fab")
			(hide yes)
			(effects
				(font
					(size 1 1)
					(thickness 0.15)
				)
				(justify mirror)
			)
		)
		(property "Author" "Antmicro"
			(at 0 0 0)
			(unlocked yes)
			(layer "B.Fab")
			(hide yes)
			(effects
				(font
					(size 1 1)
					(thickness 0.15)
				)
				(justify mirror)
			)
		)
		(sheetname "/PD and TB DC-DC/")
		(sheetfile "PD_and_TB_DC_DC.kicad_sch")
		(attr smd)
		(fp_rect
			(start -0.925 0.47)
			(end 0.925 -0.47)
			(stroke
				(width 0.05)
				(type default)
			)
			(fill no)
			(layer "B.CrtYd")
		)
		(fp_rect
			(start -0.5 0.25)
			(end 0.5 -0.25)
			(stroke
				(width 0.15)
				(type solid)
			)
			(fill no)
			(layer "B.Fab")
		)
		(fp_text user "Author: Antmicro"
			(at -0.95 -4.169 180)
			(layer "B.Fab")
			(effects
				(font
					(size 0.7 0.7)
					(thickness 0.15)
				)
				(justify left bottom mirror)
			)
		)
		(fp_text user "${REFERENCE}"
			(at -0.95 -3.168 180)
			(layer "B.Fab")
			(effects
				(font
					(size 0.7 0.7)
					(thickness 0.15)
				)
				(justify left bottom mirror)
			)
		)
		(fp_text user "License: Apache-2.0"
			(at -0.95 -5.169 180)
			(layer "B.Fab")
			(effects
				(font
					(size 0.7 0.7)
					(thickness 0.15)
				)
				(justify left bottom mirror)
			)
		)
		(pad "1" smd roundrect
			(at -0.48 0)
			(size 0.59 0.64)
			(layers "B.Cu" "B.Mask" "B.Paste")
			(roundrect_rratio 0.25)
			(net 304 "/PD and TB DC-DC/TPS_3V3")
			(pintype "passive")
		)
		(pad "2" smd roundrect
			(at 0.48 0)
			(size 0.59 0.64)
			(layers "B.Cu" "B.Mask" "B.Paste")
			(roundrect_rratio 0.25)
			(net 201 "Net-(U3-GPIO0(HD3_AMSEL))")
			(pintype "passive")
		)
	)
	(footprint "antmicro-footprints:TP_SMD_0.75mm"
		(layer "B.Cu")
		(at 158.386866 72.760117 -90)
		(property "Reference" "TP30"
			(at 9.839883 -20.713136 90)
			(layer "B.SilkS")
			(effects
				(font
					(size 0.7 0.7)
					(thickness 0.15)
				)
				(justify mirror)
			)
		)
		(property "Value" "TP_0.75mm_SMD"
			(at 0 -1.2 90)
			(layer "B.Fab")
			(effects
				(font
					(size 0.7 0.7)
					(thickness 0.15)
				)
				(justify left bottom mirror)
			)
		)
		(property "Description" "SMT test point"
			(at 0 0 90)
			(layer "B.Fab")
			(hide yes)
			(effects
				(font
					(size 1.27 1.27)
					(thickness 0.15)
				)
				(justify mirror)
			)
		)
		(property "MPN" ""
			(at 0 0 270)
			(unlocked yes)
			(layer "B.Fab")
			(hide yes)
			(effects
				(font
					(size 1 1)
					(thickness 0.15)
				)
				(justify mirror)
			)
		)
		(property "Manufacturer" ""
			(at 0 0 270)
			(unlocked yes)
			(layer "B.Fab")
			(hide yes)
			(effects
				(font
					(size 1 1)
					(thickness 0.15)
				)
				(justify mirror)
			)
		)
		(property "Author" "Antmicro"
			(at 0 0 270)
			(unlocked yes)
			(layer "B.Fab")
			(hide yes)
			(effects
				(font
					(size 1 1)
					(thickness 0.15)
				)
				(justify mirror)
			)
		)
		(property "License" "Apache-2.0"
			(at 0 0 270)
			(unlocked yes)
			(layer "B.Fab")
			(hide yes)
			(effects
				(font
					(size 1 1)
					(thickness 0.15)
				)
				(justify mirror)
			)
		)
		(sheetname "/X710-AT2 Misc/")
		(sheetfile "x710-at2-mics.kicad_sch")
		(attr exclude_from_pos_files exclude_from_bom)
		(fp_circle
			(center 0 0)
			(end 0.475 0)
			(stroke
				(width 0.05)
				(type default)
			)
			(fill no)
			(layer "B.CrtYd")
		)
		(fp_text user "License: Apache-2.0"
			(at -0.4 -5.101 90)
			(layer "B.Fab")
			(effects
				(font
					(size 0.7 0.7)
					(thickness 0.15)
				)
				(justify left bottom mirror)
			)
		)
		(fp_text user "Author: Antmicro"
			(at -0.4 -3.901 90)
			(layer "B.Fab")
			(effects
				(font
					(size 0.7 0.7)
					(thickness 0.15)
				)
				(justify left bottom mirror)
			)
		)
		(fp_text user "${REFERENCE}"
			(at -0.4 -2.7 90)
			(layer "B.Fab")
			(effects
				(font
					(size 0.7 0.7)
					(thickness 0.15)
				)
				(justify left bottom mirror)
			)
		)
		(pad "1" smd circle
			(at 0 0 270)
			(size 0.75 0.75)
			(layers "B.Cu" "B.Mask")
			(net 149 "/X710-AT2 Misc/REFCLK_SEL")
			(pinfunction "1")
			(pintype "passive")
		)
	)
	(footprint "antmicro-footprints:C_0402_1005Metric"
		(layer "B.Cu")
		(at 129.979999 129.31 180)
		(descr "Capacitor SMD 0402")
		(tags "capacitor SMD 0402")
		(property "Reference" "C90"
			(at -21.900002 7.700002 0)
			(layer "B.SilkS")
			(effects
				(font
					(size 0.7 0.7)
					(thickness 0.15)
				)
				(justify mirror)
			)
		)
		(property "Value" "C_10u_0402"
			(at -1.022927 -2.155213 0)
			(layer "B.Fab")
			(effects
				(font
					(size 0.7 0.7)
					(thickness 0.15)
				)
				(justify left bottom mirror)
			)
		)
		(property "Datasheet" "https://www.yageo.com/en/Chart/Download/pdf/CC0402MRX5R5BB106"
			(at 0 0 0)
			(layer "B.Fab")
			(hide yes)
			(effects
				(font
					(size 1.27 1.27)
					(thickness 0.15)
				)
				(justify mirror)
			)
		)
		(property "Description" "SMD Multilayer Ceramic Capacitor, 10 µF, 6.3 V, 0402 [1005 Metric], ± 20%, X5R, CC Series"
			(at 0 0 0)
			(layer "B.Fab")
			(hide yes)
			(effects
				(font
					(size 1.27 1.27)
					(thickness 0.15)
				)
				(justify mirror)
			)
		)
		(property "MPN" "CC0402MRX5R5BB106"
			(at 0 0 180)
			(unlocked yes)
			(layer "B.Fab")
			(hide yes)
			(effects
				(font
					(size 1 1)
					(thickness 0.15)
				)
				(justify mirror)
			)
		)
		(property "Manufacturer" "YAGEO"
			(at 0 0 180)
			(unlocked yes)
			(layer "B.Fab")
			(hide yes)
			(effects
				(font
					(size 1 1)
					(thickness 0.15)
				)
				(justify mirror)
			)
		)
		(property "License" "Apache-2.0"
			(at 0 0 180)
			(unlocked yes)
			(layer "B.Fab")
			(hide yes)
			(effects
				(font
					(size 1 1)
					(thickness 0.15)
				)
				(justify mirror)
			)
		)
		(property "Val" "10u"
			(at 0 0 180)
			(unlocked yes)
			(layer "B.Fab")
			(hide yes)
			(effects
				(font
					(size 1 1)
					(thickness 0.15)
				)
				(justify mirror)
			)
		)
		(property "Voltage" ""
			(at 0 0 180)
			(unlocked yes)
			(layer "B.Fab")
			(hide yes)
			(effects
				(font
					(size 1 1)
					(thickness 0.15)
				)
				(justify mirror)
			)
		)
		(property "Dielectric" ""
			(at 0 0 180)
			(unlocked yes)
			(layer "B.Fab")
			(hide yes)
			(effects
				(font
					(size 1 1)
					(thickness 0.15)
				)
				(justify mirror)
			)
		)
		(property "Author" "Antmicro"
			(at 0 0 180)
			(unlocked yes)
			(layer "B.Fab")
			(hide yes)
			(effects
				(font
					(size 1 1)
					(thickness 0.15)
				)
				(justify mirror)
			)
		)
		(sheetname "/TB Controller - Power/")
		(sheetfile "tb-power.kicad_sch")
		(attr smd)
		(fp_rect
			(start -0.925 0.47)
			(end 0.925 -0.47)
			(stroke
				(width 0.05)
				(type default)
			)
			(fill no)
			(layer "B.CrtYd")
		)
		(fp_line
			(start 0.504 0.25)
			(end 0.504 -0.248)
			(stroke
				(width 0.15)
				(type solid)
			)
			(layer "B.Fab")
		)
		(fp_line
			(start 0.504 -0.248)
			(end -0.494 -0.248)
			(stroke
				(width 0.15)
				(type solid)
			)
			(layer "B.Fab")
		)
		(fp_line
			(start -0.494 0.25)
			(end 0.504 0.25)
			(stroke
				(width 0.15)
				(type solid)
			)
			(layer "B.Fab")
		)
		(fp_line
			(start -0.494 -0.248)
			(end -0.494 0.25)
			(stroke
				(width 0.15)
				(type solid)
			)
			(layer "B.Fab")
		)
		(fp_text user "Author: Antmicro"
			(at -0.939 -3.399 0)
			(layer "B.Fab")
			(effects
				(font
					(size 0.7 0.7)
					(thickness 0.15)
				)
				(justify left bottom mirror)
			)
		)
		(fp_text user "${REFERENCE}"
			(at -0.939 -4.599 0)
			(layer "B.Fab")
			(effects
				(font
					(size 0.7 0.7)
					(thickness 0.15)
				)
				(justify left bottom mirror)
			)
		)
		(fp_text user "License: Apache-2.0"
			(at -0.939 -5.799 0)
			(layer "B.Fab")
			(effects
				(font
					(size 0.7 0.7)
					(thickness 0.15)
				)
				(justify left bottom mirror)
			)
		)
		(pad "1" smd roundrect
			(at -0.48 0 180)
			(size 0.59 0.64)
			(layers "B.Cu" "B.Mask" "B.Paste")
			(roundrect_rratio 0.25)
			(net 23 "GND")
			(pintype "passive")
		)
		(pad "2" smd roundrect
			(at 0.48 0 180)
			(size 0.59 0.64)
			(layers "B.Cu" "B.Mask" "B.Paste")
			(roundrect_rratio 0.25)
			(net 180 "Net-(U4A-VCC0P9_LVR_SENSE)")
			(pintype "passive")
		)
	)
	(footprint "antmicro-footprints:R_0402_1005Metric"
		(layer "B.Cu")
		(at 126.219998 119.941002 90)
		(descr "Resistor SMD 0402")
		(tags "resistor SMD 0402")
		(property "Reference" "R70"
			(at 7.700002 21.900002 270)
			(layer "B.SilkS")
			(effects
				(font
					(size 0.7 0.7)
					(thickness 0.15)
				)
				(justify mirror)
			)
		)
		(property "Value" "R_3k01_0402"
			(at -1.011843 -1.772047 270)
			(layer "B.Fab")
			(effects
				(font
					(size 0.7 0.7)
					(thickness 0.15)
				)
				(justify left bottom mirror)
			)
		)
		(property "Datasheet" "https://www.bourns.com/docs/product-datasheets/cr.pdf"
			(at 0 0 270)
			(layer "B.Fab")
			(hide yes)
			(effects
				(font
					(size 1.27 1.27)
					(thickness 0.15)
				)
				(justify mirror)
			)
		)
		(property "Description" "SMD Chip Resistor, 3.01 kohm, ± 1%, 62.5 mW, 0402 [1005 Metric], Thick Film, General Purpose"
			(at 0 0 270)
			(layer "B.Fab")
			(hide yes)
			(effects
				(font
					(size 1.27 1.27)
					(thickness 0.15)
				)
				(justify mirror)
			)
		)
		(property "MPN" "CR0402-FX-3011GLF"
			(at 0 0 90)
			(unlocked yes)
			(layer "B.Fab")
			(hide yes)
			(effects
				(font
					(size 1 1)
					(thickness 0.15)
				)
				(justify mirror)
			)
		)
		(property "Manufacturer" "Bourns"
			(at 0 0 90)
			(unlocked yes)
			(layer "B.Fab")
			(hide yes)
			(effects
				(font
					(size 1 1)
					(thickness 0.15)
				)
				(justify mirror)
			)
		)
		(property "License" "Apache-2.0"
			(at 0 0 90)
			(unlocked yes)
			(layer "B.Fab")
			(hide yes)
			(effects
				(font
					(size 1 1)
					(thickness 0.15)
				)
				(justify mirror)
			)
		)
		(property "Val" "3k01"
			(at 0 0 90)
			(unlocked yes)
			(layer "B.Fab")
			(hide yes)
			(effects
				(font
					(size 1 1)
					(thickness 0.15)
				)
				(justify mirror)
			)
		)
		(property "Tolerance" "1%"
			(at 0 0 90)
			(unlocked yes)
			(layer "B.Fab")
			(hide yes)
			(effects
				(font
					(size 1 1)
					(thickness 0.15)
				)
				(justify mirror)
			)
		)
		(property "Author" "Antmicro"
			(at 0 0 90)
			(unlocked yes)
			(layer "B.Fab")
			(hide yes)
			(effects
				(font
					(size 1 1)
					(thickness 0.15)
				)
				(justify mirror)
			)
		)
		(sheetname "/TB Controller/")
		(sheetfile "tb.kicad_sch")
		(attr smd)
		(fp_rect
			(start -0.925 0.47)
			(end 0.925 -0.47)
			(stroke
				(width 0.05)
				(type default)
			)
			(fill no)
			(layer "B.CrtYd")
		)
		(fp_rect
			(start -0.5 0.25)
			(end 0.5 -0.25)
			(stroke
				(width 0.15)
				(type solid)
			)
			(fill no)
			(layer "B.Fab")
		)
		(fp_text user "Author: Antmicro"
			(at -0.95 -4.169 270)
			(layer "B.Fab")
			(effects
				(font
					(size 0.7 0.7)
					(thickness 0.15)
				)
				(justify left bottom mirror)
			)
		)
		(fp_text user "${REFERENCE}"
			(at -0.95 -3.168 270)
			(layer "B.Fab")
			(effects
				(font
					(size 0.7 0.7)
					(thickness 0.15)
				)
				(justify left bottom mirror)
			)
		)
		(fp_text user "License: Apache-2.0"
			(at -0.95 -5.169 270)
			(layer "B.Fab")
			(effects
				(font
					(size 0.7 0.7)
					(thickness 0.15)
				)
				(justify left bottom mirror)
			)
		)
		(pad "1" smd roundrect
			(at -0.48 0 90)
			(size 0.59 0.64)
			(layers "B.Cu" "B.Mask" "B.Paste")
			(roundrect_rratio 0.25)
			(net 183 "Net-(U4B-PCIE_RBIAS)")
			(pintype "passive")
		)
		(pad "2" smd roundrect
			(at 0.48 0 90)
			(size 0.59 0.64)
			(layers "B.Cu" "B.Mask" "B.Paste")
			(roundrect_rratio 0.25)
			(net 23 "GND")
			(pintype "passive")
		)
	)
	(footprint "antmicro-footprints:R_0402_1005Metric"
		(layer "B.Cu")
		(at 138.35 135.6)
		(descr "Resistor SMD 0402")
		(tags "resistor SMD 0402")
		(property "Reference" "R23"
			(at 19.525001 -8.1 180)
			(layer "B.SilkS")
			(effects
				(font
					(size 0.7 0.7)
					(thickness 0.15)
				)
				(justify mirror)
			)
		)
		(property "Value" "R_100k_0402"
			(at -1.011843 -1.772047 180)
			(layer "B.Fab")
			(effects
				(font
					(size 0.7 0.7)
					(thickness 0.15)
				)
				(justify left bottom mirror)
			)
		)
		(property "Datasheet" "https://www.bourns.com/docs/product-datasheets/cr.pdf"
			(at 0 0 180)
			(layer "B.Fab")
			(hide yes)
			(effects
				(font
					(size 1.27 1.27)
					(thickness 0.15)
				)
				(justify mirror)
			)
		)
		(property "Description" "SMD Chip Resistor, 100 kohm, ± 1%, 62.5 mW, 0402 [1005 Metric], Thick Film, General Purpose"
			(at 0 0 180)
			(layer "B.Fab")
			(hide yes)
			(effects
				(font
					(size 1.27 1.27)
					(thickness 0.15)
				)
				(justify mirror)
			)
		)
		(property "MPN" "CR0402-FX-1003GLF"
			(at 0 0 0)
			(unlocked yes)
			(layer "B.Fab")
			(hide yes)
			(effects
				(font
					(size 1 1)
					(thickness 0.15)
				)
				(justify mirror)
			)
		)
		(property "Manufacturer" "Bourns"
			(at 0 0 0)
			(unlocked yes)
			(layer "B.Fab")
			(hide yes)
			(effects
				(font
					(size 1 1)
					(thickness 0.15)
				)
				(justify mirror)
			)
		)
		(property "License" "Apache-2.0"
			(at 0 0 0)
			(unlocked yes)
			(layer "B.Fab")
			(hide yes)
			(effects
				(font
					(size 1 1)
					(thickness 0.15)
				)
				(justify mirror)
			)
		)
		(property "Val" "100k"
			(at 0 0 0)
			(unlocked yes)
			(layer "B.Fab")
			(hide yes)
			(effects
				(font
					(size 1 1)
					(thickness 0.15)
				)
				(justify mirror)
			)
		)
		(property "Tolerance" "1%"
			(at 0 0 0)
			(unlocked yes)
			(layer "B.Fab")
			(hide yes)
			(effects
				(font
					(size 1 1)
					(thickness 0.15)
				)
				(justify mirror)
			)
		)
		(property "Author" "Antmicro"
			(at 0 0 0)
			(unlocked yes)
			(layer "B.Fab")
			(hide yes)
			(effects
				(font
					(size 1 1)
					(thickness 0.15)
				)
				(justify mirror)
			)
		)
		(sheetname "/PD and TB DC-DC/")
		(sheetfile "PD_and_TB_DC_DC.kicad_sch")
		(attr smd)
		(fp_rect
			(start -0.925 0.47)
			(end 0.925 -0.47)
			(stroke
				(width 0.05)
				(type default)
			)
			(fill no)
			(layer "B.CrtYd")
		)
		(fp_rect
			(start -0.5 0.25)
			(end 0.5 -0.25)
			(stroke
				(width 0.15)
				(type solid)
			)
			(fill no)
			(layer "B.Fab")
		)
		(fp_text user "License: Apache-2.0"
			(at -0.95 -5.169 180)
			(layer "B.Fab")
			(effects
				(font
					(size 0.7 0.7)
					(thickness 0.15)
				)
				(justify left bottom mirror)
			)
		)
		(fp_text user "${REFERENCE}"
			(at -0.95 -3.168 180)
			(layer "B.Fab")
			(effects
				(font
					(size 0.7 0.7)
					(thickness 0.15)
				)
				(justify left bottom mirror)
			)
		)
		(fp_text user "Author: Antmicro"
			(at -0.95 -4.169 180)
			(layer "B.Fab")
			(effects
				(font
					(size 0.7 0.7)
					(thickness 0.15)
				)
				(justify left bottom mirror)
			)
		)
		(pad "1" smd roundrect
			(at -0.48 0)
			(size 0.59 0.64)
			(layers "B.Cu" "B.Mask" "B.Paste")
			(roundrect_rratio 0.25)
			(net 206 "Net-(U3-DEBUG_CTL2(GPIO17,_I2CADDR_B5))")
			(pintype "passive")
		)
		(pad "2" smd roundrect
			(at 0.48 0)
			(size 0.59 0.64)
			(layers "B.Cu" "B.Mask" "B.Paste")
			(roundrect_rratio 0.25)
			(net 304 "/PD and TB DC-DC/TPS_3V3")
			(pintype "passive")
		)
	)
	(footprint "antmicro-footprints:C_Pol_EIA-A"
		(layer "B.Cu")
		(at 155 97.5 180)
		(property "Reference" "C332"
			(at -1.5 1.2 0)
			(layer "B.SilkS")
			(effects
				(font
					(size 0.7 0.7)
					(thickness 0.15)
				)
				(justify left bottom mirror)
			)
		)
		(property "Value" "C_Pol_100u_6V_KEMET-T490-A"
			(at 0 -2 0)
			(layer "B.Fab")
			(effects
				(font
					(size 0.7 0.7)
					(thickness 0.15)
				)
				(justify left bottom mirror)
			)
		)
		(property "Datasheet" "https://www.kemet.com/en/us/capacitors/product/T490A107M006ATE800.html"
			(at 0 0 0)
			(layer "B.Fab")
			(hide yes)
			(effects
				(font
					(size 1.27 1.27)
					(thickness 0.15)
				)
				(justify mirror)
			)
		)
		(property "Description" "Surface Mount Tantalum Capacitor,  Solid SMD 6V 100uF 1206 20% ESR=800mOhms"
			(at 0 0 0)
			(layer "B.Fab")
			(hide yes)
			(effects
				(font
					(size 1.27 1.27)
					(thickness 0.15)
				)
				(justify mirror)
			)
		)
		(property "Val" "100u"
			(at 0 0 180)
			(unlocked yes)
			(layer "B.Fab")
			(hide yes)
			(effects
				(font
					(size 1 1)
					(thickness 0.15)
				)
				(justify mirror)
			)
		)
		(property "MPN" "T490A107M006ATE800"
			(at 0 0 180)
			(unlocked yes)
			(layer "B.Fab")
			(hide yes)
			(effects
				(font
					(size 1 1)
					(thickness 0.15)
				)
				(justify mirror)
			)
		)
		(property "Manufacturer" "KEMET"
			(at 0 0 180)
			(unlocked yes)
			(layer "B.Fab")
			(hide yes)
			(effects
				(font
					(size 1 1)
					(thickness 0.15)
				)
				(justify mirror)
			)
		)
		(property "License" "Apache-2.0"
			(at 0 0 180)
			(unlocked yes)
			(layer "B.Fab")
			(hide yes)
			(effects
				(font
					(size 1 1)
					(thickness 0.15)
				)
				(justify mirror)
			)
		)
		(property "Author" "Antmicro"
			(at 0 0 180)
			(unlocked yes)
			(layer "B.Fab")
			(hide yes)
			(effects
				(font
					(size 1 1)
					(thickness 0.15)
				)
				(justify mirror)
			)
		)
		(property "Voltage" "6V"
			(at 0 0 180)
			(unlocked yes)
			(layer "B.Fab")
			(hide yes)
			(effects
				(font
					(size 1 1)
					(thickness 0.15)
				)
				(justify mirror)
			)
		)
		(property "Dielectric" "template_dielectric"
			(at 0 0 180)
			(unlocked yes)
			(layer "B.Fab")
			(hide yes)
			(effects
				(font
					(size 1 1)
					(thickness 0.15)
				)
				(justify mirror)
			)
		)
		(sheetname "/X710-AT2 power/")
		(sheetfile "x710-at2-power.kicad_sch")
		(attr smd)
		(fp_line
			(start 1.5 0.75)
			(end 1.5 0.85)
			(stroke
				(width 0.12)
				(type solid)
			)
			(layer "B.SilkS")
		)
		(fp_line
			(start 1.5 -0.75)
			(end 1.5 -0.85)
			(stroke
				(width 0.12)
				(type solid)
			)
			(layer "B.SilkS")
		)
		(fp_line
			(start 1.5 -0.85)
			(end -1.5 -0.85)
			(stroke
				(width 0.12)
				(type solid)
			)
			(layer "B.SilkS")
		)
		(fp_line
			(start -1.5 0.85)
			(end 1.5 0.85)
			(stroke
				(width 0.12)
				(type solid)
			)
			(layer "B.SilkS")
		)
		(fp_line
			(start -1.5 0.75)
			(end -1.5 0.85)
			(stroke
				(width 0.12)
				(type solid)
			)
			(layer "B.SilkS")
		)
		(fp_line
			(start -1.5 -0.75)
			(end -1.5 -0.85)
			(stroke
				(width 0.12)
				(type solid)
			)
			(layer "B.SilkS")
		)
		(fp_line
			(start -1.95 1.25)
			(end -1.95 0.95)
			(stroke
				(width 0.12)
				(type solid)
			)
			(layer "B.SilkS")
		)
		(fp_line
			(start -2.1 1.1)
			(end -1.8 1.1)
			(stroke
				(width 0.12)
				(type solid)
			)
			(layer "B.SilkS")
		)
		(fp_line
			(start 2.05 0.85)
			(end 2.05 -0.85)
			(stroke
				(width 0.05)
				(type solid)
			)
			(layer "B.CrtYd")
		)
		(fp_line
			(start 2.05 0.85)
			(end 1.7 0.85)
			(stroke
				(width 0.05)
				(type solid)
			)
			(layer "B.CrtYd")
		)
		(fp_line
			(start 2.05 -0.85)
			(end 1.7 -0.85)
			(stroke
				(width 0.05)
				(type solid)
			)
			(layer "B.CrtYd")
		)
		(fp_line
			(start 1.7 1.05)
			(end -1.7 1.05)
			(stroke
				(width 0.05)
				(type solid)
			)
			(layer "B.CrtYd")
		)
		(fp_line
			(start 1.7 0.85)
			(end 1.7 1.05)
			(stroke
				(width 0.05)
				(type solid)
			)
			(layer "B.CrtYd")
		)
		(fp_line
			(start 1.7 -1.05)
			(end 1.7 -0.85)
			(stroke
				(width 0.05)
				(type solid)
			)
			(layer "B.CrtYd")
		)
		(fp_line
			(start 1.7 -1.05)
			(end -1.7 -1.05)
			(stroke
				(width 0.05)
				(type solid)
			)
			(layer "B.CrtYd")
		)
		(fp_line
			(start -1.7 0.85)
			(end -1.7 1.05)
			(stroke
				(width 0.05)
				(type solid)
			)
			(layer "B.CrtYd")
		)
		(fp_line
			(start -1.7 0.85)
			(end -2.05 0.85)
			(stroke
				(width 0.05)
				(type solid)
			)
			(layer "B.CrtYd")
		)
		(fp_line
			(start -1.7 -0.85)
			(end -2.05 -0.85)
			(stroke
				(width 0.05)
				(type solid)
			)
			(layer "B.CrtYd")
		)
		(fp_line
			(start -1.7 -1.05)
			(end -1.7 -0.85)
			(stroke
				(width 0.05)
				(type solid)
			)
			(layer "B.CrtYd")
		)
		(fp_line
			(start -2.05 0.85)
			(end -2.05 -0.85)
			(stroke
				(width 0.05)
				(type solid)
			)
			(layer "B.CrtYd")
		)
		(fp_rect
			(start -1.601 0.802)
			(end 1.6 -0.8)
			(stroke
				(width 0.1)
				(type solid)
			)
			(fill no)
			(layer "B.Fab")
		)
		(fp_text user "${REFERENCE}"
			(at -2.1 -4.198 0)
			(layer "B.Fab")
			(effects
				(font
					(size 0.7 0.7)
					(thickness 0.15)
				)
				(justify left bottom mirror)
			)
		)
		(fp_text user "Author: Antmicro"
			(at -2.1 -6.198 0)
			(layer "B.Fab")
			(effects
				(font
					(size 0.7 0.7)
					(thickness 0.15)
				)
				(justify left bottom mirror)
			)
		)
		(fp_text user "License: Apache-2.0"
			(at -2.1 -5.198 0)
			(layer "B.Fab")
			(effects
				(font
					(size 0.7 0.7)
					(thickness 0.15)
				)
				(justify left bottom mirror)
			)
		)
		(pad "1" smd roundrect
			(at -1.2 0 180)
			(size 1.2 1.2)
			(layers "B.Cu" "B.Mask" "B.Paste")
			(roundrect_rratio 0.1)
			(net 136 "+1V0")
			(pintype "passive")
		)
		(pad "2" smd roundrect
			(at 1.2 0 180)
			(size 1.2 1.2)
			(layers "B.Cu" "B.Mask" "B.Paste")
			(roundrect_rratio 0.1)
			(net 23 "GND")
			(pintype "passive")
		)
	)
	(footprint "antmicro-footprints:L_0402_1005Metric"
		(layer "B.Cu")
		(at 159 137.5 180)
		(descr "Inductor SMD 0402")
		(tags "Inductor SMD 0402")
		(property "Reference" "L12"
			(at 1 -0.5 0)
			(layer "B.SilkS")
			(effects
				(font
					(size 0.7 0.7)
					(thickness 0.15)
				)
				(justify left bottom mirror)
			)
		)
		(property "Value" "L_2n4_0.85A_0402"
			(at 0 -1.4 0)
			(layer "B.Fab")
			(effects
				(font
					(size 0.7 0.7)
					(thickness 0.15)
				)
				(justify left bottom mirror)
			)
		)
		(property "Datasheet" "https://www.murata.com/products/productdetail?partno=LQW15AN2N4B00%23"
			(at 0 0 0)
			(layer "B.Fab")
			(hide yes)
			(effects
				(font
					(size 1.27 1.27)
					(thickness 0.15)
				)
				(justify mirror)
			)
		)
		(property "Description" "Wirewound Inductor, 2.4 nH, 0.05 ohm, 15 GHz, 850 mA, 0402 [1005 Metric], LQW15AN"
			(at 0 0 0)
			(layer "B.Fab")
			(hide yes)
			(effects
				(font
					(size 1.27 1.27)
					(thickness 0.15)
				)
				(justify mirror)
			)
		)
		(property "Val" "2n4/0.85A"
			(at 0 0 180)
			(unlocked yes)
			(layer "B.Fab")
			(hide yes)
			(effects
				(font
					(size 1 1)
					(thickness 0.15)
				)
				(justify mirror)
			)
		)
		(property "Manufacturer" "Murata"
			(at 0 0 180)
			(unlocked yes)
			(layer "B.Fab")
			(hide yes)
			(effects
				(font
					(size 1 1)
					(thickness 0.15)
				)
				(justify mirror)
			)
		)
		(property "MPN" "LQW15AN2N4B00D"
			(at 0 0 180)
			(unlocked yes)
			(layer "B.Fab")
			(hide yes)
			(effects
				(font
					(size 1 1)
					(thickness 0.15)
				)
				(justify mirror)
			)
		)
		(property "ISat" "0.85 A"
			(at 0 0 180)
			(unlocked yes)
			(layer "B.Fab")
			(hide yes)
			(effects
				(font
					(size 1 1)
					(thickness 0.15)
				)
				(justify mirror)
			)
		)
		(property "IMax" "0.85 A"
			(at 0 0 180)
			(unlocked yes)
			(layer "B.Fab")
			(hide yes)
			(effects
				(font
					(size 1 1)
					(thickness 0.15)
				)
				(justify mirror)
			)
		)
		(property "Size" "1.0x0.5"
			(at 0 0 180)
			(unlocked yes)
			(layer "B.Fab")
			(hide yes)
			(effects
				(font
					(size 1 1)
					(thickness 0.15)
				)
				(justify mirror)
			)
		)
		(property "Author" "Antmicro"
			(at 0 0 180)
			(unlocked yes)
			(layer "B.Fab")
			(hide yes)
			(effects
				(font
					(size 1 1)
					(thickness 0.15)
				)
				(justify mirror)
			)
		)
		(property "License" "Apache-2.0"
			(at 0 0 180)
			(unlocked yes)
			(layer "B.Fab")
			(hide yes)
			(effects
				(font
					(size 1 1)
					(thickness 0.15)
				)
				(justify mirror)
			)
		)
		(sheetname "/2xRJ45/")
		(sheetfile "2xrj45.kicad_sch")
		(attr smd)
		(fp_rect
			(start -0.925 0.47)
			(end 0.925 -0.47)
			(stroke
				(width 0.05)
				(type default)
			)
			(fill no)
			(layer "B.CrtYd")
		)
		(fp_rect
			(start -0.499 0.249)
			(end 0.499 -0.249)
			(stroke
				(width 0.15)
				(type solid)
			)
			(fill no)
			(layer "B.Fab")
		)
		(fp_text user "License: Apache-2.0"
			(at -0.932 -5.17 0)
			(layer "B.Fab")
			(effects
				(font
					(size 0.7 0.7)
					(thickness 0.15)
				)
				(justify left bottom mirror)
			)
		)
		(fp_text user "Author: Antmicro"
			(at -0.932 -4.17 0)
			(layer "B.Fab")
			(effects
				(font
					(size 0.7 0.7)
					(thickness 0.15)
				)
				(justify left bottom mirror)
			)
		)
		(fp_text user "${REFERENCE}"
			(at -0.932 -3.168 0)
			(layer "B.Fab")
			(effects
				(font
					(size 0.7 0.7)
					(thickness 0.15)
				)
				(justify left bottom mirror)
			)
		)
		(pad "1" smd roundrect
			(at -0.48 0 180)
			(size 0.59 0.64)
			(layers "B.Cu" "B.Mask" "B.Paste")
			(roundrect_rratio 0.25)
			(net 135 "+1V88_CT")
			(pintype "passive")
		)
		(pad "2" smd roundrect
			(at 0.48 0 180)
			(size 0.59 0.64)
			(layers "B.Cu" "B.Mask" "B.Paste")
			(roundrect_rratio 0.25)
			(net 133 "/2xRJ45/P0_CT")
			(pintype "passive")
		)
	)
	(footprint "antmicro-footprints:TP_SMD_0.75mm"
		(layer "B.Cu")
		(at 142.25 55.25 180)
		(property "Reference" "TP2"
			(at -0.5 2.5 270)
			(layer "B.SilkS")
			(effects
				(font
					(size 0.7 0.7)
					(thickness 0.15)
				)
				(justify left bottom mirror)
			)
		)
		(property "Value" "TP_0.75mm_SMD"
			(at 0 -1.2 0)
			(layer "B.Fab")
			(effects
				(font
					(size 0.7 0.7)
					(thickness 0.15)
				)
				(justify left bottom mirror)
			)
		)
		(property "Description" "SMT test point"
			(at 0 0 0)
			(layer "B.Fab")
			(hide yes)
			(effects
				(font
					(size 1.27 1.27)
					(thickness 0.15)
				)
				(justify mirror)
			)
		)
		(property "MPN" ""
			(at 0 0 180)
			(unlocked yes)
			(layer "B.Fab")
			(hide yes)
			(effects
				(font
					(size 1 1)
					(thickness 0.15)
				)
				(justify mirror)
			)
		)
		(property "Manufacturer" ""
			(at 0 0 180)
			(unlocked yes)
			(layer "B.Fab")
			(hide yes)
			(effects
				(font
					(size 1 1)
					(thickness 0.15)
				)
				(justify mirror)
			)
		)
		(property "Author" "Antmicro"
			(at 0 0 180)
			(unlocked yes)
			(layer "B.Fab")
			(hide yes)
			(effects
				(font
					(size 1 1)
					(thickness 0.15)
				)
				(justify mirror)
			)
		)
		(property "License" "Apache-2.0"
			(at 0 0 180)
			(unlocked yes)
			(layer "B.Fab")
			(hide yes)
			(effects
				(font
					(size 1 1)
					(thickness 0.15)
				)
				(justify mirror)
			)
		)
		(sheetname "/Power input/")
		(sheetfile "power_input.kicad_sch")
		(attr exclude_from_pos_files exclude_from_bom)
		(fp_circle
			(center 0 0)
			(end 0.475 0)
			(stroke
				(width 0.05)
				(type default)
			)
			(fill no)
			(layer "B.CrtYd")
		)
		(fp_text user "License: Apache-2.0"
			(at -0.4 -5.101 0)
			(layer "B.Fab")
			(effects
				(font
					(size 0.7 0.7)
					(thickness 0.15)
				)
				(justify left bottom mirror)
			)
		)
		(fp_text user "Author: Antmicro"
			(at -0.4 -3.901 0)
			(layer "B.Fab")
			(effects
				(font
					(size 0.7 0.7)
					(thickness 0.15)
				)
				(justify left bottom mirror)
			)
		)
		(fp_text user "${REFERENCE}"
			(at -0.4 -2.7 0)
			(layer "B.Fab")
			(effects
				(font
					(size 0.7 0.7)
					(thickness 0.15)
				)
				(justify left bottom mirror)
			)
		)
		(pad "1" smd circle
			(at 0 0 180)
			(size 0.75 0.75)
			(layers "B.Cu" "B.Mask")
			(net 23 "GND")
			(pinfunction "1")
			(pintype "passive")
		)
	)
	(footprint "antmicro-footprints:R_0402_1005Metric"
		(layer "B.Cu")
		(at 162.381866 76.985117)
		(descr "Resistor SMD 0402")
		(tags "resistor SMD 0402")
		(property "Reference" "R127"
			(at 2.368134 0.014883 180)
			(layer "B.SilkS")
			(effects
				(font
					(size 0.7 0.7)
					(thickness 0.15)
				)
				(justify mirror)
			)
		)
		(property "Value" "R_1k_0402"
			(at -1.011843 -1.772047 180)
			(layer "B.Fab")
			(effects
				(font
					(size 0.7 0.7)
					(thickness 0.15)
				)
				(justify left bottom mirror)
			)
		)
		(property "Datasheet" "https://www.bourns.com/docs/product-datasheets/cr.pdf"
			(at 0 0 180)
			(layer "B.Fab")
			(hide yes)
			(effects
				(font
					(size 1.27 1.27)
					(thickness 0.15)
				)
				(justify mirror)
			)
		)
		(property "Description" "SMD Chip Resistor, 1 kohm, ± 1%, 63 mW, 0402 [1005 Metric], Thick Film, General Purpose"
			(at 0 0 180)
			(layer "B.Fab")
			(hide yes)
			(effects
				(font
					(size 1.27 1.27)
					(thickness 0.15)
				)
				(justify mirror)
			)
		)
		(property "MPN" "CR0402-FX-1001GLF"
			(at 0 0 0)
			(unlocked yes)
			(layer "B.Fab")
			(hide yes)
			(effects
				(font
					(size 1 1)
					(thickness 0.15)
				)
				(justify mirror)
			)
		)
		(property "Manufacturer" "Bourns"
			(at 0 0 0)
			(unlocked yes)
			(layer "B.Fab")
			(hide yes)
			(effects
				(font
					(size 1 1)
					(thickness 0.15)
				)
				(justify mirror)
			)
		)
		(property "License" "Apache-2.0"
			(at 0 0 0)
			(unlocked yes)
			(layer "B.Fab")
			(hide yes)
			(effects
				(font
					(size 1 1)
					(thickness 0.15)
				)
				(justify mirror)
			)
		)
		(property "Author" "Antmicro"
			(at 0 0 0)
			(unlocked yes)
			(layer "B.Fab")
			(hide yes)
			(effects
				(font
					(size 1 1)
					(thickness 0.15)
				)
				(justify mirror)
			)
		)
		(property "Val" "1k"
			(at 0 0 0)
			(unlocked yes)
			(layer "B.Fab")
			(hide yes)
			(effects
				(font
					(size 1 1)
					(thickness 0.15)
				)
				(justify mirror)
			)
		)
		(property "Tolerance" "1%"
			(at 0 0 0)
			(unlocked yes)
			(layer "B.Fab")
			(hide yes)
			(effects
				(font
					(size 1 1)
					(thickness 0.15)
				)
				(justify mirror)
			)
		)
		(sheetname "/X710-AT2 RSVD/")
		(sheetfile "x710-at2-rsvd.kicad_sch")
		(attr smd)
		(fp_rect
			(start -0.925 0.47)
			(end 0.925 -0.47)
			(stroke
				(width 0.05)
				(type default)
			)
			(fill no)
			(layer "B.CrtYd")
		)
		(fp_rect
			(start -0.5 0.25)
			(end 0.5 -0.25)
			(stroke
				(width 0.15)
				(type solid)
			)
			(fill no)
			(layer "B.Fab")
		)
		(fp_text user "License: Apache-2.0"
			(at -0.95 -5.169 180)
			(layer "B.Fab")
			(effects
				(font
					(size 0.7 0.7)
					(thickness 0.15)
				)
				(justify left bottom mirror)
			)
		)
		(fp_text user "Author: Antmicro"
			(at -0.95 -4.169 180)
			(layer "B.Fab")
			(effects
				(font
					(size 0.7 0.7)
					(thickness 0.15)
				)
				(justify left bottom mirror)
			)
		)
		(fp_text user "${REFERENCE}"
			(at -0.95 -3.168 180)
			(layer "B.Fab")
			(effects
				(font
					(size 0.7 0.7)
					(thickness 0.15)
				)
				(justify left bottom mirror)
			)
		)
		(pad "1" smd roundrect
			(at -0.48 0)
			(size 0.59 0.64)
			(layers "B.Cu" "B.Mask" "B.Paste")
			(roundrect_rratio 0.25)
			(net 101 "/X710-AT2 RSVD/RSVDD8_1P88V")
			(pintype "passive")
		)
		(pad "2" smd roundrect
			(at 0.48 0)
			(size 0.59 0.64)
			(layers "B.Cu" "B.Mask" "B.Paste")
			(roundrect_rratio 0.25)
			(net 18 "+1V88")
			(pintype "passive")
		)
	)
	(footprint "antmicro-footprints:C_0402_1005Metric"
		(layer "B.Cu")
		(at 159.406866 85.485117 90)
		(descr "Capacitor SMD 0402")
		(tags "capacitor SMD 0402")
		(property "Reference" "C206"
			(at -9.014883 21.398134 270)
			(layer "B.SilkS")
			(effects
				(font
					(size 0.7 0.7)
					(thickness 0.15)
				)
				(justify mirror)
			)
		)
		(property "Value" "C_1u_25V_0402"
			(at -1.022927 -2.155213 270)
			(layer "B.Fab")
			(effects
				(font
					(size 0.7 0.7)
					(thickness 0.15)
				)
				(justify left bottom mirror)
			)
		)
		(property "Datasheet" "https://www.murata.com/products/productdetail?partno=GRM155R61E105KE11%23"
			(at 0 0 270)
			(layer "B.Fab")
			(hide yes)
			(effects
				(font
					(size 1.27 1.27)
					(thickness 0.15)
				)
				(justify mirror)
			)
		)
		(property "Description" "SMD Multilayer Ceramic Capacitor, 1 µF, 25 V, 0402 [1005 Metric], ± 10%, X5R, GRM Series"
			(at 0 0 270)
			(layer "B.Fab")
			(hide yes)
			(effects
				(font
					(size 1.27 1.27)
					(thickness 0.15)
				)
				(justify mirror)
			)
		)
		(property "MPN" "GRM155R61E105KE11J"
			(at 0 0 90)
			(unlocked yes)
			(layer "B.Fab")
			(hide yes)
			(effects
				(font
					(size 1 1)
					(thickness 0.15)
				)
				(justify mirror)
			)
		)
		(property "Manufacturer" "Murata"
			(at 0 0 90)
			(unlocked yes)
			(layer "B.Fab")
			(hide yes)
			(effects
				(font
					(size 1 1)
					(thickness 0.15)
				)
				(justify mirror)
			)
		)
		(property "License" "Apache-2.0"
			(at 0 0 90)
			(unlocked yes)
			(layer "B.Fab")
			(hide yes)
			(effects
				(font
					(size 1 1)
					(thickness 0.15)
				)
				(justify mirror)
			)
		)
		(property "Author" "Antmicro"
			(at 0 0 90)
			(unlocked yes)
			(layer "B.Fab")
			(hide yes)
			(effects
				(font
					(size 1 1)
					(thickness 0.15)
				)
				(justify mirror)
			)
		)
		(property "Val" "1u"
			(at 0 0 90)
			(unlocked yes)
			(layer "B.Fab")
			(hide yes)
			(effects
				(font
					(size 1 1)
					(thickness 0.15)
				)
				(justify mirror)
			)
		)
		(property "Voltage" "25V"
			(at 0 0 90)
			(unlocked yes)
			(layer "B.Fab")
			(hide yes)
			(effects
				(font
					(size 1 1)
					(thickness 0.15)
				)
				(justify mirror)
			)
		)
		(property "Dielectric" "X5R"
			(at 0 0 90)
			(unlocked yes)
			(layer "B.Fab")
			(hide yes)
			(effects
				(font
					(size 1 1)
					(thickness 0.15)
				)
				(justify mirror)
			)
		)
		(sheetname "/X710-AT2 power/")
		(sheetfile "x710-at2-power.kicad_sch")
		(attr smd)
		(fp_rect
			(start -0.925 0.47)
			(end 0.925 -0.47)
			(stroke
				(width 0.05)
				(type default)
			)
			(fill no)
			(layer "B.CrtYd")
		)
		(fp_line
			(start 0.504 -0.248)
			(end -0.494 -0.248)
			(stroke
				(width 0.15)
				(type solid)
			)
			(layer "B.Fab")
		)
		(fp_line
			(start -0.494 -0.248)
			(end -0.494 0.25)
			(stroke
				(width 0.15)
				(type solid)
			)
			(layer "B.Fab")
		)
		(fp_line
			(start 0.504 0.25)
			(end 0.504 -0.248)
			(stroke
				(width 0.15)
				(type solid)
			)
			(layer "B.Fab")
		)
		(fp_line
			(start -0.494 0.25)
			(end 0.504 0.25)
			(stroke
				(width 0.15)
				(type solid)
			)
			(layer "B.Fab")
		)
		(fp_text user "${REFERENCE}"
			(at -0.939 -4.599 270)
			(layer "B.Fab")
			(effects
				(font
					(size 0.7 0.7)
					(thickness 0.15)
				)
				(justify left bottom mirror)
			)
		)
		(fp_text user "License: Apache-2.0"
			(at -0.939 -5.799 270)
			(layer "B.Fab")
			(effects
				(font
					(size 0.7 0.7)
					(thickness 0.15)
				)
				(justify left bottom mirror)
			)
		)
		(fp_text user "Author: Antmicro"
			(at -0.939 -3.399 270)
			(layer "B.Fab")
			(effects
				(font
					(size 0.7 0.7)
					(thickness 0.15)
				)
				(justify left bottom mirror)
			)
		)
		(pad "1" smd roundrect
			(at -0.48 0 90)
			(size 0.59 0.64)
			(layers "B.Cu" "B.Mask" "B.Paste")
			(roundrect_rratio 0.25)
			(net 23 "GND")
			(pintype "passive")
		)
		(pad "2" smd roundrect
			(at 0.48 0 90)
			(size 0.59 0.64)
			(layers "B.Cu" "B.Mask" "B.Paste")
			(roundrect_rratio 0.25)
			(net 14 "P1_AVDDL")
			(pintype "passive")
		)
	)
	(footprint "antmicro-footprints:C_0402_1005Metric"
		(layer "B.Cu")
		(at 131.424998 123.95 -90)
		(descr "Capacitor SMD 0402")
		(tags "capacitor SMD 0402")
		(property "Reference" "C59"
			(at -7.700002 -21.900002 90)
			(layer "B.SilkS")
			(effects
				(font
					(size 0.7 0.7)
					(thickness 0.15)
				)
				(justify mirror)
			)
		)
		(property "Value" "C_1u_0402"
			(at -1.022927 -2.155213 90)
			(layer "B.Fab")
			(effects
				(font
					(size 0.7 0.7)
					(thickness 0.15)
				)
				(justify left bottom mirror)
			)
		)
		(property "Datasheet" "https://product.tdk.com/en/search/capacitor/ceramic/mlcc/info?part_no=C1005X6S1A105K050BC"
			(at 0 0 90)
			(layer "B.Fab")
			(hide yes)
			(effects
				(font
					(size 1.27 1.27)
					(thickness 0.15)
				)
				(justify mirror)
			)
		)
		(property "Description" "SMD Multilayer Ceramic Capacitor, 1 µF, 10 V, 0402 [1005 Metric], ± 10%, X6S, C"
			(at 0 0 90)
			(layer "B.Fab")
			(hide yes)
			(effects
				(font
					(size 1.27 1.27)
					(thickness 0.15)
				)
				(justify mirror)
			)
		)
		(property "MPN" "C1005X6S1A105K050BC"
			(at 0 0 270)
			(unlocked yes)
			(layer "B.Fab")
			(hide yes)
			(effects
				(font
					(size 1 1)
					(thickness 0.15)
				)
				(justify mirror)
			)
		)
		(property "Manufacturer" "TDK"
			(at 0 0 270)
			(unlocked yes)
			(layer "B.Fab")
			(hide yes)
			(effects
				(font
					(size 1 1)
					(thickness 0.15)
				)
				(justify mirror)
			)
		)
		(property "License" "Apache-2.0"
			(at 0 0 270)
			(unlocked yes)
			(layer "B.Fab")
			(hide yes)
			(effects
				(font
					(size 1 1)
					(thickness 0.15)
				)
				(justify mirror)
			)
		)
		(property "Val" "1u"
			(at 0 0 270)
			(unlocked yes)
			(layer "B.Fab")
			(hide yes)
			(effects
				(font
					(size 1 1)
					(thickness 0.15)
				)
				(justify mirror)
			)
		)
		(property "Voltage" ""
			(at 0 0 270)
			(unlocked yes)
			(layer "B.Fab")
			(hide yes)
			(effects
				(font
					(size 1 1)
					(thickness 0.15)
				)
				(justify mirror)
			)
		)
		(property "Dielectric" ""
			(at 0 0 270)
			(unlocked yes)
			(layer "B.Fab")
			(hide yes)
			(effects
				(font
					(size 1 1)
					(thickness 0.15)
				)
				(justify mirror)
			)
		)
		(property "Author" "Antmicro"
			(at 0 0 270)
			(unlocked yes)
			(layer "B.Fab")
			(hide yes)
			(effects
				(font
					(size 1 1)
					(thickness 0.15)
				)
				(justify mirror)
			)
		)
		(sheetname "/TB Controller - Power/")
		(sheetfile "tb-power.kicad_sch")
		(attr smd)
		(fp_rect
			(start -0.925 0.47)
			(end 0.925 -0.47)
			(stroke
				(width 0.05)
				(type default)
			)
			(fill no)
			(layer "B.CrtYd")
		)
		(fp_line
			(start -0.494 0.25)
			(end 0.504 0.25)
			(stroke
				(width 0.15)
				(type solid)
			)
			(layer "B.Fab")
		)
		(fp_line
			(start 0.504 0.25)
			(end 0.504 -0.248)
			(stroke
				(width 0.15)
				(type solid)
			)
			(layer "B.Fab")
		)
		(fp_line
			(start -0.494 -0.248)
			(end -0.494 0.25)
			(stroke
				(width 0.15)
				(type solid)
			)
			(layer "B.Fab")
		)
		(fp_line
			(start 0.504 -0.248)
			(end -0.494 -0.248)
			(stroke
				(width 0.15)
				(type solid)
			)
			(layer "B.Fab")
		)
		(fp_text user "Author: Antmicro"
			(at -0.939 -3.399 90)
			(layer "B.Fab")
			(effects
				(font
					(size 0.7 0.7)
					(thickness 0.15)
				)
				(justify left bottom mirror)
			)
		)
		(fp_text user "${REFERENCE}"
			(at -0.939 -4.599 90)
			(layer "B.Fab")
			(effects
				(font
					(size 0.7 0.7)
					(thickness 0.15)
				)
				(justify left bottom mirror)
			)
		)
		(fp_text user "License: Apache-2.0"
			(at -0.939 -5.799 90)
			(layer "B.Fab")
			(effects
				(font
					(size 0.7 0.7)
					(thickness 0.15)
				)
				(justify left bottom mirror)
			)
		)
		(pad "1" smd roundrect
			(at -0.48 0 270)
			(size 0.59 0.64)
			(layers "B.Cu" "B.Mask" "B.Paste")
			(roundrect_rratio 0.25)
			(net 23 "GND")
			(pintype "passive")
		)
		(pad "2" smd roundrect
			(at 0.48 0 270)
			(size 0.59 0.64)
			(layers "B.Cu" "B.Mask" "B.Paste")
			(roundrect_rratio 0.25)
			(net 402 "Net-(C52-Pad2)")
			(pintype "passive")
		)
	)
	(footprint "antmicro-footprints:C_0402_1005Metric"
		(layer "B.Cu")
		(at 129.474999 122.000001 -90)
		(descr "Capacitor SMD 0402")
		(tags "capacitor SMD 0402")
		(property "Reference" "C61"
			(at -7.700002 -21.900002 90)
			(layer "B.SilkS")
			(effects
				(font
					(size 0.7 0.7)
					(thickness 0.15)
				)
				(justify mirror)
			)
		)
		(property "Value" "C_1u_0402"
			(at -1.022927 -2.155213 90)
			(layer "B.Fab")
			(effects
				(font
					(size 0.7 0.7)
					(thickness 0.15)
				)
				(justify left bottom mirror)
			)
		)
		(property "Datasheet" "https://product.tdk.com/en/search/capacitor/ceramic/mlcc/info?part_no=C1005X6S1A105K050BC"
			(at 0 0 90)
			(layer "B.Fab")
			(hide yes)
			(effects
				(font
					(size 1.27 1.27)
					(thickness 0.15)
				)
				(justify mirror)
			)
		)
		(property "Description" "SMD Multilayer Ceramic Capacitor, 1 µF, 10 V, 0402 [1005 Metric], ± 10%, X6S, C"
			(at 0 0 90)
			(layer "B.Fab")
			(hide yes)
			(effects
				(font
					(size 1.27 1.27)
					(thickness 0.15)
				)
				(justify mirror)
			)
		)
		(property "MPN" "C1005X6S1A105K050BC"
			(at 0 0 270)
			(unlocked yes)
			(layer "B.Fab")
			(hide yes)
			(effects
				(font
					(size 1 1)
					(thickness 0.15)
				)
				(justify mirror)
			)
		)
		(property "Manufacturer" "TDK"
			(at 0 0 270)
			(unlocked yes)
			(layer "B.Fab")
			(hide yes)
			(effects
				(font
					(size 1 1)
					(thickness 0.15)
				)
				(justify mirror)
			)
		)
		(property "License" "Apache-2.0"
			(at 0 0 270)
			(unlocked yes)
			(layer "B.Fab")
			(hide yes)
			(effects
				(font
					(size 1 1)
					(thickness 0.15)
				)
				(justify mirror)
			)
		)
		(property "Val" "1u"
			(at 0 0 270)
			(unlocked yes)
			(layer "B.Fab")
			(hide yes)
			(effects
				(font
					(size 1 1)
					(thickness 0.15)
				)
				(justify mirror)
			)
		)
		(property "Voltage" ""
			(at 0 0 270)
			(unlocked yes)
			(layer "B.Fab")
			(hide yes)
			(effects
				(font
					(size 1 1)
					(thickness 0.15)
				)
				(justify mirror)
			)
		)
		(property "Dielectric" ""
			(at 0 0 270)
			(unlocked yes)
			(layer "B.Fab")
			(hide yes)
			(effects
				(font
					(size 1 1)
					(thickness 0.15)
				)
				(justify mirror)
			)
		)
		(property "Author" "Antmicro"
			(at 0 0 270)
			(unlocked yes)
			(layer "B.Fab")
			(hide yes)
			(effects
				(font
					(size 1 1)
					(thickness 0.15)
				)
				(justify mirror)
			)
		)
		(sheetname "/TB Controller - Power/")
		(sheetfile "tb-power.kicad_sch")
		(attr smd)
		(fp_rect
			(start -0.925 0.47)
			(end 0.925 -0.47)
			(stroke
				(width 0.05)
				(type default)
			)
			(fill no)
			(layer "B.CrtYd")
		)
		(fp_line
			(start -0.494 0.25)
			(end 0.504 0.25)
			(stroke
				(width 0.15)
				(type solid)
			)
			(layer "B.Fab")
		)
		(fp_line
			(start 0.504 0.25)
			(end 0.504 -0.248)
			(stroke
				(width 0.15)
				(type solid)
			)
			(layer "B.Fab")
		)
		(fp_line
			(start -0.494 -0.248)
			(end -0.494 0.25)
			(stroke
				(width 0.15)
				(type solid)
			)
			(layer "B.Fab")
		)
		(fp_line
			(start 0.504 -0.248)
			(end -0.494 -0.248)
			(stroke
				(width 0.15)
				(type solid)
			)
			(layer "B.Fab")
		)
		(fp_text user "${REFERENCE}"
			(at -0.939 -4.599 90)
			(layer "B.Fab")
			(effects
				(font
					(size 0.7 0.7)
					(thickness 0.15)
				)
				(justify left bottom mirror)
			)
		)
		(fp_text user "License: Apache-2.0"
			(at -0.939 -5.799 90)
			(layer "B.Fab")
			(effects
				(font
					(size 0.7 0.7)
					(thickness 0.15)
				)
				(justify left bottom mirror)
			)
		)
		(fp_text user "Author: Antmicro"
			(at -0.939 -3.399 90)
			(layer "B.Fab")
			(effects
				(font
					(size 0.7 0.7)
					(thickness 0.15)
				)
				(justify left bottom mirror)
			)
		)
		(pad "1" smd roundrect
			(at -0.48 0 270)
			(size 0.59 0.64)
			(layers "B.Cu" "B.Mask" "B.Paste")
			(roundrect_rratio 0.25)
			(net 23 "GND")
			(pintype "passive")
		)
		(pad "2" smd roundrect
			(at 0.48 0 270)
			(size 0.59 0.64)
			(layers "B.Cu" "B.Mask" "B.Paste")
			(roundrect_rratio 0.25)
			(net 404 "Net-(C58-Pad2)")
			(pintype "passive")
		)
	)
	(footprint "antmicro-footprints:C_0402_1005Metric"
		(layer "B.Cu")
		(at 147.481865 75.285116)
		(descr "Capacitor SMD 0402")
		(tags "capacitor SMD 0402")
		(property "Reference" "C234"
			(at 18.618135 9.464883 180)
			(layer "B.SilkS")
			(effects
				(font
					(size 0.7 0.7)
					(thickness 0.15)
				)
				(justify mirror)
			)
		)
		(property "Value" "C_1u_25V_0402"
			(at -1.022927 -2.155213 180)
			(layer "B.Fab")
			(effects
				(font
					(size 0.7 0.7)
					(thickness 0.15)
				)
				(justify left bottom mirror)
			)
		)
		(property "Datasheet" "https://www.murata.com/products/productdetail?partno=GRM155R61E105KE11%23"
			(at 0 0 180)
			(layer "B.Fab")
			(hide yes)
			(effects
				(font
					(size 1.27 1.27)
					(thickness 0.15)
				)
				(justify mirror)
			)
		)
		(property "Description" "SMD Multilayer Ceramic Capacitor, 1 µF, 25 V, 0402 [1005 Metric], ± 10%, X5R, GRM Series"
			(at 0 0 180)
			(layer "B.Fab")
			(hide yes)
			(effects
				(font
					(size 1.27 1.27)
					(thickness 0.15)
				)
				(justify mirror)
			)
		)
		(property "MPN" "GRM155R61E105KE11J"
			(at 0 0 0)
			(unlocked yes)
			(layer "B.Fab")
			(hide yes)
			(effects
				(font
					(size 1 1)
					(thickness 0.15)
				)
				(justify mirror)
			)
		)
		(property "Manufacturer" "Murata"
			(at 0 0 0)
			(unlocked yes)
			(layer "B.Fab")
			(hide yes)
			(effects
				(font
					(size 1 1)
					(thickness 0.15)
				)
				(justify mirror)
			)
		)
		(property "License" "Apache-2.0"
			(at 0 0 0)
			(unlocked yes)
			(layer "B.Fab")
			(hide yes)
			(effects
				(font
					(size 1 1)
					(thickness 0.15)
				)
				(justify mirror)
			)
		)
		(property "Author" "Antmicro"
			(at 0 0 0)
			(unlocked yes)
			(layer "B.Fab")
			(hide yes)
			(effects
				(font
					(size 1 1)
					(thickness 0.15)
				)
				(justify mirror)
			)
		)
		(property "Val" "1u"
			(at 0 0 0)
			(unlocked yes)
			(layer "B.Fab")
			(hide yes)
			(effects
				(font
					(size 1 1)
					(thickness 0.15)
				)
				(justify mirror)
			)
		)
		(property "Voltage" "25V"
			(at 0 0 0)
			(unlocked yes)
			(layer "B.Fab")
			(hide yes)
			(effects
				(font
					(size 1 1)
					(thickness 0.15)
				)
				(justify mirror)
			)
		)
		(property "Dielectric" "X5R"
			(at 0 0 0)
			(unlocked yes)
			(layer "B.Fab")
			(hide yes)
			(effects
				(font
					(size 1 1)
					(thickness 0.15)
				)
				(justify mirror)
			)
		)
		(sheetname "/X710-AT2 power/")
		(sheetfile "x710-at2-power.kicad_sch")
		(attr smd)
		(fp_rect
			(start -0.925 0.47)
			(end 0.925 -0.47)
			(stroke
				(width 0.05)
				(type default)
			)
			(fill no)
			(layer "B.CrtYd")
		)
		(fp_line
			(start -0.494 -0.248)
			(end -0.494 0.25)
			(stroke
				(width 0.15)
				(type solid)
			)
			(layer "B.Fab")
		)
		(fp_line
			(start -0.494 0.25)
			(end 0.504 0.25)
			(stroke
				(width 0.15)
				(type solid)
			)
			(layer "B.Fab")
		)
		(fp_line
			(start 0.504 -0.248)
			(end -0.494 -0.248)
			(stroke
				(width 0.15)
				(type solid)
			)
			(layer "B.Fab")
		)
		(fp_line
			(start 0.504 0.25)
			(end 0.504 -0.248)
			(stroke
				(width 0.15)
				(type solid)
			)
			(layer "B.Fab")
		)
		(fp_text user "Author: Antmicro"
			(at -0.939 -3.399 180)
			(layer "B.Fab")
			(effects
				(font
					(size 0.7 0.7)
					(thickness 0.15)
				)
				(justify left bottom mirror)
			)
		)
		(fp_text user "License: Apache-2.0"
			(at -0.939 -5.799 180)
			(layer "B.Fab")
			(effects
				(font
					(size 0.7 0.7)
					(thickness 0.15)
				)
				(justify left bottom mirror)
			)
		)
		(fp_text user "${REFERENCE}"
			(at -0.939 -4.599 180)
			(layer "B.Fab")
			(effects
				(font
					(size 0.7 0.7)
					(thickness 0.15)
				)
				(justify left bottom mirror)
			)
		)
		(pad "1" smd roundrect
			(at -0.48 0)
			(size 0.59 0.64)
			(layers "B.Cu" "B.Mask" "B.Paste")
			(roundrect_rratio 0.25)
			(net 23 "GND")
			(pintype "passive")
		)
		(pad "2" smd roundrect
			(at 0.48 0)
			(size 0.59 0.64)
			(layers "B.Cu" "B.Mask" "B.Paste")
			(roundrect_rratio 0.25)
			(net 9 "VCCD")
			(pintype "passive")
		)
	)
	(footprint "antmicro-footprints:R_0402_1005Metric"
		(layer "B.Cu")
		(at 136.5 123.15)
		(descr "Resistor SMD 0402")
		(tags "resistor SMD 0402")
		(property "Reference" "R49"
			(at 19.525001 -7.450001 180)
			(layer "B.SilkS")
			(effects
				(font
					(size 0.7 0.7)
					(thickness 0.15)
				)
				(justify mirror)
			)
		)
		(property "Value" "R_10k_0402"
			(at -1.011843 -1.772047 180)
			(layer "B.Fab")
			(effects
				(font
					(size 0.7 0.7)
					(thickness 0.15)
				)
				(justify left bottom mirror)
			)
		)
		(property "Datasheet" "https://www.bourns.com/docs/product-datasheets/cr.pdf"
			(at 0 0 180)
			(layer "B.Fab")
			(hide yes)
			(effects
				(font
					(size 1.27 1.27)
					(thickness 0.15)
				)
				(justify mirror)
			)
		)
		(property "Description" "SMD Chip Resistor, 10 kohm, ± 1%, 62.5 mW, 0402 [1005 Metric], Thick Film, General Purpose"
			(at 0 0 180)
			(layer "B.Fab")
			(hide yes)
			(effects
				(font
					(size 1.27 1.27)
					(thickness 0.15)
				)
				(justify mirror)
			)
		)
		(property "MPN" "CR0402-FX-1002GLF"
			(at 0 0 0)
			(unlocked yes)
			(layer "B.Fab")
			(hide yes)
			(effects
				(font
					(size 1 1)
					(thickness 0.15)
				)
				(justify mirror)
			)
		)
		(property "Manufacturer" "Bourns"
			(at 0 0 0)
			(unlocked yes)
			(layer "B.Fab")
			(hide yes)
			(effects
				(font
					(size 1 1)
					(thickness 0.15)
				)
				(justify mirror)
			)
		)
		(property "License" "Apache-2.0"
			(at 0 0 0)
			(unlocked yes)
			(layer "B.Fab")
			(hide yes)
			(effects
				(font
					(size 1 1)
					(thickness 0.15)
				)
				(justify mirror)
			)
		)
		(property "Val" "10k"
			(at 0 0 0)
			(unlocked yes)
			(layer "B.Fab")
			(hide yes)
			(effects
				(font
					(size 1 1)
					(thickness 0.15)
				)
				(justify mirror)
			)
		)
		(property "Tolerance" "1%"
			(at 0 0 0)
			(unlocked yes)
			(layer "B.Fab")
			(hide yes)
			(effects
				(font
					(size 1 1)
					(thickness 0.15)
				)
				(justify mirror)
			)
		)
		(property "Author" "Antmicro"
			(at 0 0 0)
			(unlocked yes)
			(layer "B.Fab")
			(hide yes)
			(effects
				(font
					(size 1 1)
					(thickness 0.15)
				)
				(justify mirror)
			)
		)
		(sheetname "/TB Controller/")
		(sheetfile "tb.kicad_sch")
		(attr smd)
		(fp_rect
			(start -0.925 0.47)
			(end 0.925 -0.47)
			(stroke
				(width 0.05)
				(type default)
			)
			(fill no)
			(layer "B.CrtYd")
		)
		(fp_rect
			(start -0.5 0.25)
			(end 0.5 -0.25)
			(stroke
				(width 0.15)
				(type solid)
			)
			(fill no)
			(layer "B.Fab")
		)
		(fp_text user "License: Apache-2.0"
			(at -0.95 -5.169 180)
			(layer "B.Fab")
			(effects
				(font
					(size 0.7 0.7)
					(thickness 0.15)
				)
				(justify left bottom mirror)
			)
		)
		(fp_text user "${REFERENCE}"
			(at -0.95 -3.168 180)
			(layer "B.Fab")
			(effects
				(font
					(size 0.7 0.7)
					(thickness 0.15)
				)
				(justify left bottom mirror)
			)
		)
		(fp_text user "Author: Antmicro"
			(at -0.95 -4.169 180)
			(layer "B.Fab")
			(effects
				(font
					(size 0.7 0.7)
					(thickness 0.15)
				)
				(justify left bottom mirror)
			)
		)
		(pad "1" smd roundrect
			(at -0.48 0)
			(size 0.59 0.64)
			(layers "B.Cu" "B.Mask" "B.Paste")
			(roundrect_rratio 0.25)
			(net 192 "Net-(U4C-POC_GPIO_1)")
			(pintype "passive")
		)
		(pad "2" smd roundrect
			(at 0.48 0)
			(size 0.59 0.64)
			(layers "B.Cu" "B.Mask" "B.Paste")
			(roundrect_rratio 0.25)
			(net 57 "+3V3_TB")
			(pintype "passive")
		)
	)
	(footprint "antmicro-footprints:C_Pol_EIA-A"
		(layer "B.Cu")
		(at 161 103 -90)
		(property "Reference" "C326"
			(at -5 -0.5 90)
			(layer "B.SilkS")
			(effects
				(font
					(size 0.7 0.7)
					(thickness 0.15)
				)
				(justify left bottom mirror)
			)
		)
		(property "Value" "C_Pol_100u_6V_KEMET-T490-A"
			(at 0 -2 90)
			(layer "B.Fab")
			(effects
				(font
					(size 0.7 0.7)
					(thickness 0.15)
				)
				(justify left bottom mirror)
			)
		)
		(property "Datasheet" "https://www.kemet.com/en/us/capacitors/product/T490A107M006ATE800.html"
			(at 0 0 90)
			(layer "B.Fab")
			(hide yes)
			(effects
				(font
					(size 1.27 1.27)
					(thickness 0.15)
				)
				(justify mirror)
			)
		)
		(property "Description" "Surface Mount Tantalum Capacitor,  Solid SMD 6V 100uF 1206 20% ESR=800mOhms"
			(at 0 0 90)
			(layer "B.Fab")
			(hide yes)
			(effects
				(font
					(size 1.27 1.27)
					(thickness 0.15)
				)
				(justify mirror)
			)
		)
		(property "Val" "100u"
			(at 0 0 270)
			(unlocked yes)
			(layer "B.Fab")
			(hide yes)
			(effects
				(font
					(size 1 1)
					(thickness 0.15)
				)
				(justify mirror)
			)
		)
		(property "MPN" "T490A107M006ATE800"
			(at 0 0 270)
			(unlocked yes)
			(layer "B.Fab")
			(hide yes)
			(effects
				(font
					(size 1 1)
					(thickness 0.15)
				)
				(justify mirror)
			)
		)
		(property "Manufacturer" "KEMET"
			(at 0 0 270)
			(unlocked yes)
			(layer "B.Fab")
			(hide yes)
			(effects
				(font
					(size 1 1)
					(thickness 0.15)
				)
				(justify mirror)
			)
		)
		(property "License" "Apache-2.0"
			(at 0 0 270)
			(unlocked yes)
			(layer "B.Fab")
			(hide yes)
			(effects
				(font
					(size 1 1)
					(thickness 0.15)
				)
				(justify mirror)
			)
		)
		(property "Author" "Antmicro"
			(at 0 0 270)
			(unlocked yes)
			(layer "B.Fab")
			(hide yes)
			(effects
				(font
					(size 1 1)
					(thickness 0.15)
				)
				(justify mirror)
			)
		)
		(property "Voltage" "6V"
			(at 0 0 270)
			(unlocked yes)
			(layer "B.Fab")
			(hide yes)
			(effects
				(font
					(size 1 1)
					(thickness 0.15)
				)
				(justify mirror)
			)
		)
		(property "Dielectric" "template_dielectric"
			(at 0 0 270)
			(unlocked yes)
			(layer "B.Fab")
			(hide yes)
			(effects
				(font
					(size 1 1)
					(thickness 0.15)
				)
				(justify mirror)
			)
		)
		(sheetname "/X710-AT2 power/")
		(sheetfile "x710-at2-power.kicad_sch")
		(attr smd)
		(fp_line
			(start -1.95 1.25)
			(end -1.95 0.95)
			(stroke
				(width 0.12)
				(type solid)
			)
			(layer "B.SilkS")
		)
		(fp_line
			(start -2.1 1.1)
			(end -1.8 1.1)
			(stroke
				(width 0.12)
				(type solid)
			)
			(layer "B.SilkS")
		)
		(fp_line
			(start -1.5 0.85)
			(end 1.5 0.85)
			(stroke
				(width 0.12)
				(type solid)
			)
			(layer "B.SilkS")
		)
		(fp_line
			(start -1.5 0.75)
			(end -1.5 0.85)
			(stroke
				(width 0.12)
				(type solid)
			)
			(layer "B.SilkS")
		)
		(fp_line
			(start 1.5 0.75)
			(end 1.5 0.85)
			(stroke
				(width 0.12)
				(type solid)
			)
			(layer "B.SilkS")
		)
		(fp_line
			(start -1.5 -0.75)
			(end -1.5 -0.85)
			(stroke
				(width 0.12)
				(type solid)
			)
			(layer "B.SilkS")
		)
		(fp_line
			(start 1.5 -0.75)
			(end 1.5 -0.85)
			(stroke
				(width 0.12)
				(type solid)
			)
			(layer "B.SilkS")
		)
		(fp_line
			(start 1.5 -0.85)
			(end -1.5 -0.85)
			(stroke
				(width 0.12)
				(type solid)
			)
			(layer "B.SilkS")
		)
		(fp_line
			(start 1.7 1.05)
			(end -1.7 1.05)
			(stroke
				(width 0.05)
				(type solid)
			)
			(layer "B.CrtYd")
		)
		(fp_line
			(start -2.05 0.85)
			(end -2.05 -0.85)
			(stroke
				(width 0.05)
				(type solid)
			)
			(layer "B.CrtYd")
		)
		(fp_line
			(start -1.7 0.85)
			(end -1.7 1.05)
			(stroke
				(width 0.05)
				(type solid)
			)
			(layer "B.CrtYd")
		)
		(fp_line
			(start -1.7 0.85)
			(end -2.05 0.85)
			(stroke
				(width 0.05)
				(type solid)
			)
			(layer "B.CrtYd")
		)
		(fp_line
			(start 1.7 0.85)
			(end 1.7 1.05)
			(stroke
				(width 0.05)
				(type solid)
			)
			(layer "B.CrtYd")
		)
		(fp_line
			(start 2.05 0.85)
			(end 1.7 0.85)
			(stroke
				(width 0.05)
				(type solid)
			)
			(layer "B.CrtYd")
		)
		(fp_line
			(start 2.05 0.85)
			(end 2.05 -0.85)
			(stroke
				(width 0.05)
				(type solid)
			)
			(layer "B.CrtYd")
		)
		(fp_line
			(start -1.7 -0.85)
			(end -2.05 -0.85)
			(stroke
				(width 0.05)
				(type solid)
			)
			(layer "B.CrtYd")
		)
		(fp_line
			(start 2.05 -0.85)
			(end 1.7 -0.85)
			(stroke
				(width 0.05)
				(type solid)
			)
			(layer "B.CrtYd")
		)
		(fp_line
			(start -1.7 -1.05)
			(end -1.7 -0.85)
			(stroke
				(width 0.05)
				(type solid)
			)
			(layer "B.CrtYd")
		)
		(fp_line
			(start 1.7 -1.05)
			(end 1.7 -0.85)
			(stroke
				(width 0.05)
				(type solid)
			)
			(layer "B.CrtYd")
		)
		(fp_line
			(start 1.7 -1.05)
			(end -1.7 -1.05)
			(stroke
				(width 0.05)
				(type solid)
			)
			(layer "B.CrtYd")
		)
		(fp_rect
			(start -1.601 0.802)
			(end 1.6 -0.8)
			(stroke
				(width 0.1)
				(type solid)
			)
			(fill no)
			(layer "B.Fab")
		)
		(fp_text user "Author: Antmicro"
			(at -2.1 -6.198 90)
			(layer "B.Fab")
			(effects
				(font
					(size 0.7 0.7)
					(thickness 0.15)
				)
				(justify left bottom mirror)
			)
		)
		(fp_text user "${REFERENCE}"
			(at -2.1 -4.198 90)
			(layer "B.Fab")
			(effects
				(font
					(size 0.7 0.7)
					(thickness 0.15)
				)
				(justify left bottom mirror)
			)
		)
		(fp_text user "License: Apache-2.0"
			(at -2.1 -5.198 90)
			(layer "B.Fab")
			(effects
				(font
					(size 0.7 0.7)
					(thickness 0.15)
				)
				(justify left bottom mirror)
			)
		)
		(pad "1" smd roundrect
			(at -1.2 0 270)
			(size 1.2 1.2)
			(layers "B.Cu" "B.Mask" "B.Paste")
			(roundrect_rratio 0.1)
			(net 136 "+1V0")
			(pintype "passive")
		)
		(pad "2" smd roundrect
			(at 1.2 0 270)
			(size 1.2 1.2)
			(layers "B.Cu" "B.Mask" "B.Paste")
			(roundrect_rratio 0.1)
			(net 23 "GND")
			(pintype "passive")
		)
	)
	(footprint "antmicro-footprints:SOD-523"
		(layer "B.Cu")
		(at 121.5 76)
		(property "Reference" "D12"
			(at 0.9 -0.8 180)
			(layer "B.SilkS")
			(effects
				(font
					(size 0.7 0.7)
					(thickness 0.15)
				)
				(justify left bottom mirror)
			)
		)
		(property "Value" "PESD5Z5_0F"
			(at 0 -1.499 180)
			(layer "B.Fab")
			(effects
				(font
					(size 0.7 0.7)
					(thickness 0.15)
				)
				(justify left bottom mirror)
			)
		)
		(property "Datasheet" "https://assets.nexperia.com/documents/data-sheet/PESD5Z5_0.pdf"
			(at 0 0 180)
			(layer "B.Fab")
			(hide yes)
			(effects
				(font
					(size 1.27 1.27)
					(thickness 0.15)
				)
				(justify mirror)
			)
		)
		(property "Description" "Unidirectional TVS, 30 kV,  SOD-523, 5 V, 89 pF"
			(at 0 0 180)
			(layer "B.Fab")
			(hide yes)
			(effects
				(font
					(size 1.27 1.27)
					(thickness 0.15)
				)
				(justify mirror)
			)
		)
		(property "Manufacturer" "Nexperia"
			(at 0 0 0)
			(unlocked yes)
			(layer "B.Fab")
			(hide yes)
			(effects
				(font
					(size 1 1)
					(thickness 0.15)
				)
				(justify mirror)
			)
		)
		(property "MPN" "PESD5Z5.0F"
			(at 0 0 0)
			(unlocked yes)
			(layer "B.Fab")
			(hide yes)
			(effects
				(font
					(size 1 1)
					(thickness 0.15)
				)
				(justify mirror)
			)
		)
		(property "Author" "Antmicro"
			(at 0 0 0)
			(unlocked yes)
			(layer "B.Fab")
			(hide yes)
			(effects
				(font
					(size 1 1)
					(thickness 0.15)
				)
				(justify mirror)
			)
		)
		(property "License" "Apache-2.0"
			(at 0 0 0)
			(unlocked yes)
			(layer "B.Fab")
			(hide yes)
			(effects
				(font
					(size 1 1)
					(thickness 0.15)
				)
				(justify mirror)
			)
		)
		(sheetname "/Fan controller/")
		(sheetfile "fan-controller.kicad_sch")
		(attr smd)
		(fp_line
			(start -0.35 0.5)
			(end -0.35 -0.5)
			(stroke
				(width 0.15)
				(type solid)
			)
			(layer "B.SilkS")
		)
		(fp_rect
			(start -1 0.6)
			(end 1 -0.6)
			(stroke
				(width 0.05)
				(type solid)
			)
			(fill no)
			(layer "B.CrtYd")
		)
		(fp_line
			(start -0.652 -0.423)
			(end -0.652 0.425)
			(stroke
				(width 0.15)
				(type solid)
			)
			(layer "B.Fab")
		)
		(fp_line
			(start -0.652 -0.423)
			(end 0.65 -0.423)
			(stroke
				(width 0.15)
				(type solid)
			)
			(layer "B.Fab")
		)
		(fp_line
			(start -0.652 0.425)
			(end 0.65 0.425)
			(stroke
				(width 0.15)
				(type solid)
			)
			(layer "B.Fab")
		)
		(fp_line
			(start -0.35 0.4)
			(end -0.35 -0.4)
			(stroke
				(width 0.15)
				(type solid)
			)
			(layer "B.Fab")
		)
		(fp_line
			(start 0.65 0.425)
			(end 0.65 -0.423)
			(stroke
				(width 0.15)
				(type solid)
			)
			(layer "B.Fab")
		)
		(fp_text user "Author: Antmicro"
			(at -1.276 -4.7 180)
			(layer "B.Fab")
			(effects
				(font
					(size 0.7 0.7)
					(thickness 0.15)
				)
				(justify left bottom mirror)
			)
		)
		(fp_text user "${REFERENCE}"
			(at -1.276 -3.499 180)
			(layer "B.Fab")
			(effects
				(font
					(size 0.7 0.7)
					(thickness 0.15)
				)
				(justify left bottom mirror)
			)
		)
		(fp_text user "License: Apache-2.0"
			(at -1.276 -5.9 180)
			(layer "B.Fab")
			(effects
				(font
					(size 0.7 0.7)
					(thickness 0.15)
				)
				(justify left bottom mirror)
			)
		)
		(pad "1" smd roundrect
			(at -0.701 0)
			(size 0.5 0.6)
			(layers "B.Cu" "B.Mask" "B.Paste")
			(roundrect_rratio 0.25)
			(net 154 "/Fan controller/PWM")
			(pinfunction "C")
			(pintype "passive")
		)
		(pad "2" smd roundrect
			(at 0.699 0)
			(size 0.5 0.6)
			(layers "B.Cu" "B.Mask" "B.Paste")
			(roundrect_rratio 0.25)
			(net 23 "GND")
			(pinfunction "A")
			(pintype "passive")
		)
	)
	(footprint "antmicro-footprints:TP_SMD_0.75mm"
		(layer "B.Cu")
		(at 149 65 180)
		(property "Reference" "TP20"
			(at 0.6 -0.4 0)
			(layer "B.SilkS")
			(effects
				(font
					(size 0.7 0.7)
					(thickness 0.15)
				)
				(justify left bottom mirror)
			)
		)
		(property "Value" "TP_0.75mm_SMD"
			(at 0 -1.2 0)
			(layer "B.Fab")
			(effects
				(font
					(size 0.7 0.7)
					(thickness 0.15)
				)
				(justify left bottom mirror)
			)
		)
		(property "Description" "SMT test point"
			(at 0 0 0)
			(layer "B.Fab")
			(hide yes)
			(effects
				(font
					(size 1.27 1.27)
					(thickness 0.15)
				)
				(justify mirror)
			)
		)
		(property "MPN" ""
			(at 0 0 180)
			(unlocked yes)
			(layer "B.Fab")
			(hide yes)
			(effects
				(font
					(size 1 1)
					(thickness 0.15)
				)
				(justify mirror)
			)
		)
		(property "Manufacturer" ""
			(at 0 0 180)
			(unlocked yes)
			(layer "B.Fab")
			(hide yes)
			(effects
				(font
					(size 1 1)
					(thickness 0.15)
				)
				(justify mirror)
			)
		)
		(property "Author" "Antmicro"
			(at 0 0 180)
			(unlocked yes)
			(layer "B.Fab")
			(hide yes)
			(effects
				(font
					(size 1 1)
					(thickness 0.15)
				)
				(justify mirror)
			)
		)
		(property "License" "Apache-2.0"
			(at 0 0 180)
			(unlocked yes)
			(layer "B.Fab")
			(hide yes)
			(effects
				(font
					(size 1 1)
					(thickness 0.15)
				)
				(justify mirror)
			)
		)
		(sheetname "/X710-AT2 power/")
		(sheetfile "x710-at2-power.kicad_sch")
		(attr exclude_from_pos_files exclude_from_bom)
		(fp_circle
			(center 0 0)
			(end 0.475 0)
			(stroke
				(width 0.05)
				(type default)
			)
			(fill no)
			(layer "B.CrtYd")
		)
		(fp_text user "Author: Antmicro"
			(at -0.4 -3.901 0)
			(layer "B.Fab")
			(effects
				(font
					(size 0.7 0.7)
					(thickness 0.15)
				)
				(justify left bottom mirror)
			)
		)
		(fp_text user "${REFERENCE}"
			(at -0.4 -2.7 0)
			(layer "B.Fab")
			(effects
				(font
					(size 0.7 0.7)
					(thickness 0.15)
				)
				(justify left bottom mirror)
			)
		)
		(fp_text user "License: Apache-2.0"
			(at -0.4 -5.101 0)
			(layer "B.Fab")
			(effects
				(font
					(size 0.7 0.7)
					(thickness 0.15)
				)
				(justify left bottom mirror)
			)
		)
		(pad "1" smd circle
			(at 0 0 180)
			(size 0.75 0.75)
			(layers "B.Cu" "B.Mask")
			(net 1 "VCCA")
			(pinfunction "1")
			(pintype "passive")
		)
	)
	(footprint "antmicro-footprints:R_0402_1005Metric"
		(layer "B.Cu")
		(at 140.4 136.580998 180)
		(descr "Resistor SMD 0402")
		(tags "resistor SMD 0402")
		(property "Reference" "R12"
			(at -19.525001 8.1 0)
			(layer "B.SilkS")
			(effects
				(font
					(size 0.7 0.7)
					(thickness 0.15)
				)
				(justify mirror)
			)
		)
		(property "Value" "R_3k3_0402"
			(at -1.011843 -1.772047 0)
			(layer "B.Fab")
			(effects
				(font
					(size 0.7 0.7)
					(thickness 0.15)
				)
				(justify left bottom mirror)
			)
		)
		(property "Datasheet" "https://www.bourns.com/docs/product-datasheets/cr.pdf"
			(at 0 0 0)
			(layer "B.Fab")
			(hide yes)
			(effects
				(font
					(size 1.27 1.27)
					(thickness 0.15)
				)
				(justify mirror)
			)
		)
		(property "Description" "SMD Chip Resistor, 3.3 kohm, ± 1%, 63 mW, 0402 [1005 Metric], Thick Film, General Purpose"
			(at 0 0 0)
			(layer "B.Fab")
			(hide yes)
			(effects
				(font
					(size 1.27 1.27)
					(thickness 0.15)
				)
				(justify mirror)
			)
		)
		(property "MPN" "CR0402-FX-3301GLF"
			(at 0 0 180)
			(unlocked yes)
			(layer "B.Fab")
			(hide yes)
			(effects
				(font
					(size 1 1)
					(thickness 0.15)
				)
				(justify mirror)
			)
		)
		(property "Manufacturer" "Bourns"
			(at 0 0 180)
			(unlocked yes)
			(layer "B.Fab")
			(hide yes)
			(effects
				(font
					(size 1 1)
					(thickness 0.15)
				)
				(justify mirror)
			)
		)
		(property "License" "Apache-2.0"
			(at 0 0 180)
			(unlocked yes)
			(layer "B.Fab")
			(hide yes)
			(effects
				(font
					(size 1 1)
					(thickness 0.15)
				)
				(justify mirror)
			)
		)
		(property "Val" "3k3"
			(at 0 0 180)
			(unlocked yes)
			(layer "B.Fab")
			(hide yes)
			(effects
				(font
					(size 1 1)
					(thickness 0.15)
				)
				(justify mirror)
			)
		)
		(property "Tolerance" "1%"
			(at 0 0 180)
			(unlocked yes)
			(layer "B.Fab")
			(hide yes)
			(effects
				(font
					(size 1 1)
					(thickness 0.15)
				)
				(justify mirror)
			)
		)
		(property "Author" "Antmicro"
			(at 0 0 180)
			(unlocked yes)
			(layer "B.Fab")
			(hide yes)
			(effects
				(font
					(size 1 1)
					(thickness 0.15)
				)
				(justify mirror)
			)
		)
		(sheetname "/PD and TB DC-DC/")
		(sheetfile "PD_and_TB_DC_DC.kicad_sch")
		(attr smd)
		(fp_rect
			(start -0.925 0.47)
			(end 0.925 -0.47)
			(stroke
				(width 0.05)
				(type default)
			)
			(fill no)
			(layer "B.CrtYd")
		)
		(fp_rect
			(start -0.5 0.25)
			(end 0.5 -0.25)
			(stroke
				(width 0.15)
				(type solid)
			)
			(fill no)
			(layer "B.Fab")
		)
		(fp_text user "Author: Antmicro"
			(at -0.95 -4.169 0)
			(layer "B.Fab")
			(effects
				(font
					(size 0.7 0.7)
					(thickness 0.15)
				)
				(justify left bottom mirror)
			)
		)
		(fp_text user "License: Apache-2.0"
			(at -0.95 -5.169 0)
			(layer "B.Fab")
			(effects
				(font
					(size 0.7 0.7)
					(thickness 0.15)
				)
				(justify left bottom mirror)
			)
		)
		(fp_text user "${REFERENCE}"
			(at -0.95 -3.168 0)
			(layer "B.Fab")
			(effects
				(font
					(size 0.7 0.7)
					(thickness 0.15)
				)
				(justify left bottom mirror)
			)
		)
		(pad "1" smd roundrect
			(at -0.48 0 180)
			(size 0.59 0.64)
			(layers "B.Cu" "B.Mask" "B.Paste")
			(roundrect_rratio 0.25)
			(net 304 "/PD and TB DC-DC/TPS_3V3")
			(pintype "passive")
		)
		(pad "2" smd roundrect
			(at 0.48 0 180)
			(size 0.59 0.64)
			(layers "B.Cu" "B.Mask" "B.Paste")
			(roundrect_rratio 0.25)
			(net 198 "Net-(U3-I2C_SDA2)")
			(pintype "passive")
		)
	)
	(footprint "antmicro-footprints:C_0402_1005Metric"
		(layer "B.Cu")
		(at 123.624999 123.950001 -90)
		(descr "Capacitor SMD 0402")
		(tags "capacitor SMD 0402")
		(property "Reference" "C70"
			(at -4.750001 -22.975001 90)
			(layer "B.SilkS")
			(effects
				(font
					(size 0.7 0.7)
					(thickness 0.15)
				)
				(justify mirror)
			)
		)
		(property "Value" "C_1u_0402"
			(at -1.022927 -2.155213 90)
			(layer "B.Fab")
			(effects
				(font
					(size 0.7 0.7)
					(thickness 0.15)
				)
				(justify left bottom mirror)
			)
		)
		(property "Datasheet" "https://product.tdk.com/en/search/capacitor/ceramic/mlcc/info?part_no=C1005X6S1A105K050BC"
			(at 0 0 90)
			(layer "B.Fab")
			(hide yes)
			(effects
				(font
					(size 1.27 1.27)
					(thickness 0.15)
				)
				(justify mirror)
			)
		)
		(property "Description" "SMD Multilayer Ceramic Capacitor, 1 µF, 10 V, 0402 [1005 Metric], ± 10%, X6S, C"
			(at 0 0 90)
			(layer "B.Fab")
			(hide yes)
			(effects
				(font
					(size 1.27 1.27)
					(thickness 0.15)
				)
				(justify mirror)
			)
		)
		(property "MPN" "C1005X6S1A105K050BC"
			(at 0 0 270)
			(unlocked yes)
			(layer "B.Fab")
			(hide yes)
			(effects
				(font
					(size 1 1)
					(thickness 0.15)
				)
				(justify mirror)
			)
		)
		(property "Manufacturer" "TDK"
			(at 0 0 270)
			(unlocked yes)
			(layer "B.Fab")
			(hide yes)
			(effects
				(font
					(size 1 1)
					(thickness 0.15)
				)
				(justify mirror)
			)
		)
		(property "License" "Apache-2.0"
			(at 0 0 270)
			(unlocked yes)
			(layer "B.Fab")
			(hide yes)
			(effects
				(font
					(size 1 1)
					(thickness 0.15)
				)
				(justify mirror)
			)
		)
		(property "Val" "1u"
			(at 0 0 270)
			(unlocked yes)
			(layer "B.Fab")
			(hide yes)
			(effects
				(font
					(size 1 1)
					(thickness 0.15)
				)
				(justify mirror)
			)
		)
		(property "Voltage" ""
			(at 0 0 270)
			(unlocked yes)
			(layer "B.Fab")
			(hide yes)
			(effects
				(font
					(size 1 1)
					(thickness 0.15)
				)
				(justify mirror)
			)
		)
		(property "Dielectric" ""
			(at 0 0 270)
			(unlocked yes)
			(layer "B.Fab")
			(hide yes)
			(effects
				(font
					(size 1 1)
					(thickness 0.15)
				)
				(justify mirror)
			)
		)
		(property "Author" "Antmicro"
			(at 0 0 270)
			(unlocked yes)
			(layer "B.Fab")
			(hide yes)
			(effects
				(font
					(size 1 1)
					(thickness 0.15)
				)
				(justify mirror)
			)
		)
		(sheetname "/TB Controller - Power/")
		(sheetfile "tb-power.kicad_sch")
		(attr smd)
		(fp_rect
			(start -0.925 0.47)
			(end 0.925 -0.47)
			(stroke
				(width 0.05)
				(type default)
			)
			(fill no)
			(layer "B.CrtYd")
		)
		(fp_line
			(start -0.494 0.25)
			(end 0.504 0.25)
			(stroke
				(width 0.15)
				(type solid)
			)
			(layer "B.Fab")
		)
		(fp_line
			(start 0.504 0.25)
			(end 0.504 -0.248)
			(stroke
				(width 0.15)
				(type solid)
			)
			(layer "B.Fab")
		)
		(fp_line
			(start -0.494 -0.248)
			(end -0.494 0.25)
			(stroke
				(width 0.15)
				(type solid)
			)
			(layer "B.Fab")
		)
		(fp_line
			(start 0.504 -0.248)
			(end -0.494 -0.248)
			(stroke
				(width 0.15)
				(type solid)
			)
			(layer "B.Fab")
		)
		(fp_text user "${REFERENCE}"
			(at -0.939 -4.599 90)
			(layer "B.Fab")
			(effects
				(font
					(size 0.7 0.7)
					(thickness 0.15)
				)
				(justify left bottom mirror)
			)
		)
		(fp_text user "License: Apache-2.0"
			(at -0.939 -5.799 90)
			(layer "B.Fab")
			(effects
				(font
					(size 0.7 0.7)
					(thickness 0.15)
				)
				(justify left bottom mirror)
			)
		)
		(fp_text user "Author: Antmicro"
			(at -0.939 -3.399 90)
			(layer "B.Fab")
			(effects
				(font
					(size 0.7 0.7)
					(thickness 0.15)
				)
				(justify left bottom mirror)
			)
		)
		(pad "1" smd roundrect
			(at -0.48 0 270)
			(size 0.59 0.64)
			(layers "B.Cu" "B.Mask" "B.Paste")
			(roundrect_rratio 0.25)
			(net 23 "GND")
			(pintype "passive")
		)
		(pad "2" smd roundrect
			(at 0.48 0 270)
			(size 0.59 0.64)
			(layers "B.Cu" "B.Mask" "B.Paste")
			(roundrect_rratio 0.25)
			(net 403 "Net-(C55-Pad2)")
			(pintype "passive")
		)
	)
	(footprint "antmicro-footprints:SOT-416"
		(layer "B.Cu")
		(at 178.5 73 -90)
		(descr "SOT-416")
		(tags "SOT-416")
		(property "Reference" "Q4"
			(at -0.75 1.3 90)
			(layer "B.SilkS")
			(effects
				(font
					(size 0.7 0.7)
					(thickness 0.15)
				)
				(justify left bottom mirror)
			)
		)
		(property "Value" "DTC014T_SOT-416"
			(at 0 -2 90)
			(layer "B.Fab")
			(effects
				(font
					(size 0.7 0.7)
					(thickness 0.15)
				)
				(justify left bottom mirror)
			)
		)
		(property "Datasheet" "https://www.rohm.com/datasheet?p=DTC014TEB&dist=Mouser&media=referral&source=mouser.com&campaign=Mouser"
			(at 0 0 90)
			(layer "B.Fab")
			(hide yes)
			(effects
				(font
					(size 1.27 1.27)
					(thickness 0.15)
				)
				(justify mirror)
			)
		)
		(property "Description" "Bipolar (BJT) Single Transistor with built-in base resistor, NPN, 50V, 100mA, 150mW, SOT-416FL, Surface Mount"
			(at 0 0 90)
			(layer "B.Fab")
			(hide yes)
			(effects
				(font
					(size 1.27 1.27)
					(thickness 0.15)
				)
				(justify mirror)
			)
		)
		(property "Manufacturer" "ROHM Semiconductor"
			(at 0 0 270)
			(unlocked yes)
			(layer "B.Fab")
			(hide yes)
			(effects
				(font
					(size 1 1)
					(thickness 0.15)
				)
				(justify mirror)
			)
		)
		(property "MPN" "DTC014TEBTL"
			(at 0 0 270)
			(unlocked yes)
			(layer "B.Fab")
			(hide yes)
			(effects
				(font
					(size 1 1)
					(thickness 0.15)
				)
				(justify mirror)
			)
		)
		(property "Author" "Antmicro"
			(at 0 0 270)
			(unlocked yes)
			(layer "B.Fab")
			(hide yes)
			(effects
				(font
					(size 1 1)
					(thickness 0.15)
				)
				(justify mirror)
			)
		)
		(property "License" "Apache-2.0"
			(at 0 0 270)
			(unlocked yes)
			(layer "B.Fab")
			(hide yes)
			(effects
				(font
					(size 1 1)
					(thickness 0.15)
				)
				(justify mirror)
			)
		)
		(sheetname "/X710 DCDC converters/")
		(sheetfile "DCDC_converters_X710.kicad_sch")
		(attr smd)
		(fp_line
			(start 0.508 0.9)
			(end -0.5 0.9)
			(stroke
				(width 0.15)
				(type solid)
			)
			(layer "B.SilkS")
		)
		(fp_line
			(start 0.508 0.9)
			(end 0.508 0.592)
			(stroke
				(width 0.15)
				(type solid)
			)
			(layer "B.SilkS")
		)
		(fp_line
			(start -0.5 0.15)
			(end -0.5 -0.15)
			(stroke
				(width 0.15)
				(type solid)
			)
			(layer "B.SilkS")
		)
		(fp_line
			(start 0.5 -0.9)
			(end 0.5 -0.7)
			(stroke
				(width 0.15)
				(type solid)
			)
			(layer "B.SilkS")
		)
		(fp_line
			(start 0.5 -0.9)
			(end -0.5 -0.9)
			(stroke
				(width 0.15)
				(type solid)
			)
			(layer "B.SilkS")
		)
		(fp_rect
			(start -1 1.05)
			(end 1 -1.05)
			(stroke
				(width 0.05)
				(type solid)
			)
			(fill no)
			(layer "B.CrtYd")
		)
		(fp_line
			(start -0.05 0.9)
			(end -0.45 0.5)
			(stroke
				(width 0.15)
				(type solid)
			)
			(layer "B.Fab")
		)
		(fp_rect
			(start 0.45 -0.9)
			(end -0.45 0.9)
			(stroke
				(width 0.15)
				(type solid)
			)
			(fill no)
			(layer "B.Fab")
		)
		(fp_text user "Author: Antmicro"
			(at -1 -4.602 90)
			(layer "B.Fab")
			(effects
				(font
					(size 0.7 0.7)
					(thickness 0.15)
				)
				(justify left bottom mirror)
			)
		)
		(fp_text user "License: Apache-2.0"
			(at -1 -5.802 90)
			(layer "B.Fab")
			(effects
				(font
					(size 0.7 0.7)
					(thickness 0.15)
				)
				(justify left bottom mirror)
			)
		)
		(fp_text user "${REFERENCE}"
			(at -1 -3.4 90)
			(layer "B.Fab")
			(effects
				(font
					(size 0.7 0.7)
					(thickness 0.15)
				)
				(justify left bottom mirror)
			)
		)
		(pad "1" smd rect
			(at -0.652 0.5 270)
			(size 0.6 0.5)
			(layers "B.Cu" "B.Mask" "B.Paste")
			(net 339 "/X710 DCDC converters/+1V0_OUT")
			(pinfunction "B")
			(pintype "input")
		)
		(pad "2" smd rect
			(at -0.652 -0.498 270)
			(size 0.6 0.5)
			(layers "B.Cu" "B.Mask" "B.Paste")
			(net 23 "GND")
			(pinfunction "E")
			(pintype "passive")
		)
		(pad "3" smd rect
			(at 0.65 0 270)
			(size 0.6 0.5)
			(layers "B.Cu" "B.Mask" "B.Paste")
			(net 430 "Net-(Q4-C)")
			(pinfunction "C")
			(pintype "passive")
		)
	)
	(footprint "antmicro-footprints:TP_SMD_0.75mm"
		(layer "B.Cu")
		(at 153.7 62.935117 -90)
		(property "Reference" "TP23"
			(at -3.135117 -0.3 90)
			(layer "B.SilkS")
			(effects
				(font
					(size 0.7 0.7)
					(thickness 0.15)
				)
				(justify left bottom mirror)
			)
		)
		(property "Value" "TP_0.75mm_SMD"
			(at 0 -1.2 90)
			(layer "B.Fab")
			(effects
				(font
					(size 0.7 0.7)
					(thickness 0.15)
				)
				(justify left bottom mirror)
			)
		)
		(property "Description" "SMT test point"
			(at 0 0 90)
			(layer "B.Fab")
			(hide yes)
			(effects
				(font
					(size 1.27 1.27)
					(thickness 0.15)
				)
				(justify mirror)
			)
		)
		(property "MPN" ""
			(at 0 0 270)
			(unlocked yes)
			(layer "B.Fab")
			(hide yes)
			(effects
				(font
					(size 1 1)
					(thickness 0.15)
				)
				(justify mirror)
			)
		)
		(property "Manufacturer" ""
			(at 0 0 270)
			(unlocked yes)
			(layer "B.Fab")
			(hide yes)
			(effects
				(font
					(size 1 1)
					(thickness 0.15)
				)
				(justify mirror)
			)
		)
		(property "Author" "Antmicro"
			(at 0 0 270)
			(unlocked yes)
			(layer "B.Fab")
			(hide yes)
			(effects
				(font
					(size 1 1)
					(thickness 0.15)
				)
				(justify mirror)
			)
		)
		(property "License" "Apache-2.0"
			(at 0 0 270)
			(unlocked yes)
			(layer "B.Fab")
			(hide yes)
			(effects
				(font
					(size 1 1)
					(thickness 0.15)
				)
				(justify mirror)
			)
		)
		(sheetname "/X710-AT2 Misc/")
		(sheetfile "x710-at2-mics.kicad_sch")
		(attr exclude_from_pos_files exclude_from_bom)
		(fp_circle
			(center 0 0)
			(end 0.475 0)
			(stroke
				(width 0.05)
				(type default)
			)
			(fill no)
			(layer "B.CrtYd")
		)
		(fp_text user "${REFERENCE}"
			(at -0.4 -2.7 90)
			(layer "B.Fab")
			(effects
				(font
					(size 0.7 0.7)
					(thickness 0.15)
				)
				(justify left bottom mirror)
			)
		)
		(fp_text user "Author: Antmicro"
			(at -0.4 -3.901 90)
			(layer "B.Fab")
			(effects
				(font
					(size 0.7 0.7)
					(thickness 0.15)
				)
				(justify left bottom mirror)
			)
		)
		(fp_text user "License: Apache-2.0"
			(at -0.4 -5.101 90)
			(layer "B.Fab")
			(effects
				(font
					(size 0.7 0.7)
					(thickness 0.15)
				)
				(justify left bottom mirror)
			)
		)
		(pad "1" smd circle
			(at 0 0 270)
			(size 0.75 0.75)
			(layers "B.Cu" "B.Mask")
			(net 144 "/X710-AT2 Misc/NCSI.REF_CLK")
			(pinfunction "1")
			(pintype "passive")
		)
	)
	(footprint "antmicro-footprints:R_0402_1005Metric"
		(layer "B.Cu")
		(at 138.450001 115.100002)
		(descr "Resistor SMD 0402")
		(tags "resistor SMD 0402")
		(property "Reference" "R48"
			(at 19.525001 -7.450001 180)
			(layer "B.SilkS")
			(effects
				(font
					(size 0.7 0.7)
					(thickness 0.15)
				)
				(justify mirror)
			)
		)
		(property "Value" "R_1M_0402"
			(at -1.011843 -1.772047 180)
			(layer "B.Fab")
			(effects
				(font
					(size 0.7 0.7)
					(thickness 0.15)
				)
				(justify left bottom mirror)
			)
		)
		(property "Datasheet" "https://www.bourns.com/docs/product-datasheets/cr.pdf"
			(at 0 0 180)
			(layer "B.Fab")
			(hide yes)
			(effects
				(font
					(size 1.27 1.27)
					(thickness 0.15)
				)
				(justify mirror)
			)
		)
		(property "Description" "SMD Chip Resistor, 1 Mohm, ± 1%, 62.5 mW, 0402 [1005 Metric], Thick Film, General Purpose"
			(at 0 0 180)
			(layer "B.Fab")
			(hide yes)
			(effects
				(font
					(size 1.27 1.27)
					(thickness 0.15)
				)
				(justify mirror)
			)
		)
		(property "MPN" "CR0402-FX-1004GLF"
			(at 0 0 0)
			(unlocked yes)
			(layer "B.Fab")
			(hide yes)
			(effects
				(font
					(size 1 1)
					(thickness 0.15)
				)
				(justify mirror)
			)
		)
		(property "Manufacturer" "Bourns"
			(at 0 0 0)
			(unlocked yes)
			(layer "B.Fab")
			(hide yes)
			(effects
				(font
					(size 1 1)
					(thickness 0.15)
				)
				(justify mirror)
			)
		)
		(property "License" "Apache-2.0"
			(at 0 0 0)
			(unlocked yes)
			(layer "B.Fab")
			(hide yes)
			(effects
				(font
					(size 1 1)
					(thickness 0.15)
				)
				(justify mirror)
			)
		)
		(property "Val" "1M"
			(at 0 0 0)
			(unlocked yes)
			(layer "B.Fab")
			(hide yes)
			(effects
				(font
					(size 1 1)
					(thickness 0.15)
				)
				(justify mirror)
			)
		)
		(property "Tolerance" "1%"
			(at 0 0 0)
			(unlocked yes)
			(layer "B.Fab")
			(hide yes)
			(effects
				(font
					(size 1 1)
					(thickness 0.15)
				)
				(justify mirror)
			)
		)
		(property "Author" "Antmicro"
			(at 0 0 0)
			(unlocked yes)
			(layer "B.Fab")
			(hide yes)
			(effects
				(font
					(size 1 1)
					(thickness 0.15)
				)
				(justify mirror)
			)
		)
		(sheetname "/TB Controller/")
		(sheetfile "tb.kicad_sch")
		(attr smd)
		(fp_rect
			(start -0.925 0.47)
			(end 0.925 -0.47)
			(stroke
				(width 0.05)
				(type default)
			)
			(fill no)
			(layer "B.CrtYd")
		)
		(fp_rect
			(start -0.5 0.25)
			(end 0.5 -0.25)
			(stroke
				(width 0.15)
				(type solid)
			)
			(fill no)
			(layer "B.Fab")
		)
		(fp_text user "${REFERENCE}"
			(at -0.95 -3.168 180)
			(layer "B.Fab")
			(effects
				(font
					(size 0.7 0.7)
					(thickness 0.15)
				)
				(justify left bottom mirror)
			)
		)
		(fp_text user "Author: Antmicro"
			(at -0.95 -4.169 180)
			(layer "B.Fab")
			(effects
				(font
					(size 0.7 0.7)
					(thickness 0.15)
				)
				(justify left bottom mirror)
			)
		)
		(fp_text user "License: Apache-2.0"
			(at -0.95 -5.169 180)
			(layer "B.Fab")
			(effects
				(font
					(size 0.7 0.7)
					(thickness 0.15)
				)
				(justify left bottom mirror)
			)
		)
		(pad "1" smd roundrect
			(at -0.48 0)
			(size 0.59 0.64)
			(layers "B.Cu" "B.Mask" "B.Paste")
			(roundrect_rratio 0.25)
			(net 191 "Net-(U4C-GPIO_8)")
			(pintype "passive")
		)
		(pad "2" smd roundrect
			(at 0.48 0)
			(size 0.59 0.64)
			(layers "B.Cu" "B.Mask" "B.Paste")
			(roundrect_rratio 0.25)
			(net 23 "GND")
			(pintype "passive")
		)
	)
	(footprint "antmicro-footprints:C_0402_1005Metric"
		(layer "B.Cu")
		(at 147.481865 81.260116 180)
		(descr "Capacitor SMD 0402")
		(tags "capacitor SMD 0402")
		(property "Reference" "C238"
			(at -18.618135 -9.464883 0)
			(layer "B.SilkS")
			(effects
				(font
					(size 0.7 0.7)
					(thickness 0.15)
				)
				(justify mirror)
			)
		)
		(property "Value" "C_1u_25V_0402"
			(at -1.022927 -2.155213 0)
			(layer "B.Fab")
			(effects
				(font
					(size 0.7 0.7)
					(thickness 0.15)
				)
				(justify left bottom mirror)
			)
		)
		(property "Datasheet" "https://www.murata.com/products/productdetail?partno=GRM155R61E105KE11%23"
			(at 0 0 0)
			(layer "B.Fab")
			(hide yes)
			(effects
				(font
					(size 1.27 1.27)
					(thickness 0.15)
				)
				(justify mirror)
			)
		)
		(property "Description" "SMD Multilayer Ceramic Capacitor, 1 µF, 25 V, 0402 [1005 Metric], ± 10%, X5R, GRM Series"
			(at 0 0 0)
			(layer "B.Fab")
			(hide yes)
			(effects
				(font
					(size 1.27 1.27)
					(thickness 0.15)
				)
				(justify mirror)
			)
		)
		(property "MPN" "GRM155R61E105KE11J"
			(at 0 0 180)
			(unlocked yes)
			(layer "B.Fab")
			(hide yes)
			(effects
				(font
					(size 1 1)
					(thickness 0.15)
				)
				(justify mirror)
			)
		)
		(property "Manufacturer" "Murata"
			(at 0 0 180)
			(unlocked yes)
			(layer "B.Fab")
			(hide yes)
			(effects
				(font
					(size 1 1)
					(thickness 0.15)
				)
				(justify mirror)
			)
		)
		(property "License" "Apache-2.0"
			(at 0 0 180)
			(unlocked yes)
			(layer "B.Fab")
			(hide yes)
			(effects
				(font
					(size 1 1)
					(thickness 0.15)
				)
				(justify mirror)
			)
		)
		(property "Author" "Antmicro"
			(at 0 0 180)
			(unlocked yes)
			(layer "B.Fab")
			(hide yes)
			(effects
				(font
					(size 1 1)
					(thickness 0.15)
				)
				(justify mirror)
			)
		)
		(property "Val" "1u"
			(at 0 0 180)
			(unlocked yes)
			(layer "B.Fab")
			(hide yes)
			(effects
				(font
					(size 1 1)
					(thickness 0.15)
				)
				(justify mirror)
			)
		)
		(property "Voltage" "25V"
			(at 0 0 180)
			(unlocked yes)
			(layer "B.Fab")
			(hide yes)
			(effects
				(font
					(size 1 1)
					(thickness 0.15)
				)
				(justify mirror)
			)
		)
		(property "Dielectric" "X5R"
			(at 0 0 180)
			(unlocked yes)
			(layer "B.Fab")
			(hide yes)
			(effects
				(font
					(size 1 1)
					(thickness 0.15)
				)
				(justify mirror)
			)
		)
		(sheetname "/X710-AT2 power/")
		(sheetfile "x710-at2-power.kicad_sch")
		(attr smd)
		(fp_rect
			(start -0.925 0.47)
			(end 0.925 -0.47)
			(stroke
				(width 0.05)
				(type default)
			)
			(fill no)
			(layer "B.CrtYd")
		)
		(fp_line
			(start 0.504 0.25)
			(end 0.504 -0.248)
			(stroke
				(width 0.15)
				(type solid)
			)
			(layer "B.Fab")
		)
		(fp_line
			(start 0.504 -0.248)
			(end -0.494 -0.248)
			(stroke
				(width 0.15)
				(type solid)
			)
			(layer "B.Fab")
		)
		(fp_line
			(start -0.494 0.25)
			(end 0.504 0.25)
			(stroke
				(width 0.15)
				(type solid)
			)
			(layer "B.Fab")
		)
		(fp_line
			(start -0.494 -0.248)
			(end -0.494 0.25)
			(stroke
				(width 0.15)
				(type solid)
			)
			(layer "B.Fab")
		)
		(fp_text user "${REFERENCE}"
			(at -0.939 -4.599 0)
			(layer "B.Fab")
			(effects
				(font
					(size 0.7 0.7)
					(thickness 0.15)
				)
				(justify left bottom mirror)
			)
		)
		(fp_text user "License: Apache-2.0"
			(at -0.939 -5.799 0)
			(layer "B.Fab")
			(effects
				(font
					(size 0.7 0.7)
					(thickness 0.15)
				)
				(justify left bottom mirror)
			)
		)
		(fp_text user "Author: Antmicro"
			(at -0.939 -3.399 0)
			(layer "B.Fab")
			(effects
				(font
					(size 0.7 0.7)
					(thickness 0.15)
				)
				(justify left bottom mirror)
			)
		)
		(pad "1" smd roundrect
			(at -0.48 0 180)
			(size 0.59 0.64)
			(layers "B.Cu" "B.Mask" "B.Paste")
			(roundrect_rratio 0.25)
			(net 23 "GND")
			(pintype "passive")
		)
		(pad "2" smd roundrect
			(at 0.48 0 180)
			(size 0.59 0.64)
			(layers "B.Cu" "B.Mask" "B.Paste")
			(roundrect_rratio 0.25)
			(net 7 "+3V3")
			(pintype "passive")
		)
	)
	(footprint "antmicro-footprints:C_0402_1005Metric"
		(layer "B.Cu")
		(at 125.074998 125.425001)
		(descr "Capacitor SMD 0402")
		(tags "capacitor SMD 0402")
		(property "Reference" "C68"
			(at 21.900002 -7.700002 180)
			(layer "B.SilkS")
			(effects
				(font
					(size 0.7 0.7)
					(thickness 0.15)
				)
				(justify mirror)
			)
		)
		(property "Value" "C_1u_0402"
			(at -1.022927 -2.155213 180)
			(layer "B.Fab")
			(effects
				(font
					(size 0.7 0.7)
					(thickness 0.15)
				)
				(justify left bottom mirror)
			)
		)
		(property "Datasheet" "https://product.tdk.com/en/search/capacitor/ceramic/mlcc/info?part_no=C1005X6S1A105K050BC"
			(at 0 0 180)
			(layer "B.Fab")
			(hide yes)
			(effects
				(font
					(size 1.27 1.27)
					(thickness 0.15)
				)
				(justify mirror)
			)
		)
		(property "Description" "SMD Multilayer Ceramic Capacitor, 1 µF, 10 V, 0402 [1005 Metric], ± 10%, X6S, C"
			(at 0 0 180)
			(layer "B.Fab")
			(hide yes)
			(effects
				(font
					(size 1.27 1.27)
					(thickness 0.15)
				)
				(justify mirror)
			)
		)
		(property "MPN" "C1005X6S1A105K050BC"
			(at 0 0 0)
			(unlocked yes)
			(layer "B.Fab")
			(hide yes)
			(effects
				(font
					(size 1 1)
					(thickness 0.15)
				)
				(justify mirror)
			)
		)
		(property "Manufacturer" "TDK"
			(at 0 0 0)
			(unlocked yes)
			(layer "B.Fab")
			(hide yes)
			(effects
				(font
					(size 1 1)
					(thickness 0.15)
				)
				(justify mirror)
			)
		)
		(property "License" "Apache-2.0"
			(at 0 0 0)
			(unlocked yes)
			(layer "B.Fab")
			(hide yes)
			(effects
				(font
					(size 1 1)
					(thickness 0.15)
				)
				(justify mirror)
			)
		)
		(property "Val" "1u"
			(at 0 0 0)
			(unlocked yes)
			(layer "B.Fab")
			(hide yes)
			(effects
				(font
					(size 1 1)
					(thickness 0.15)
				)
				(justify mirror)
			)
		)
		(property "Voltage" ""
			(at 0 0 0)
			(unlocked yes)
			(layer "B.Fab")
			(hide yes)
			(effects
				(font
					(size 1 1)
					(thickness 0.15)
				)
				(justify mirror)
			)
		)
		(property "Dielectric" ""
			(at 0 0 0)
			(unlocked yes)
			(layer "B.Fab")
			(hide yes)
			(effects
				(font
					(size 1 1)
					(thickness 0.15)
				)
				(justify mirror)
			)
		)
		(property "Author" "Antmicro"
			(at 0 0 0)
			(unlocked yes)
			(layer "B.Fab")
			(hide yes)
			(effects
				(font
					(size 1 1)
					(thickness 0.15)
				)
				(justify mirror)
			)
		)
		(sheetname "/TB Controller - Power/")
		(sheetfile "tb-power.kicad_sch")
		(attr smd)
		(fp_rect
			(start -0.925 0.47)
			(end 0.925 -0.47)
			(stroke
				(width 0.05)
				(type default)
			)
			(fill no)
			(layer "B.CrtYd")
		)
		(fp_line
			(start -0.494 -0.248)
			(end -0.494 0.25)
			(stroke
				(width 0.15)
				(type solid)
			)
			(layer "B.Fab")
		)
		(fp_line
			(start -0.494 0.25)
			(end 0.504 0.25)
			(stroke
				(width 0.15)
				(type solid)
			)
			(layer "B.Fab")
		)
		(fp_line
			(start 0.504 -0.248)
			(end -0.494 -0.248)
			(stroke
				(width 0.15)
				(type solid)
			)
			(layer "B.Fab")
		)
		(fp_line
			(start 0.504 0.25)
			(end 0.504 -0.248)
			(stroke
				(width 0.15)
				(type solid)
			)
			(layer "B.Fab")
		)
		(fp_text user "${REFERENCE}"
			(at -0.939 -4.599 180)
			(layer "B.Fab")
			(effects
				(font
					(size 0.7 0.7)
					(thickness 0.15)
				)
				(justify left bottom mirror)
			)
		)
		(fp_text user "Author: Antmicro"
			(at -0.939 -3.399 180)
			(layer "B.Fab")
			(effects
				(font
					(size 0.7 0.7)
					(thickness 0.15)
				)
				(justify left bottom mirror)
			)
		)
		(fp_text user "License: Apache-2.0"
			(at -0.939 -5.799 180)
			(layer "B.Fab")
			(effects
				(font
					(size 0.7 0.7)
					(thickness 0.15)
				)
				(justify left bottom mirror)
			)
		)
		(pad "1" smd roundrect
			(at -0.48 0)
			(size 0.59 0.64)
			(layers "B.Cu" "B.Mask" "B.Paste")
			(roundrect_rratio 0.25)
			(net 23 "GND")
			(pintype "passive")
		)
		(pad "2" smd roundrect
			(at 0.48 0)
			(size 0.59 0.64)
			(layers "B.Cu" "B.Mask" "B.Paste")
			(roundrect_rratio 0.25)
			(net 178 "Net-(U4A-VCC3P3_ANA_USB2)")
			(pintype "passive")
		)
	)
	(footprint "antmicro-footprints:C_Pol_EIA-A"
		(layer "B.Cu")
		(at 146.7 102.7)
		(property "Reference" "C329"
			(at 2.2 -0.4 0)
			(layer "B.SilkS")
			(effects
				(font
					(size 0.7 0.7)
					(thickness 0.15)
				)
				(justify right top mirror)
			)
		)
		(property "Value" "C_Pol_100u_6V_KEMET-T490-A"
			(at 0 -2 0)
			(layer "B.Fab")
			(effects
				(font
					(size 0.7 0.7)
					(thickness 0.15)
				)
				(justify right top mirror)
			)
		)
		(property "Datasheet" "https://www.kemet.com/en/us/capacitors/product/T490A107M006ATE800.html"
			(at 0 0 0)
			(layer "B.Fab")
			(hide yes)
			(effects
				(font
					(size 1.27 1.27)
					(thickness 0.15)
				)
				(justify mirror)
			)
		)
		(property "Description" "Surface Mount Tantalum Capacitor,  Solid SMD 6V 100uF 1206 20% ESR=800mOhms"
			(at 0 0 0)
			(layer "B.Fab")
			(hide yes)
			(effects
				(font
					(size 1.27 1.27)
					(thickness 0.15)
				)
				(justify mirror)
			)
		)
		(property "Val" "100u"
			(at 0 0 0)
			(unlocked yes)
			(layer "B.Fab")
			(hide yes)
			(effects
				(font
					(size 1 1)
					(thickness 0.15)
				)
				(justify mirror)
			)
		)
		(property "MPN" "T490A107M006ATE800"
			(at 0 0 0)
			(unlocked yes)
			(layer "B.Fab")
			(hide yes)
			(effects
				(font
					(size 1 1)
					(thickness 0.15)
				)
				(justify mirror)
			)
		)
		(property "Manufacturer" "KEMET"
			(at 0 0 0)
			(unlocked yes)
			(layer "B.Fab")
			(hide yes)
			(effects
				(font
					(size 1 1)
					(thickness 0.15)
				)
				(justify mirror)
			)
		)
		(property "License" "Apache-2.0"
			(at 0 0 0)
			(unlocked yes)
			(layer "B.Fab")
			(hide yes)
			(effects
				(font
					(size 1 1)
					(thickness 0.15)
				)
				(justify mirror)
			)
		)
		(property "Author" "Antmicro"
			(at 0 0 0)
			(unlocked yes)
			(layer "B.Fab")
			(hide yes)
			(effects
				(font
					(size 1 1)
					(thickness 0.15)
				)
				(justify mirror)
			)
		)
		(property "Voltage" "6V"
			(at 0 0 0)
			(unlocked yes)
			(layer "B.Fab")
			(hide yes)
			(effects
				(font
					(size 1 1)
					(thickness 0.15)
				)
				(justify mirror)
			)
		)
		(property "Dielectric" "template_dielectric"
			(at 0 0 0)
			(unlocked yes)
			(layer "B.Fab")
			(hide yes)
			(effects
				(font
					(size 1 1)
					(thickness 0.15)
				)
				(justify mirror)
			)
		)
		(sheetname "/X710-AT2 power/")
		(sheetfile "x710-at2-power.kicad_sch")
		(attr smd)
		(fp_line
			(start -2.1 1.1)
			(end -1.8 1.1)
			(stroke
				(width 0.12)
				(type solid)
			)
			(layer "B.SilkS")
		)
		(fp_line
			(start -1.95 1.25)
			(end -1.95 0.95)
			(stroke
				(width 0.12)
				(type solid)
			)
			(layer "B.SilkS")
		)
		(fp_line
			(start -1.5 -0.75)
			(end -1.5 -0.85)
			(stroke
				(width 0.12)
				(type solid)
			)
			(layer "B.SilkS")
		)
		(fp_line
			(start -1.5 0.75)
			(end -1.5 0.85)
			(stroke
				(width 0.12)
				(type solid)
			)
			(layer "B.SilkS")
		)
		(fp_line
			(start -1.5 0.85)
			(end 1.5 0.85)
			(stroke
				(width 0.12)
				(type solid)
			)
			(layer "B.SilkS")
		)
		(fp_line
			(start 1.5 -0.85)
			(end -1.5 -0.85)
			(stroke
				(width 0.12)
				(type solid)
			)
			(layer "B.SilkS")
		)
		(fp_line
			(start 1.5 -0.75)
			(end 1.5 -0.85)
			(stroke
				(width 0.12)
				(type solid)
			)
			(layer "B.SilkS")
		)
		(fp_line
			(start 1.5 0.75)
			(end 1.5 0.85)
			(stroke
				(width 0.12)
				(type solid)
			)
			(layer "B.SilkS")
		)
		(fp_line
			(start -2.05 0.85)
			(end -2.05 -0.85)
			(stroke
				(width 0.05)
				(type solid)
			)
			(layer "B.CrtYd")
		)
		(fp_line
			(start -1.7 -1.05)
			(end -1.7 -0.85)
			(stroke
				(width 0.05)
				(type solid)
			)
			(layer "B.CrtYd")
		)
		(fp_line
			(start -1.7 -0.85)
			(end -2.05 -0.85)
			(stroke
				(width 0.05)
				(type solid)
			)
			(layer "B.CrtYd")
		)
		(fp_line
			(start -1.7 0.85)
			(end -2.05 0.85)
			(stroke
				(width 0.05)
				(type solid)
			)
			(layer "B.CrtYd")
		)
		(fp_line
			(start -1.7 0.85)
			(end -1.7 1.05)
			(stroke
				(width 0.05)
				(type solid)
			)
			(layer "B.CrtYd")
		)
		(fp_line
			(start 1.7 -1.05)
			(end -1.7 -1.05)
			(stroke
				(width 0.05)
				(type solid)
			)
			(layer "B.CrtYd")
		)
		(fp_line
			(start 1.7 -1.05)
			(end 1.7 -0.85)
			(stroke
				(width 0.05)
				(type solid)
			)
			(layer "B.CrtYd")
		)
		(fp_line
			(start 1.7 0.85)
			(end 1.7 1.05)
			(stroke
				(width 0.05)
				(type solid)
			)
			(layer "B.CrtYd")
		)
		(fp_line
			(start 1.7 1.05)
			(end -1.7 1.05)
			(stroke
				(width 0.05)
				(type solid)
			)
			(layer "B.CrtYd")
		)
		(fp_line
			(start 2.05 -0.85)
			(end 1.7 -0.85)
			(stroke
				(width 0.05)
				(type solid)
			)
			(layer "B.CrtYd")
		)
		(fp_line
			(start 2.05 0.85)
			(end 1.7 0.85)
			(stroke
				(width 0.05)
				(type solid)
			)
			(layer "B.CrtYd")
		)
		(fp_line
			(start 2.05 0.85)
			(end 2.05 -0.85)
			(stroke
				(width 0.05)
				(type solid)
			)
			(layer "B.CrtYd")
		)
		(fp_rect
			(start -1.601 0.802)
			(end 1.6 -0.8)
			(stroke
				(width 0.1)
				(type solid)
			)
			(fill no)
			(layer "B.Fab")
		)
		(fp_text user "Author: Antmicro"
			(at -2.1 -6.198 0)
			(layer "B.Fab")
			(effects
				(font
					(size 0.7 0.7)
					(thickness 0.15)
				)
				(justify right top mirror)
			)
		)
		(fp_text user "${REFERENCE}"
			(at -2.1 -4.198 0)
			(layer "B.Fab")
			(effects
				(font
					(size 0.7 0.7)
					(thickness 0.15)
				)
				(justify right top mirror)
			)
		)
		(fp_text user "License: Apache-2.0"
			(at -2.1 -5.198 0)
			(layer "B.Fab")
			(effects
				(font
					(size 0.7 0.7)
					(thickness 0.15)
				)
				(justify right top mirror)
			)
		)
		(pad "1" smd roundrect
			(at -1.2 0)
			(size 1.2 1.2)
			(layers "B.Cu" "B.Mask" "B.Paste")
			(roundrect_rratio 0.1)
			(net 6 "DVDD")
			(pintype "passive")
		)
		(pad "2" smd roundrect
			(at 1.2 0)
			(size 1.2 1.2)
			(layers "B.Cu" "B.Mask" "B.Paste")
			(roundrect_rratio 0.1)
			(net 23 "GND")
			(pintype "passive")
		)
	)
	(footprint "antmicro-footprints:C_0402_1005Metric"
		(layer "B.Cu")
		(at 158.931867 90.695117)
		(descr "Capacitor SMD 0402")
		(tags "capacitor SMD 0402")
		(property "Reference" "C199"
			(at 20.068133 10.984883 180)
			(layer "B.SilkS")
			(effects
				(font
					(size 0.7 0.7)
					(thickness 0.15)
				)
				(justify mirror)
			)
		)
		(property "Value" "C_1u_25V_0402"
			(at -1.022927 -2.155213 180)
			(layer "B.Fab")
			(effects
				(font
					(size 0.7 0.7)
					(thickness 0.15)
				)
				(justify left bottom mirror)
			)
		)
		(property "Datasheet" "https://www.murata.com/products/productdetail?partno=GRM155R61E105KE11%23"
			(at 0 0 180)
			(layer "B.Fab")
			(hide yes)
			(effects
				(font
					(size 1.27 1.27)
					(thickness 0.15)
				)
				(justify mirror)
			)
		)
		(property "Description" "SMD Multilayer Ceramic Capacitor, 1 µF, 25 V, 0402 [1005 Metric], ± 10%, X5R, GRM Series"
			(at 0 0 180)
			(layer "B.Fab")
			(hide yes)
			(effects
				(font
					(size 1.27 1.27)
					(thickness 0.15)
				)
				(justify mirror)
			)
		)
		(property "MPN" "GRM155R61E105KE11J"
			(at 0 0 0)
			(unlocked yes)
			(layer "B.Fab")
			(hide yes)
			(effects
				(font
					(size 1 1)
					(thickness 0.15)
				)
				(justify mirror)
			)
		)
		(property "Manufacturer" "Murata"
			(at 0 0 0)
			(unlocked yes)
			(layer "B.Fab")
			(hide yes)
			(effects
				(font
					(size 1 1)
					(thickness 0.15)
				)
				(justify mirror)
			)
		)
		(property "License" "Apache-2.0"
			(at 0 0 0)
			(unlocked yes)
			(layer "B.Fab")
			(hide yes)
			(effects
				(font
					(size 1 1)
					(thickness 0.15)
				)
				(justify mirror)
			)
		)
		(property "Author" "Antmicro"
			(at 0 0 0)
			(unlocked yes)
			(layer "B.Fab")
			(hide yes)
			(effects
				(font
					(size 1 1)
					(thickness 0.15)
				)
				(justify mirror)
			)
		)
		(property "Val" "1u"
			(at 0 0 0)
			(unlocked yes)
			(layer "B.Fab")
			(hide yes)
			(effects
				(font
					(size 1 1)
					(thickness 0.15)
				)
				(justify mirror)
			)
		)
		(property "Voltage" "25V"
			(at 0 0 0)
			(unlocked yes)
			(layer "B.Fab")
			(hide yes)
			(effects
				(font
					(size 1 1)
					(thickness 0.15)
				)
				(justify mirror)
			)
		)
		(property "Dielectric" "X5R"
			(at 0 0 0)
			(unlocked yes)
			(layer "B.Fab")
			(hide yes)
			(effects
				(font
					(size 1 1)
					(thickness 0.15)
				)
				(justify mirror)
			)
		)
		(sheetname "/X710-AT2 power/")
		(sheetfile "x710-at2-power.kicad_sch")
		(attr smd)
		(fp_rect
			(start -0.925 0.47)
			(end 0.925 -0.47)
			(stroke
				(width 0.05)
				(type default)
			)
			(fill no)
			(layer "B.CrtYd")
		)
		(fp_line
			(start -0.494 -0.248)
			(end -0.494 0.25)
			(stroke
				(width 0.15)
				(type solid)
			)
			(layer "B.Fab")
		)
		(fp_line
			(start -0.494 0.25)
			(end 0.504 0.25)
			(stroke
				(width 0.15)
				(type solid)
			)
			(layer "B.Fab")
		)
		(fp_line
			(start 0.504 -0.248)
			(end -0.494 -0.248)
			(stroke
				(width 0.15)
				(type solid)
			)
			(layer "B.Fab")
		)
		(fp_line
			(start 0.504 0.25)
			(end 0.504 -0.248)
			(stroke
				(width 0.15)
				(type solid)
			)
			(layer "B.Fab")
		)
		(fp_text user "License: Apache-2.0"
			(at -0.939 -5.799 180)
			(layer "B.Fab")
			(effects
				(font
					(size 0.7 0.7)
					(thickness 0.15)
				)
				(justify left bottom mirror)
			)
		)
		(fp_text user "${REFERENCE}"
			(at -0.939 -4.599 180)
			(layer "B.Fab")
			(effects
				(font
					(size 0.7 0.7)
					(thickness 0.15)
				)
				(justify left bottom mirror)
			)
		)
		(fp_text user "Author: Antmicro"
			(at -0.939 -3.399 180)
			(layer "B.Fab")
			(effects
				(font
					(size 0.7 0.7)
					(thickness 0.15)
				)
				(justify left bottom mirror)
			)
		)
		(pad "1" smd roundrect
			(at -0.48 0)
			(size 0.59 0.64)
			(layers "B.Cu" "B.Mask" "B.Paste")
			(roundrect_rratio 0.25)
			(net 23 "GND")
			(pintype "passive")
		)
		(pad "2" smd roundrect
			(at 0.48 0)
			(size 0.59 0.64)
			(layers "B.Cu" "B.Mask" "B.Paste")
			(roundrect_rratio 0.25)
			(net 5 "P0_AVDDL")
			(pintype "passive")
		)
	)
	(footprint "antmicro-footprints:C_0402_1005Metric"
		(layer "B.Cu")
		(at 153.579998 146.66 -90)
		(descr "Capacitor SMD 0402")
		(tags "capacitor SMD 0402")
		(property "Reference" "C302"
			(at 1.09 -0.42 90)
			(layer "B.SilkS")
			(effects
				(font
					(size 0.7 0.7)
					(thickness 0.15)
				)
				(justify left bottom mirror)
			)
		)
		(property "Value" "C_470p_0402"
			(at -1.022927 -2.155213 90)
			(layer "B.Fab")
			(effects
				(font
					(size 0.7 0.7)
					(thickness 0.15)
				)
				(justify left bottom mirror)
			)
		)
		(property "Datasheet" "https://www.passivecomponent.com/wp-content/uploads/datasheet/WTC_MLCC_General_Purpose.pdf"
			(at 0 0 90)
			(layer "B.Fab")
			(hide yes)
			(effects
				(font
					(size 1.27 1.27)
					(thickness 0.15)
				)
				(justify mirror)
			)
		)
		(property "Description" "SMD Multilayer Ceramic Capacitor, General Purpose, 470 pF, 25 V, 0402 [1005 Metric], ± 10%, X7R"
			(at 0 0 90)
			(layer "B.Fab")
			(hide yes)
			(effects
				(font
					(size 1.27 1.27)
					(thickness 0.15)
				)
				(justify mirror)
			)
		)
		(property "MPN" "0402B471K250CT"
			(at 0 0 270)
			(unlocked yes)
			(layer "B.Fab")
			(hide yes)
			(effects
				(font
					(size 1 1)
					(thickness 0.15)
				)
				(justify mirror)
			)
		)
		(property "Manufacturer" "Walsin"
			(at 0 0 270)
			(unlocked yes)
			(layer "B.Fab")
			(hide yes)
			(effects
				(font
					(size 1 1)
					(thickness 0.15)
				)
				(justify mirror)
			)
		)
		(property "License" "Apache-2.0"
			(at 0 0 270)
			(unlocked yes)
			(layer "B.Fab")
			(hide yes)
			(effects
				(font
					(size 1 1)
					(thickness 0.15)
				)
				(justify mirror)
			)
		)
		(property "Author" "Antmicro"
			(at 0 0 270)
			(unlocked yes)
			(layer "B.Fab")
			(hide yes)
			(effects
				(font
					(size 1 1)
					(thickness 0.15)
				)
				(justify mirror)
			)
		)
		(property "Val" "470p"
			(at 0 0 270)
			(unlocked yes)
			(layer "B.Fab")
			(hide yes)
			(effects
				(font
					(size 1 1)
					(thickness 0.15)
				)
				(justify mirror)
			)
		)
		(property "Voltage" "25V"
			(at 0 0 270)
			(unlocked yes)
			(layer "B.Fab")
			(hide yes)
			(effects
				(font
					(size 1 1)
					(thickness 0.15)
				)
				(justify mirror)
			)
		)
		(property "Dielectric" "X7R"
			(at 0 0 270)
			(unlocked yes)
			(layer "B.Fab")
			(hide yes)
			(effects
				(font
					(size 1 1)
					(thickness 0.15)
				)
				(justify mirror)
			)
		)
		(sheetname "/2xRJ45/")
		(sheetfile "2xrj45.kicad_sch")
		(attr smd)
		(fp_rect
			(start -0.925 0.47)
			(end 0.925 -0.47)
			(stroke
				(width 0.05)
				(type default)
			)
			(fill no)
			(layer "B.CrtYd")
		)
		(fp_line
			(start -0.494 0.25)
			(end 0.504 0.25)
			(stroke
				(width 0.15)
				(type solid)
			)
			(layer "B.Fab")
		)
		(fp_line
			(start 0.504 0.25)
			(end 0.504 -0.248)
			(stroke
				(width 0.15)
				(type solid)
			)
			(layer "B.Fab")
		)
		(fp_line
			(start -0.494 -0.248)
			(end -0.494 0.25)
			(stroke
				(width 0.15)
				(type solid)
			)
			(layer "B.Fab")
		)
		(fp_line
			(start 0.504 -0.248)
			(end -0.494 -0.248)
			(stroke
				(width 0.15)
				(type solid)
			)
			(layer "B.Fab")
		)
		(fp_text user "License: Apache-2.0"
			(at -0.939 -5.799 90)
			(layer "B.Fab")
			(effects
				(font
					(size 0.7 0.7)
					(thickness 0.15)
				)
				(justify left bottom mirror)
			)
		)
		(fp_text user "${REFERENCE}"
			(at -0.939 -4.599 90)
			(layer "B.Fab")
			(effects
				(font
					(size 0.7 0.7)
					(thickness 0.15)
				)
				(justify left bottom mirror)
			)
		)
		(fp_text user "Author: Antmicro"
			(at -0.939 -3.399 90)
			(layer "B.Fab")
			(effects
				(font
					(size 0.7 0.7)
					(thickness 0.15)
				)
				(justify left bottom mirror)
			)
		)
		(pad "1" smd roundrect
			(at -0.48 0 270)
			(size 0.59 0.64)
			(layers "B.Cu" "B.Mask" "B.Paste")
			(roundrect_rratio 0.25)
			(net 23 "GND")
			(pintype "passive")
		)
		(pad "2" smd roundrect
			(at 0.48 0 270)
			(size 0.59 0.64)
			(layers "B.Cu" "B.Mask" "B.Paste")
			(roundrect_rratio 0.25)
			(net 406 "Net-(J3-LED_YG_Y-)")
			(pintype "passive")
		)
	)
	(footprint "antmicro-footprints:C_0402_1005Metric"
		(layer "B.Cu")
		(at 181.25 136 180)
		(descr "Capacitor SMD 0402")
		(tags "capacitor SMD 0402")
		(property "Reference" "C297"
			(at -1.2 0.5 0)
			(layer "B.SilkS")
			(effects
				(font
					(size 0.7 0.7)
					(thickness 0.15)
				)
				(justify left bottom mirror)
			)
		)
		(property "Value" "C_1u_25V_0402"
			(at -1.022927 -2.155213 0)
			(layer "B.Fab")
			(effects
				(font
					(size 0.7 0.7)
					(thickness 0.15)
				)
				(justify left bottom mirror)
			)
		)
		(property "Datasheet" "https://www.murata.com/products/productdetail?partno=GRM155R61E105KE11%23"
			(at 0 0 0)
			(layer "B.Fab")
			(hide yes)
			(effects
				(font
					(size 1.27 1.27)
					(thickness 0.15)
				)
				(justify mirror)
			)
		)
		(property "Description" "SMD Multilayer Ceramic Capacitor, 1 µF, 25 V, 0402 [1005 Metric], ± 10%, X5R, GRM Series"
			(at 0 0 0)
			(layer "B.Fab")
			(hide yes)
			(effects
				(font
					(size 1.27 1.27)
					(thickness 0.15)
				)
				(justify mirror)
			)
		)
		(property "MPN" "GRM155R61E105KE11J"
			(at 0 0 180)
			(unlocked yes)
			(layer "B.Fab")
			(hide yes)
			(effects
				(font
					(size 1 1)
					(thickness 0.15)
				)
				(justify mirror)
			)
		)
		(property "Manufacturer" "Murata"
			(at 0 0 180)
			(unlocked yes)
			(layer "B.Fab")
			(hide yes)
			(effects
				(font
					(size 1 1)
					(thickness 0.15)
				)
				(justify mirror)
			)
		)
		(property "License" "Apache-2.0"
			(at 0 0 180)
			(unlocked yes)
			(layer "B.Fab")
			(hide yes)
			(effects
				(font
					(size 1 1)
					(thickness 0.15)
				)
				(justify mirror)
			)
		)
		(property "Author" "Antmicro"
			(at 0 0 180)
			(unlocked yes)
			(layer "B.Fab")
			(hide yes)
			(effects
				(font
					(size 1 1)
					(thickness 0.15)
				)
				(justify mirror)
			)
		)
		(property "Val" "1u"
			(at 0 0 180)
			(unlocked yes)
			(layer "B.Fab")
			(hide yes)
			(effects
				(font
					(size 1 1)
					(thickness 0.15)
				)
				(justify mirror)
			)
		)
		(property "Voltage" "25V"
			(at 0 0 180)
			(unlocked yes)
			(layer "B.Fab")
			(hide yes)
			(effects
				(font
					(size 1 1)
					(thickness 0.15)
				)
				(justify mirror)
			)
		)
		(property "Dielectric" "X5R"
			(at 0 0 180)
			(unlocked yes)
			(layer "B.Fab")
			(hide yes)
			(effects
				(font
					(size 1 1)
					(thickness 0.15)
				)
				(justify mirror)
			)
		)
		(sheetname "/2xRJ45/")
		(sheetfile "2xrj45.kicad_sch")
		(attr smd)
		(fp_rect
			(start -0.925 0.47)
			(end 0.925 -0.47)
			(stroke
				(width 0.05)
				(type default)
			)
			(fill no)
			(layer "B.CrtYd")
		)
		(fp_line
			(start 0.504 0.25)
			(end 0.504 -0.248)
			(stroke
				(width 0.15)
				(type solid)
			)
			(layer "B.Fab")
		)
		(fp_line
			(start 0.504 -0.248)
			(end -0.494 -0.248)
			(stroke
				(width 0.15)
				(type solid)
			)
			(layer "B.Fab")
		)
		(fp_line
			(start -0.494 0.25)
			(end 0.504 0.25)
			(stroke
				(width 0.15)
				(type solid)
			)
			(layer "B.Fab")
		)
		(fp_line
			(start -0.494 -0.248)
			(end -0.494 0.25)
			(stroke
				(width 0.15)
				(type solid)
			)
			(layer "B.Fab")
		)
		(fp_text user "Author: Antmicro"
			(at -0.939 -3.399 0)
			(layer "B.Fab")
			(effects
				(font
					(size 0.7 0.7)
					(thickness 0.15)
				)
				(justify left bottom mirror)
			)
		)
		(fp_text user "${REFERENCE}"
			(at -0.939 -4.599 0)
			(layer "B.Fab")
			(effects
				(font
					(size 0.7 0.7)
					(thickness 0.15)
				)
				(justify left bottom mirror)
			)
		)
		(fp_text user "License: Apache-2.0"
			(at -0.939 -5.799 0)
			(layer "B.Fab")
			(effects
				(font
					(size 0.7 0.7)
					(thickness 0.15)
				)
				(justify left bottom mirror)
			)
		)
		(pad "1" smd roundrect
			(at -0.48 0 180)
			(size 0.59 0.64)
			(layers "B.Cu" "B.Mask" "B.Paste")
			(roundrect_rratio 0.25)
			(net 23 "GND")
			(pintype "passive")
		)
		(pad "2" smd roundrect
			(at 0.48 0 180)
			(size 0.59 0.64)
			(layers "B.Cu" "B.Mask" "B.Paste")
			(roundrect_rratio 0.25)
			(net 134 "/2xRJ45/P1_CT")
			(pintype "passive")
		)
	)
	(footprint "antmicro-footprints:R_0402_1005Metric"
		(layer "B.Cu")
		(at 134.850002 131.099998 -90)
		(descr "Resistor SMD 0402")
		(tags "resistor SMD 0402")
		(property "Reference" "R25"
			(at -8.35 -19.525001 90)
			(layer "B.SilkS")
			(effects
				(font
					(size 0.7 0.7)
					(thickness 0.15)
				)
				(justify mirror)
			)
		)
		(property "Value" "R_0R_0402"
			(at -1.011843 -1.772047 90)
			(layer "B.Fab")
			(effects
				(font
					(size 0.7 0.7)
					(thickness 0.15)
				)
				(justify left bottom mirror)
			)
		)
		(property "Datasheet" "https://industrial.panasonic.com/cdbs/www-data/pdf/RDA0000/AOA0000C301.pdf"
			(at 0 0 90)
			(layer "B.Fab")
			(hide yes)
			(effects
				(font
					(size 1.27 1.27)
					(thickness 0.15)
				)
				(justify mirror)
			)
		)
		(property "Description" "SMD Chip Resistor, Jumper, 0 ohm, 100 mW, 0402 [1005 Metric], Thick Film, General Purpose"
			(at 0 0 90)
			(layer "B.Fab")
			(hide yes)
			(effects
				(font
					(size 1.27 1.27)
					(thickness 0.15)
				)
				(justify mirror)
			)
		)
		(property "MPN" "ERJ2GE0R00X"
			(at 0 0 270)
			(unlocked yes)
			(layer "B.Fab")
			(hide yes)
			(effects
				(font
					(size 1 1)
					(thickness 0.15)
				)
				(justify mirror)
			)
		)
		(property "Manufacturer" "Panasonic"
			(at 0 0 270)
			(unlocked yes)
			(layer "B.Fab")
			(hide yes)
			(effects
				(font
					(size 1 1)
					(thickness 0.15)
				)
				(justify mirror)
			)
		)
		(property "License" "Apache-2.0"
			(at 0 0 270)
			(unlocked yes)
			(layer "B.Fab")
			(hide yes)
			(effects
				(font
					(size 1 1)
					(thickness 0.15)
				)
				(justify mirror)
			)
		)
		(property "Val" "0R"
			(at 0 0 270)
			(unlocked yes)
			(layer "B.Fab")
			(hide yes)
			(effects
				(font
					(size 1 1)
					(thickness 0.15)
				)
				(justify mirror)
			)
		)
		(property "Tolerance" "~"
			(at 0 0 270)
			(unlocked yes)
			(layer "B.Fab")
			(hide yes)
			(effects
				(font
					(size 1 1)
					(thickness 0.15)
				)
				(justify mirror)
			)
		)
		(property "Current" "1A"
			(at 0 0 270)
			(unlocked yes)
			(layer "B.Fab")
			(hide yes)
			(effects
				(font
					(size 1 1)
					(thickness 0.15)
				)
				(justify mirror)
			)
		)
		(property "Author" "Antmicro"
			(at 0 0 270)
			(unlocked yes)
			(layer "B.Fab")
			(hide yes)
			(effects
				(font
					(size 1 1)
					(thickness 0.15)
				)
				(justify mirror)
			)
		)
		(sheetname "/PD and TB DC-DC/")
		(sheetfile "PD_and_TB_DC_DC.kicad_sch")
		(attr smd)
		(fp_rect
			(start -0.925 0.47)
			(end 0.925 -0.47)
			(stroke
				(width 0.05)
				(type default)
			)
			(fill no)
			(layer "B.CrtYd")
		)
		(fp_rect
			(start -0.5 0.25)
			(end 0.5 -0.25)
			(stroke
				(width 0.15)
				(type solid)
			)
			(fill no)
			(layer "B.Fab")
		)
		(fp_text user "${REFERENCE}"
			(at -0.95 -3.168 90)
			(layer "B.Fab")
			(effects
				(font
					(size 0.7 0.7)
					(thickness 0.15)
				)
				(justify left bottom mirror)
			)
		)
		(fp_text user "License: Apache-2.0"
			(at -0.95 -5.169 90)
			(layer "B.Fab")
			(effects
				(font
					(size 0.7 0.7)
					(thickness 0.15)
				)
				(justify left bottom mirror)
			)
		)
		(fp_text user "Author: Antmicro"
			(at -0.95 -4.169 90)
			(layer "B.Fab")
			(effects
				(font
					(size 0.7 0.7)
					(thickness 0.15)
				)
				(justify left bottom mirror)
			)
		)
		(pad "1" smd roundrect
			(at -0.48 0 270)
			(size 0.59 0.64)
			(layers "B.Cu" "B.Mask" "B.Paste")
			(roundrect_rratio 0.25)
			(net 208 "Net-(U3-I2C_ADDR)")
			(pintype "passive")
		)
		(pad "2" smd roundrect
			(at 0.48 0 270)
			(size 0.59 0.64)
			(layers "B.Cu" "B.Mask" "B.Paste")
			(roundrect_rratio 0.25)
			(net 23 "GND")
			(pintype "passive")
		)
	)
	(footprint "antmicro-footprints:C_0402_1005Metric"
		(layer "B.Cu")
		(at 153.031866 81.260117 180)
		(descr "Capacitor SMD 0402")
		(tags "capacitor SMD 0402")
		(property "Reference" "C229"
			(at -21.168135 -9.464883 0)
			(layer "B.SilkS")
			(effects
				(font
					(size 0.7 0.7)
					(thickness 0.15)
				)
				(justify mirror)
			)
		)
		(property "Value" "C_1u_25V_0402"
			(at -1.022927 -2.155213 0)
			(layer "B.Fab")
			(effects
				(font
					(size 0.7 0.7)
					(thickness 0.15)
				)
				(justify left bottom mirror)
			)
		)
		(property "Datasheet" "https://www.murata.com/products/productdetail?partno=GRM155R61E105KE11%23"
			(at 0 0 0)
			(layer "B.Fab")
			(hide yes)
			(effects
				(font
					(size 1.27 1.27)
					(thickness 0.15)
				)
				(justify mirror)
			)
		)
		(property "Description" "SMD Multilayer Ceramic Capacitor, 1 µF, 25 V, 0402 [1005 Metric], ± 10%, X5R, GRM Series"
			(at 0 0 0)
			(layer "B.Fab")
			(hide yes)
			(effects
				(font
					(size 1.27 1.27)
					(thickness 0.15)
				)
				(justify mirror)
			)
		)
		(property "MPN" "GRM155R61E105KE11J"
			(at 0 0 180)
			(unlocked yes)
			(layer "B.Fab")
			(hide yes)
			(effects
				(font
					(size 1 1)
					(thickness 0.15)
				)
				(justify mirror)
			)
		)
		(property "Manufacturer" "Murata"
			(at 0 0 180)
			(unlocked yes)
			(layer "B.Fab")
			(hide yes)
			(effects
				(font
					(size 1 1)
					(thickness 0.15)
				)
				(justify mirror)
			)
		)
		(property "License" "Apache-2.0"
			(at 0 0 180)
			(unlocked yes)
			(layer "B.Fab")
			(hide yes)
			(effects
				(font
					(size 1 1)
					(thickness 0.15)
				)
				(justify mirror)
			)
		)
		(property "Author" "Antmicro"
			(at 0 0 180)
			(unlocked yes)
			(layer "B.Fab")
			(hide yes)
			(effects
				(font
					(size 1 1)
					(thickness 0.15)
				)
				(justify mirror)
			)
		)
		(property "Val" "1u"
			(at 0 0 180)
			(unlocked yes)
			(layer "B.Fab")
			(hide yes)
			(effects
				(font
					(size 1 1)
					(thickness 0.15)
				)
				(justify mirror)
			)
		)
		(property "Voltage" "25V"
			(at 0 0 180)
			(unlocked yes)
			(layer "B.Fab")
			(hide yes)
			(effects
				(font
					(size 1 1)
					(thickness 0.15)
				)
				(justify mirror)
			)
		)
		(property "Dielectric" "X5R"
			(at 0 0 180)
			(unlocked yes)
			(layer "B.Fab")
			(hide yes)
			(effects
				(font
					(size 1 1)
					(thickness 0.15)
				)
				(justify mirror)
			)
		)
		(sheetname "/X710-AT2 power/")
		(sheetfile "x710-at2-power.kicad_sch")
		(attr smd)
		(fp_rect
			(start -0.925 0.47)
			(end 0.925 -0.47)
			(stroke
				(width 0.05)
				(type default)
			)
			(fill no)
			(layer "B.CrtYd")
		)
		(fp_line
			(start 0.504 0.25)
			(end 0.504 -0.248)
			(stroke
				(width 0.15)
				(type solid)
			)
			(layer "B.Fab")
		)
		(fp_line
			(start 0.504 -0.248)
			(end -0.494 -0.248)
			(stroke
				(width 0.15)
				(type solid)
			)
			(layer "B.Fab")
		)
		(fp_line
			(start -0.494 0.25)
			(end 0.504 0.25)
			(stroke
				(width 0.15)
				(type solid)
			)
			(layer "B.Fab")
		)
		(fp_line
			(start -0.494 -0.248)
			(end -0.494 0.25)
			(stroke
				(width 0.15)
				(type solid)
			)
			(layer "B.Fab")
		)
		(fp_text user "${REFERENCE}"
			(at -0.939 -4.599 0)
			(layer "B.Fab")
			(effects
				(font
					(size 0.7 0.7)
					(thickness 0.15)
				)
				(justify left bottom mirror)
			)
		)
		(fp_text user "License: Apache-2.0"
			(at -0.939 -5.799 0)
			(layer "B.Fab")
			(effects
				(font
					(size 0.7 0.7)
					(thickness 0.15)
				)
				(justify left bottom mirror)
			)
		)
		(fp_text user "Author: Antmicro"
			(at -0.939 -3.399 0)
			(layer "B.Fab")
			(effects
				(font
					(size 0.7 0.7)
					(thickness 0.15)
				)
				(justify left bottom mirror)
			)
		)
		(pad "1" smd roundrect
			(at -0.48 0 180)
			(size 0.59 0.64)
			(layers "B.Cu" "B.Mask" "B.Paste")
			(roundrect_rratio 0.25)
			(net 23 "GND")
			(pintype "passive")
		)
		(pad "2" smd roundrect
			(at 0.48 0 180)
			(size 0.59 0.64)
			(layers "B.Cu" "B.Mask" "B.Paste")
			(roundrect_rratio 0.25)
			(net 9 "VCCD")
			(pintype "passive")
		)
	)
	(footprint "antmicro-footprints:R_0402_1005Metric"
		(layer "B.Cu")
		(at 154.131866 70.035118 90)
		(descr "Resistor SMD 0402")
		(tags "resistor SMD 0402")
		(property "Reference" "R187"
			(at -9.464883 19.468134 270)
			(layer "B.SilkS")
			(effects
				(font
					(size 0.7 0.7)
					(thickness 0.15)
				)
				(justify mirror)
			)
		)
		(property "Value" "R_3k3_0402"
			(at -1.011843 -1.772047 270)
			(layer "B.Fab")
			(effects
				(font
					(size 0.7 0.7)
					(thickness 0.15)
				)
				(justify left bottom mirror)
			)
		)
		(property "Datasheet" "https://www.bourns.com/docs/product-datasheets/cr.pdf"
			(at 0 0 270)
			(layer "B.Fab")
			(hide yes)
			(effects
				(font
					(size 1.27 1.27)
					(thickness 0.15)
				)
				(justify mirror)
			)
		)
		(property "Description" "SMD Chip Resistor, 3.3 kohm, ± 1%, 63 mW, 0402 [1005 Metric], Thick Film, General Purpose"
			(at 0 0 270)
			(layer "B.Fab")
			(hide yes)
			(effects
				(font
					(size 1.27 1.27)
					(thickness 0.15)
				)
				(justify mirror)
			)
		)
		(property "MPN" "CR0402-FX-3301GLF"
			(at 0 0 90)
			(unlocked yes)
			(layer "B.Fab")
			(hide yes)
			(effects
				(font
					(size 1 1)
					(thickness 0.15)
				)
				(justify mirror)
			)
		)
		(property "Manufacturer" "Bourns"
			(at 0 0 90)
			(unlocked yes)
			(layer "B.Fab")
			(hide yes)
			(effects
				(font
					(size 1 1)
					(thickness 0.15)
				)
				(justify mirror)
			)
		)
		(property "License" "Apache-2.0"
			(at 0 0 90)
			(unlocked yes)
			(layer "B.Fab")
			(hide yes)
			(effects
				(font
					(size 1 1)
					(thickness 0.15)
				)
				(justify mirror)
			)
		)
		(property "Author" "Antmicro"
			(at 0 0 90)
			(unlocked yes)
			(layer "B.Fab")
			(hide yes)
			(effects
				(font
					(size 1 1)
					(thickness 0.15)
				)
				(justify mirror)
			)
		)
		(property "Val" "3k3"
			(at 0 0 90)
			(unlocked yes)
			(layer "B.Fab")
			(hide yes)
			(effects
				(font
					(size 1 1)
					(thickness 0.15)
				)
				(justify mirror)
			)
		)
		(property "Tolerance" "1%"
			(at 0 0 90)
			(unlocked yes)
			(layer "B.Fab")
			(hide yes)
			(effects
				(font
					(size 1 1)
					(thickness 0.15)
				)
				(justify mirror)
			)
		)
		(sheetname "/X710-AT2 10GbE/")
		(sheetfile "x710-at2-10gbe.kicad_sch")
		(attr smd)
		(fp_rect
			(start -0.925 0.47)
			(end 0.925 -0.47)
			(stroke
				(width 0.05)
				(type default)
			)
			(fill no)
			(layer "B.CrtYd")
		)
		(fp_rect
			(start -0.5 0.25)
			(end 0.5 -0.25)
			(stroke
				(width 0.15)
				(type solid)
			)
			(fill no)
			(layer "B.Fab")
		)
		(fp_text user "${REFERENCE}"
			(at -0.95 -3.168 270)
			(layer "B.Fab")
			(effects
				(font
					(size 0.7 0.7)
					(thickness 0.15)
				)
				(justify left bottom mirror)
			)
		)
		(fp_text user "License: Apache-2.0"
			(at -0.95 -5.169 270)
			(layer "B.Fab")
			(effects
				(font
					(size 0.7 0.7)
					(thickness 0.15)
				)
				(justify left bottom mirror)
			)
		)
		(fp_text user "Author: Antmicro"
			(at -0.95 -4.169 270)
			(layer "B.Fab")
			(effects
				(font
					(size 0.7 0.7)
					(thickness 0.15)
				)
				(justify left bottom mirror)
			)
		)
		(pad "1" smd roundrect
			(at -0.48 0 90)
			(size 0.59 0.64)
			(layers "B.Cu" "B.Mask" "B.Paste")
			(roundrect_rratio 0.25)
			(net 70 "/X710-AT2 10GbE/MDC3_SCL3")
			(pintype "passive")
		)
		(pad "2" smd roundrect
			(at 0.48 0 90)
			(size 0.59 0.64)
			(layers "B.Cu" "B.Mask" "B.Paste")
			(roundrect_rratio 0.25)
			(net 7 "+3V3")
			(pintype "passive")
		)
	)
	(footprint "antmicro-footprints:R_0402_1005Metric"
		(layer "B.Cu")
		(at 137.5 126.6)
		(descr "Resistor SMD 0402")
		(tags "resistor SMD 0402")
		(property "Reference" "R50"
			(at 19.525001 -7.450001 180)
			(layer "B.SilkS")
			(effects
				(font
					(size 0.7 0.7)
					(thickness 0.15)
				)
				(justify mirror)
			)
		)
		(property "Value" "R_100k_0402"
			(at -1.011843 -1.772047 180)
			(layer "B.Fab")
			(effects
				(font
					(size 0.7 0.7)
					(thickness 0.15)
				)
				(justify left bottom mirror)
			)
		)
		(property "Datasheet" "https://www.bourns.com/docs/product-datasheets/cr.pdf"
			(at 0 0 180)
			(layer "B.Fab")
			(hide yes)
			(effects
				(font
					(size 1.27 1.27)
					(thickness 0.15)
				)
				(justify mirror)
			)
		)
		(property "Description" "SMD Chip Resistor, 100 kohm, ± 1%, 62.5 mW, 0402 [1005 Metric], Thick Film, General Purpose"
			(at 0 0 180)
			(layer "B.Fab")
			(hide yes)
			(effects
				(font
					(size 1.27 1.27)
					(thickness 0.15)
				)
				(justify mirror)
			)
		)
		(property "MPN" "CR0402-FX-1003GLF"
			(at 0 0 0)
			(unlocked yes)
			(layer "B.Fab")
			(hide yes)
			(effects
				(font
					(size 1 1)
					(thickness 0.15)
				)
				(justify mirror)
			)
		)
		(property "Manufacturer" "Bourns"
			(at 0 0 0)
			(unlocked yes)
			(layer "B.Fab")
			(hide yes)
			(effects
				(font
					(size 1 1)
					(thickness 0.15)
				)
				(justify mirror)
			)
		)
		(property "License" "Apache-2.0"
			(at 0 0 0)
			(unlocked yes)
			(layer "B.Fab")
			(hide yes)
			(effects
				(font
					(size 1 1)
					(thickness 0.15)
				)
				(justify mirror)
			)
		)
		(property "Val" "100k"
			(at 0 0 0)
			(unlocked yes)
			(layer "B.Fab")
			(hide yes)
			(effects
				(font
					(size 1 1)
					(thickness 0.15)
				)
				(justify mirror)
			)
		)
		(property "Tolerance" "1%"
			(at 0 0 0)
			(unlocked yes)
			(layer "B.Fab")
			(hide yes)
			(effects
				(font
					(size 1 1)
					(thickness 0.15)
				)
				(justify mirror)
			)
		)
		(property "Author" "Antmicro"
			(at 0 0 0)
			(unlocked yes)
			(layer "B.Fab")
			(hide yes)
			(effects
				(font
					(size 1 1)
					(thickness 0.15)
				)
				(justify mirror)
			)
		)
		(sheetname "/TB Controller/")
		(sheetfile "tb.kicad_sch")
		(attr smd)
		(fp_rect
			(start -0.925 0.47)
			(end 0.925 -0.47)
			(stroke
				(width 0.05)
				(type default)
			)
			(fill no)
			(layer "B.CrtYd")
		)
		(fp_rect
			(start -0.5 0.25)
			(end 0.5 -0.25)
			(stroke
				(width 0.15)
				(type solid)
			)
			(fill no)
			(layer "B.Fab")
		)
		(fp_text user "Author: Antmicro"
			(at -0.95 -4.169 180)
			(layer "B.Fab")
			(effects
				(font
					(size 0.7 0.7)
					(thickness 0.15)
				)
				(justify left bottom mirror)
			)
		)
		(fp_text user "${REFERENCE}"
			(at -0.95 -3.168 180)
			(layer "B.Fab")
			(effects
				(font
					(size 0.7 0.7)
					(thickness 0.15)
				)
				(justify left bottom mirror)
			)
		)
		(fp_text user "License: Apache-2.0"
			(at -0.95 -5.169 180)
			(layer "B.Fab")
			(effects
				(font
					(size 0.7 0.7)
					(thickness 0.15)
				)
				(justify left bottom mirror)
			)
		)
		(pad "1" smd roundrect
			(at -0.48 0)
			(size 0.59 0.64)
			(layers "B.Cu" "B.Mask" "B.Paste")
			(roundrect_rratio 0.25)
			(net 193 "Net-(U4C-POC_GPIO_2)")
			(pintype "passive")
		)
		(pad "2" smd roundrect
			(at 0.48 0)
			(size 0.59 0.64)
			(layers "B.Cu" "B.Mask" "B.Paste")
			(roundrect_rratio 0.25)
			(net 23 "GND")
			(pintype "passive")
		)
	)
	(footprint "antmicro-footprints:R_0402_1005Metric"
		(layer "B.Cu")
		(at 133.85 131.1 -90)
		(descr "Resistor SMD 0402")
		(tags "resistor SMD 0402")
		(property "Reference" "R5"
			(at -8.35 -19.525001 90)
			(layer "B.SilkS")
			(effects
				(font
					(size 0.7 0.7)
					(thickness 0.15)
				)
				(justify mirror)
			)
		)
		(property "Value" "R_100k_0402"
			(at -1.011843 -1.772047 90)
			(layer "B.Fab")
			(effects
				(font
					(size 0.7 0.7)
					(thickness 0.15)
				)
				(justify left bottom mirror)
			)
		)
		(property "Datasheet" "https://www.bourns.com/docs/product-datasheets/cr.pdf"
			(at 0 0 90)
			(layer "B.Fab")
			(hide yes)
			(effects
				(font
					(size 1.27 1.27)
					(thickness 0.15)
				)
				(justify mirror)
			)
		)
		(property "Description" "SMD Chip Resistor, 100 kohm, ± 1%, 62.5 mW, 0402 [1005 Metric], Thick Film, General Purpose"
			(at 0 0 90)
			(layer "B.Fab")
			(hide yes)
			(effects
				(font
					(size 1.27 1.27)
					(thickness 0.15)
				)
				(justify mirror)
			)
		)
		(property "MPN" "CR0402-FX-1003GLF"
			(at 0 0 270)
			(unlocked yes)
			(layer "B.Fab")
			(hide yes)
			(effects
				(font
					(size 1 1)
					(thickness 0.15)
				)
				(justify mirror)
			)
		)
		(property "Manufacturer" "Bourns"
			(at 0 0 270)
			(unlocked yes)
			(layer "B.Fab")
			(hide yes)
			(effects
				(font
					(size 1 1)
					(thickness 0.15)
				)
				(justify mirror)
			)
		)
		(property "License" "Apache-2.0"
			(at 0 0 270)
			(unlocked yes)
			(layer "B.Fab")
			(hide yes)
			(effects
				(font
					(size 1 1)
					(thickness 0.15)
				)
				(justify mirror)
			)
		)
		(property "Val" "100k"
			(at 0 0 270)
			(unlocked yes)
			(layer "B.Fab")
			(hide yes)
			(effects
				(font
					(size 1 1)
					(thickness 0.15)
				)
				(justify mirror)
			)
		)
		(property "Tolerance" "1%"
			(at 0 0 270)
			(unlocked yes)
			(layer "B.Fab")
			(hide yes)
			(effects
				(font
					(size 1 1)
					(thickness 0.15)
				)
				(justify mirror)
			)
		)
		(property "Author" "Antmicro"
			(at 0 0 270)
			(unlocked yes)
			(layer "B.Fab")
			(hide yes)
			(effects
				(font
					(size 1 1)
					(thickness 0.15)
				)
				(justify mirror)
			)
		)
		(sheetname "/PD and TB DC-DC/")
		(sheetfile "PD_and_TB_DC_DC.kicad_sch")
		(attr smd)
		(fp_rect
			(start -0.925 0.47)
			(end 0.925 -0.47)
			(stroke
				(width 0.05)
				(type default)
			)
			(fill no)
			(layer "B.CrtYd")
		)
		(fp_rect
			(start -0.5 0.25)
			(end 0.5 -0.25)
			(stroke
				(width 0.15)
				(type solid)
			)
			(fill no)
			(layer "B.Fab")
		)
		(fp_text user "Author: Antmicro"
			(at -0.95 -4.169 90)
			(layer "B.Fab")
			(effects
				(font
					(size 0.7 0.7)
					(thickness 0.15)
				)
				(justify left bottom mirror)
			)
		)
		(fp_text user "${REFERENCE}"
			(at -0.95 -3.168 90)
			(layer "B.Fab")
			(effects
				(font
					(size 0.7 0.7)
					(thickness 0.15)
				)
				(justify left bottom mirror)
			)
		)
		(fp_text user "License: Apache-2.0"
			(at -0.95 -5.169 90)
			(layer "B.Fab")
			(effects
				(font
					(size 0.7 0.7)
					(thickness 0.15)
				)
				(justify left bottom mirror)
			)
		)
		(pad "1" smd roundrect
			(at -0.48 0 270)
			(size 0.59 0.64)
			(layers "B.Cu" "B.Mask" "B.Paste")
			(roundrect_rratio 0.25)
			(net 23 "GND")
			(pintype "passive")
		)
		(pad "2" smd roundrect
			(at 0.48 0 270)
			(size 0.59 0.64)
			(layers "B.Cu" "B.Mask" "B.Paste")
			(roundrect_rratio 0.25)
			(net 69 "/PD and TB DC-DC/AUX.+")
			(pintype "passive")
		)
	)
	(footprint "antmicro-footprints:TP_SMD_0.75mm"
		(layer "B.Cu")
		(at 183.75 86.25 180)
		(property "Reference" "TP5"
			(at -0.75 -14.5 270)
			(layer "B.SilkS")
			(effects
				(font
					(size 0.7 0.7)
					(thickness 0.15)
				)
				(justify left bottom mirror)
			)
		)
		(property "Value" "TP_0.75mm_SMD"
			(at 0 -1.2 0)
			(layer "B.Fab")
			(effects
				(font
					(size 0.7 0.7)
					(thickness 0.15)
				)
				(justify left bottom mirror)
			)
		)
		(property "Description" "SMT test point"
			(at 0 0 0)
			(layer "B.Fab")
			(hide yes)
			(effects
				(font
					(size 1.27 1.27)
					(thickness 0.15)
				)
				(justify mirror)
			)
		)
		(property "MPN" ""
			(at 0 0 180)
			(unlocked yes)
			(layer "B.Fab")
			(hide yes)
			(effects
				(font
					(size 1 1)
					(thickness 0.15)
				)
				(justify mirror)
			)
		)
		(property "Manufacturer" ""
			(at 0 0 180)
			(unlocked yes)
			(layer "B.Fab")
			(hide yes)
			(effects
				(font
					(size 1 1)
					(thickness 0.15)
				)
				(justify mirror)
			)
		)
		(property "Author" "Antmicro"
			(at 0 0 180)
			(unlocked yes)
			(layer "B.Fab")
			(hide yes)
			(effects
				(font
					(size 1 1)
					(thickness 0.15)
				)
				(justify mirror)
			)
		)
		(property "License" "Apache-2.0"
			(at 0 0 180)
			(unlocked yes)
			(layer "B.Fab")
			(hide yes)
			(effects
				(font
					(size 1 1)
					(thickness 0.15)
				)
				(justify mirror)
			)
		)
		(sheetname "/X710 DCDC converters/")
		(sheetfile "DCDC_converters_X710.kicad_sch")
		(attr exclude_from_pos_files exclude_from_bom)
		(fp_circle
			(center 0 0)
			(end 0.475 0)
			(stroke
				(width 0.05)
				(type default)
			)
			(fill no)
			(layer "B.CrtYd")
		)
		(fp_text user "Author: Antmicro"
			(at -0.4 -3.901 0)
			(layer "B.Fab")
			(effects
				(font
					(size 0.7 0.7)
					(thickness 0.15)
				)
				(justify left bottom mirror)
			)
		)
		(fp_text user "License: Apache-2.0"
			(at -0.4 -5.101 0)
			(layer "B.Fab")
			(effects
				(font
					(size 0.7 0.7)
					(thickness 0.15)
				)
				(justify left bottom mirror)
			)
		)
		(fp_text user "${REFERENCE}"
			(at -0.4 -2.7 0)
			(layer "B.Fab")
			(effects
				(font
					(size 0.7 0.7)
					(thickness 0.15)
				)
				(justify left bottom mirror)
			)
		)
		(pad "1" smd circle
			(at 0 0 180)
			(size 0.75 0.75)
			(layers "B.Cu" "B.Mask")
			(net 23 "GND")
			(pinfunction "1")
			(pintype "passive")
		)
	)
	(footprint "antmicro-footprints:C_0402_1005Metric"
		(layer "B.Cu")
		(at 145.631866 81.260117 180)
		(descr "Capacitor SMD 0402")
		(tags "capacitor SMD 0402")
		(property "Reference" "C255"
			(at -17.768134 -9.464883 0)
			(layer "B.SilkS")
			(effects
				(font
					(size 0.7 0.7)
					(thickness 0.15)
				)
				(justify mirror)
			)
		)
		(property "Value" "C_1u_25V_0402"
			(at -1.022927 -2.155213 0)
			(layer "B.Fab")
			(effects
				(font
					(size 0.7 0.7)
					(thickness 0.15)
				)
				(justify left bottom mirror)
			)
		)
		(property "Datasheet" "https://www.murata.com/products/productdetail?partno=GRM155R61E105KE11%23"
			(at 0 0 0)
			(layer "B.Fab")
			(hide yes)
			(effects
				(font
					(size 1.27 1.27)
					(thickness 0.15)
				)
				(justify mirror)
			)
		)
		(property "Description" "SMD Multilayer Ceramic Capacitor, 1 µF, 25 V, 0402 [1005 Metric], ± 10%, X5R, GRM Series"
			(at 0 0 0)
			(layer "B.Fab")
			(hide yes)
			(effects
				(font
					(size 1.27 1.27)
					(thickness 0.15)
				)
				(justify mirror)
			)
		)
		(property "MPN" "GRM155R61E105KE11J"
			(at 0 0 180)
			(unlocked yes)
			(layer "B.Fab")
			(hide yes)
			(effects
				(font
					(size 1 1)
					(thickness 0.15)
				)
				(justify mirror)
			)
		)
		(property "Manufacturer" "Murata"
			(at 0 0 180)
			(unlocked yes)
			(layer "B.Fab")
			(hide yes)
			(effects
				(font
					(size 1 1)
					(thickness 0.15)
				)
				(justify mirror)
			)
		)
		(property "License" "Apache-2.0"
			(at 0 0 180)
			(unlocked yes)
			(layer "B.Fab")
			(hide yes)
			(effects
				(font
					(size 1 1)
					(thickness 0.15)
				)
				(justify mirror)
			)
		)
		(property "Author" "Antmicro"
			(at 0 0 180)
			(unlocked yes)
			(layer "B.Fab")
			(hide yes)
			(effects
				(font
					(size 1 1)
					(thickness 0.15)
				)
				(justify mirror)
			)
		)
		(property "Val" "1u"
			(at 0 0 180)
			(unlocked yes)
			(layer "B.Fab")
			(hide yes)
			(effects
				(font
					(size 1 1)
					(thickness 0.15)
				)
				(justify mirror)
			)
		)
		(property "Voltage" "25V"
			(at 0 0 180)
			(unlocked yes)
			(layer "B.Fab")
			(hide yes)
			(effects
				(font
					(size 1 1)
					(thickness 0.15)
				)
				(justify mirror)
			)
		)
		(property "Dielectric" "X5R"
			(at 0 0 180)
			(unlocked yes)
			(layer "B.Fab")
			(hide yes)
			(effects
				(font
					(size 1 1)
					(thickness 0.15)
				)
				(justify mirror)
			)
		)
		(sheetname "/X710-AT2 power/")
		(sheetfile "x710-at2-power.kicad_sch")
		(attr smd)
		(fp_rect
			(start -0.925 0.47)
			(end 0.925 -0.47)
			(stroke
				(width 0.05)
				(type default)
			)
			(fill no)
			(layer "B.CrtYd")
		)
		(fp_line
			(start 0.504 0.25)
			(end 0.504 -0.248)
			(stroke
				(width 0.15)
				(type solid)
			)
			(layer "B.Fab")
		)
		(fp_line
			(start 0.504 -0.248)
			(end -0.494 -0.248)
			(stroke
				(width 0.15)
				(type solid)
			)
			(layer "B.Fab")
		)
		(fp_line
			(start -0.494 0.25)
			(end 0.504 0.25)
			(stroke
				(width 0.15)
				(type solid)
			)
			(layer "B.Fab")
		)
		(fp_line
			(start -0.494 -0.248)
			(end -0.494 0.25)
			(stroke
				(width 0.15)
				(type solid)
			)
			(layer "B.Fab")
		)
		(fp_text user "Author: Antmicro"
			(at -0.939 -3.399 0)
			(layer "B.Fab")
			(effects
				(font
					(size 0.7 0.7)
					(thickness 0.15)
				)
				(justify left bottom mirror)
			)
		)
		(fp_text user "${REFERENCE}"
			(at -0.939 -4.599 0)
			(layer "B.Fab")
			(effects
				(font
					(size 0.7 0.7)
					(thickness 0.15)
				)
				(justify left bottom mirror)
			)
		)
		(fp_text user "License: Apache-2.0"
			(at -0.939 -5.799 0)
			(layer "B.Fab")
			(effects
				(font
					(size 0.7 0.7)
					(thickness 0.15)
				)
				(justify left bottom mirror)
			)
		)
		(pad "1" smd roundrect
			(at -0.48 0 180)
			(size 0.59 0.64)
			(layers "B.Cu" "B.Mask" "B.Paste")
			(roundrect_rratio 0.25)
			(net 23 "GND")
			(pintype "passive")
		)
		(pad "2" smd roundrect
			(at 0.48 0 180)
			(size 0.59 0.64)
			(layers "B.Cu" "B.Mask" "B.Paste")
			(roundrect_rratio 0.25)
			(net 1 "VCCA")
			(pintype "passive")
		)
	)
	(footprint "antmicro-footprints:C_0402_1005Metric"
		(layer "B.Cu")
		(at 145.631866 75.260117 180)
		(descr "Capacitor SMD 0402")
		(tags "capacitor SMD 0402")
		(property "Reference" "C213"
			(at -17.768134 -9.464883 0)
			(layer "B.SilkS")
			(effects
				(font
					(size 0.7 0.7)
					(thickness 0.15)
				)
				(justify mirror)
			)
		)
		(property "Value" "C_1u_25V_0402"
			(at -1.022927 -2.155213 0)
			(layer "B.Fab")
			(effects
				(font
					(size 0.7 0.7)
					(thickness 0.15)
				)
				(justify left bottom mirror)
			)
		)
		(property "Datasheet" "https://www.murata.com/products/productdetail?partno=GRM155R61E105KE11%23"
			(at 0 0 0)
			(layer "B.Fab")
			(hide yes)
			(effects
				(font
					(size 1.27 1.27)
					(thickness 0.15)
				)
				(justify mirror)
			)
		)
		(property "Description" "SMD Multilayer Ceramic Capacitor, 1 µF, 25 V, 0402 [1005 Metric], ± 10%, X5R, GRM Series"
			(at 0 0 0)
			(layer "B.Fab")
			(hide yes)
			(effects
				(font
					(size 1.27 1.27)
					(thickness 0.15)
				)
				(justify mirror)
			)
		)
		(property "MPN" "GRM155R61E105KE11J"
			(at 0 0 180)
			(unlocked yes)
			(layer "B.Fab")
			(hide yes)
			(effects
				(font
					(size 1 1)
					(thickness 0.15)
				)
				(justify mirror)
			)
		)
		(property "Manufacturer" "Murata"
			(at 0 0 180)
			(unlocked yes)
			(layer "B.Fab")
			(hide yes)
			(effects
				(font
					(size 1 1)
					(thickness 0.15)
				)
				(justify mirror)
			)
		)
		(property "License" "Apache-2.0"
			(at 0 0 180)
			(unlocked yes)
			(layer "B.Fab")
			(hide yes)
			(effects
				(font
					(size 1 1)
					(thickness 0.15)
				)
				(justify mirror)
			)
		)
		(property "Author" "Antmicro"
			(at 0 0 180)
			(unlocked yes)
			(layer "B.Fab")
			(hide yes)
			(effects
				(font
					(size 1 1)
					(thickness 0.15)
				)
				(justify mirror)
			)
		)
		(property "Val" "1u"
			(at 0 0 180)
			(unlocked yes)
			(layer "B.Fab")
			(hide yes)
			(effects
				(font
					(size 1 1)
					(thickness 0.15)
				)
				(justify mirror)
			)
		)
		(property "Voltage" "25V"
			(at 0 0 180)
			(unlocked yes)
			(layer "B.Fab")
			(hide yes)
			(effects
				(font
					(size 1 1)
					(thickness 0.15)
				)
				(justify mirror)
			)
		)
		(property "Dielectric" "X5R"
			(at 0 0 180)
			(unlocked yes)
			(layer "B.Fab")
			(hide yes)
			(effects
				(font
					(size 1 1)
					(thickness 0.15)
				)
				(justify mirror)
			)
		)
		(sheetname "/X710-AT2 power/")
		(sheetfile "x710-at2-power.kicad_sch")
		(attr smd)
		(fp_rect
			(start -0.925 0.47)
			(end 0.925 -0.47)
			(stroke
				(width 0.05)
				(type default)
			)
			(fill no)
			(layer "B.CrtYd")
		)
		(fp_line
			(start 0.504 0.25)
			(end 0.504 -0.248)
			(stroke
				(width 0.15)
				(type solid)
			)
			(layer "B.Fab")
		)
		(fp_line
			(start 0.504 -0.248)
			(end -0.494 -0.248)
			(stroke
				(width 0.15)
				(type solid)
			)
			(layer "B.Fab")
		)
		(fp_line
			(start -0.494 0.25)
			(end 0.504 0.25)
			(stroke
				(width 0.15)
				(type solid)
			)
			(layer "B.Fab")
		)
		(fp_line
			(start -0.494 -0.248)
			(end -0.494 0.25)
			(stroke
				(width 0.15)
				(type solid)
			)
			(layer "B.Fab")
		)
		(fp_text user "${REFERENCE}"
			(at -0.939 -4.599 0)
			(layer "B.Fab")
			(effects
				(font
					(size 0.7 0.7)
					(thickness 0.15)
				)
				(justify left bottom mirror)
			)
		)
		(fp_text user "Author: Antmicro"
			(at -0.939 -3.399 0)
			(layer "B.Fab")
			(effects
				(font
					(size 0.7 0.7)
					(thickness 0.15)
				)
				(justify left bottom mirror)
			)
		)
		(fp_text user "License: Apache-2.0"
			(at -0.939 -5.799 0)
			(layer "B.Fab")
			(effects
				(font
					(size 0.7 0.7)
					(thickness 0.15)
				)
				(justify left bottom mirror)
			)
		)
		(pad "1" smd roundrect
			(at -0.48 0 180)
			(size 0.59 0.64)
			(layers "B.Cu" "B.Mask" "B.Paste")
			(roundrect_rratio 0.25)
			(net 23 "GND")
			(pintype "passive")
		)
		(pad "2" smd roundrect
			(at 0.48 0 180)
			(size 0.59 0.64)
			(layers "B.Cu" "B.Mask" "B.Paste")
			(roundrect_rratio 0.25)
			(net 9 "VCCD")
			(pintype "passive")
		)
	)
	(footprint "antmicro-footprints:C_0402_1005Metric"
		(layer "B.Cu")
		(at 154.261866 86.265117 180)
		(descr "Capacitor SMD 0402")
		(tags "capacitor SMD 0402")
		(property "Reference" "C201"
			(at -17.938134 -9.464883 0)
			(layer "B.SilkS")
			(effects
				(font
					(size 0.7 0.7)
					(thickness 0.15)
				)
				(justify mirror)
			)
		)
		(property "Value" "C_1u_25V_0402"
			(at -1.022927 -2.155213 0)
			(layer "B.Fab")
			(effects
				(font
					(size 0.7 0.7)
					(thickness 0.15)
				)
				(justify left bottom mirror)
			)
		)
		(property "Datasheet" "https://www.murata.com/products/productdetail?partno=GRM155R61E105KE11%23"
			(at 0 0 0)
			(layer "B.Fab")
			(hide yes)
			(effects
				(font
					(size 1.27 1.27)
					(thickness 0.15)
				)
				(justify mirror)
			)
		)
		(property "Description" "SMD Multilayer Ceramic Capacitor, 1 µF, 25 V, 0402 [1005 Metric], ± 10%, X5R, GRM Series"
			(at 0 0 0)
			(layer "B.Fab")
			(hide yes)
			(effects
				(font
					(size 1.27 1.27)
					(thickness 0.15)
				)
				(justify mirror)
			)
		)
		(property "MPN" "GRM155R61E105KE11J"
			(at 0 0 180)
			(unlocked yes)
			(layer "B.Fab")
			(hide yes)
			(effects
				(font
					(size 1 1)
					(thickness 0.15)
				)
				(justify mirror)
			)
		)
		(property "Manufacturer" "Murata"
			(at 0 0 180)
			(unlocked yes)
			(layer "B.Fab")
			(hide yes)
			(effects
				(font
					(size 1 1)
					(thickness 0.15)
				)
				(justify mirror)
			)
		)
		(property "License" "Apache-2.0"
			(at 0 0 180)
			(unlocked yes)
			(layer "B.Fab")
			(hide yes)
			(effects
				(font
					(size 1 1)
					(thickness 0.15)
				)
				(justify mirror)
			)
		)
		(property "Author" "Antmicro"
			(at 0 0 180)
			(unlocked yes)
			(layer "B.Fab")
			(hide yes)
			(effects
				(font
					(size 1 1)
					(thickness 0.15)
				)
				(justify mirror)
			)
		)
		(property "Val" "1u"
			(at 0 0 180)
			(unlocked yes)
			(layer "B.Fab")
			(hide yes)
			(effects
				(font
					(size 1 1)
					(thickness 0.15)
				)
				(justify mirror)
			)
		)
		(property "Voltage" "25V"
			(at 0 0 180)
			(unlocked yes)
			(layer "B.Fab")
			(hide yes)
			(effects
				(font
					(size 1 1)
					(thickness 0.15)
				)
				(justify mirror)
			)
		)
		(property "Dielectric" "X5R"
			(at 0 0 180)
			(unlocked yes)
			(layer "B.Fab")
			(hide yes)
			(effects
				(font
					(size 1 1)
					(thickness 0.15)
				)
				(justify mirror)
			)
		)
		(sheetname "/X710-AT2 power/")
		(sheetfile "x710-at2-power.kicad_sch")
		(attr smd)
		(fp_rect
			(start -0.925 0.47)
			(end 0.925 -0.47)
			(stroke
				(width 0.05)
				(type default)
			)
			(fill no)
			(layer "B.CrtYd")
		)
		(fp_line
			(start 0.504 0.25)
			(end 0.504 -0.248)
			(stroke
				(width 0.15)
				(type solid)
			)
			(layer "B.Fab")
		)
		(fp_line
			(start 0.504 -0.248)
			(end -0.494 -0.248)
			(stroke
				(width 0.15)
				(type solid)
			)
			(layer "B.Fab")
		)
		(fp_line
			(start -0.494 0.25)
			(end 0.504 0.25)
			(stroke
				(width 0.15)
				(type solid)
			)
			(layer "B.Fab")
		)
		(fp_line
			(start -0.494 -0.248)
			(end -0.494 0.25)
			(stroke
				(width 0.15)
				(type solid)
			)
			(layer "B.Fab")
		)
		(fp_text user "License: Apache-2.0"
			(at -0.939 -5.799 0)
			(layer "B.Fab")
			(effects
				(font
					(size 0.7 0.7)
					(thickness 0.15)
				)
				(justify left bottom mirror)
			)
		)
		(fp_text user "${REFERENCE}"
			(at -0.939 -4.599 0)
			(layer "B.Fab")
			(effects
				(font
					(size 0.7 0.7)
					(thickness 0.15)
				)
				(justify left bottom mirror)
			)
		)
		(fp_text user "Author: Antmicro"
			(at -0.939 -3.399 0)
			(layer "B.Fab")
			(effects
				(font
					(size 0.7 0.7)
					(thickness 0.15)
				)
				(justify left bottom mirror)
			)
		)
		(pad "1" smd roundrect
			(at -0.48 0 180)
			(size 0.59 0.64)
			(layers "B.Cu" "B.Mask" "B.Paste")
			(roundrect_rratio 0.25)
			(net 23 "GND")
			(pintype "passive")
		)
		(pad "2" smd roundrect
			(at 0.48 0 180)
			(size 0.59 0.64)
			(layers "B.Cu" "B.Mask" "B.Paste")
			(roundrect_rratio 0.25)
			(net 12 "XFI_VDD")
			(pintype "passive")
		)
	)
	(footprint "antmicro-footprints:C_0402_1005Metric"
		(layer "B.Cu")
		(at 151.181866 79.260117 180)
		(descr "Capacitor SMD 0402")
		(tags "capacitor SMD 0402")
		(property "Reference" "C241"
			(at -20.368136 -9.464883 0)
			(layer "B.SilkS")
			(effects
				(font
					(size 0.7 0.7)
					(thickness 0.15)
				)
				(justify mirror)
			)
		)
		(property "Value" "C_1u_25V_0402"
			(at -1.022927 -2.155213 0)
			(layer "B.Fab")
			(effects
				(font
					(size 0.7 0.7)
					(thickness 0.15)
				)
				(justify left bottom mirror)
			)
		)
		(property "Datasheet" "https://www.murata.com/products/productdetail?partno=GRM155R61E105KE11%23"
			(at 0 0 0)
			(layer "B.Fab")
			(hide yes)
			(effects
				(font
					(size 1.27 1.27)
					(thickness 0.15)
				)
				(justify mirror)
			)
		)
		(property "Description" "SMD Multilayer Ceramic Capacitor, 1 µF, 25 V, 0402 [1005 Metric], ± 10%, X5R, GRM Series"
			(at 0 0 0)
			(layer "B.Fab")
			(hide yes)
			(effects
				(font
					(size 1.27 1.27)
					(thickness 0.15)
				)
				(justify mirror)
			)
		)
		(property "MPN" "GRM155R61E105KE11J"
			(at 0 0 180)
			(unlocked yes)
			(layer "B.Fab")
			(hide yes)
			(effects
				(font
					(size 1 1)
					(thickness 0.15)
				)
				(justify mirror)
			)
		)
		(property "Manufacturer" "Murata"
			(at 0 0 180)
			(unlocked yes)
			(layer "B.Fab")
			(hide yes)
			(effects
				(font
					(size 1 1)
					(thickness 0.15)
				)
				(justify mirror)
			)
		)
		(property "License" "Apache-2.0"
			(at 0 0 180)
			(unlocked yes)
			(layer "B.Fab")
			(hide yes)
			(effects
				(font
					(size 1 1)
					(thickness 0.15)
				)
				(justify mirror)
			)
		)
		(property "Author" "Antmicro"
			(at 0 0 180)
			(unlocked yes)
			(layer "B.Fab")
			(hide yes)
			(effects
				(font
					(size 1 1)
					(thickness 0.15)
				)
				(justify mirror)
			)
		)
		(property "Val" "1u"
			(at 0 0 180)
			(unlocked yes)
			(layer "B.Fab")
			(hide yes)
			(effects
				(font
					(size 1 1)
					(thickness 0.15)
				)
				(justify mirror)
			)
		)
		(property "Voltage" "25V"
			(at 0 0 180)
			(unlocked yes)
			(layer "B.Fab")
			(hide yes)
			(effects
				(font
					(size 1 1)
					(thickness 0.15)
				)
				(justify mirror)
			)
		)
		(property "Dielectric" "X5R"
			(at 0 0 180)
			(unlocked yes)
			(layer "B.Fab")
			(hide yes)
			(effects
				(font
					(size 1 1)
					(thickness 0.15)
				)
				(justify mirror)
			)
		)
		(sheetname "/X710-AT2 power/")
		(sheetfile "x710-at2-power.kicad_sch")
		(attr smd)
		(fp_rect
			(start -0.925 0.47)
			(end 0.925 -0.47)
			(stroke
				(width 0.05)
				(type default)
			)
			(fill no)
			(layer "B.CrtYd")
		)
		(fp_line
			(start 0.504 0.25)
			(end 0.504 -0.248)
			(stroke
				(width 0.15)
				(type solid)
			)
			(layer "B.Fab")
		)
		(fp_line
			(start 0.504 -0.248)
			(end -0.494 -0.248)
			(stroke
				(width 0.15)
				(type solid)
			)
			(layer "B.Fab")
		)
		(fp_line
			(start -0.494 0.25)
			(end 0.504 0.25)
			(stroke
				(width 0.15)
				(type solid)
			)
			(layer "B.Fab")
		)
		(fp_line
			(start -0.494 -0.248)
			(end -0.494 0.25)
			(stroke
				(width 0.15)
				(type solid)
			)
			(layer "B.Fab")
		)
		(fp_text user "Author: Antmicro"
			(at -0.939 -3.399 0)
			(layer "B.Fab")
			(effects
				(font
					(size 0.7 0.7)
					(thickness 0.15)
				)
				(justify left bottom mirror)
			)
		)
		(fp_text user "${REFERENCE}"
			(at -0.939 -4.599 0)
			(layer "B.Fab")
			(effects
				(font
					(size 0.7 0.7)
					(thickness 0.15)
				)
				(justify left bottom mirror)
			)
		)
		(fp_text user "License: Apache-2.0"
			(at -0.939 -5.799 0)
			(layer "B.Fab")
			(effects
				(font
					(size 0.7 0.7)
					(thickness 0.15)
				)
				(justify left bottom mirror)
			)
		)
		(pad "1" smd roundrect
			(at -0.48 0 180)
			(size 0.59 0.64)
			(layers "B.Cu" "B.Mask" "B.Paste")
			(roundrect_rratio 0.25)
			(net 23 "GND")
			(pintype "passive")
		)
		(pad "2" smd roundrect
			(at 0.48 0 180)
			(size 0.59 0.64)
			(layers "B.Cu" "B.Mask" "B.Paste")
			(roundrect_rratio 0.25)
			(net 9 "VCCD")
			(pintype "passive")
		)
	)
	(footprint "antmicro-footprints:C_0402_1005Metric"
		(layer "B.Cu")
		(at 127.999999 125.425001 180)
		(descr "Capacitor SMD 0402")
		(tags "capacitor SMD 0402")
		(property "Reference" "C62"
			(at -21.900002 7.700002 0)
			(layer "B.SilkS")
			(effects
				(font
					(size 0.7 0.7)
					(thickness 0.15)
				)
				(justify mirror)
			)
		)
		(property "Value" "C_1u_0402"
			(at -1.022927 -2.155213 0)
			(layer "B.Fab")
			(effects
				(font
					(size 0.7 0.7)
					(thickness 0.15)
				)
				(justify left bottom mirror)
			)
		)
		(property "Datasheet" "https://product.tdk.com/en/search/capacitor/ceramic/mlcc/info?part_no=C1005X6S1A105K050BC"
			(at 0 0 0)
			(layer "B.Fab")
			(hide yes)
			(effects
				(font
					(size 1.27 1.27)
					(thickness 0.15)
				)
				(justify mirror)
			)
		)
		(property "Description" "SMD Multilayer Ceramic Capacitor, 1 µF, 10 V, 0402 [1005 Metric], ± 10%, X6S, C"
			(at 0 0 0)
			(layer "B.Fab")
			(hide yes)
			(effects
				(font
					(size 1.27 1.27)
					(thickness 0.15)
				)
				(justify mirror)
			)
		)
		(property "MPN" "C1005X6S1A105K050BC"
			(at 0 0 180)
			(unlocked yes)
			(layer "B.Fab")
			(hide yes)
			(effects
				(font
					(size 1 1)
					(thickness 0.15)
				)
				(justify mirror)
			)
		)
		(property "Manufacturer" "TDK"
			(at 0 0 180)
			(unlocked yes)
			(layer "B.Fab")
			(hide yes)
			(effects
				(font
					(size 1 1)
					(thickness 0.15)
				)
				(justify mirror)
			)
		)
		(property "License" "Apache-2.0"
			(at 0 0 180)
			(unlocked yes)
			(layer "B.Fab")
			(hide yes)
			(effects
				(font
					(size 1 1)
					(thickness 0.15)
				)
				(justify mirror)
			)
		)
		(property "Val" "1u"
			(at 0 0 180)
			(unlocked yes)
			(layer "B.Fab")
			(hide yes)
			(effects
				(font
					(size 1 1)
					(thickness 0.15)
				)
				(justify mirror)
			)
		)
		(property "Voltage" ""
			(at 0 0 180)
			(unlocked yes)
			(layer "B.Fab")
			(hide yes)
			(effects
				(font
					(size 1 1)
					(thickness 0.15)
				)
				(justify mirror)
			)
		)
		(property "Dielectric" ""
			(at 0 0 180)
			(unlocked yes)
			(layer "B.Fab")
			(hide yes)
			(effects
				(font
					(size 1 1)
					(thickness 0.15)
				)
				(justify mirror)
			)
		)
		(property "Author" "Antmicro"
			(at 0 0 180)
			(unlocked yes)
			(layer "B.Fab")
			(hide yes)
			(effects
				(font
					(size 1 1)
					(thickness 0.15)
				)
				(justify mirror)
			)
		)
		(sheetname "/TB Controller - Power/")
		(sheetfile "tb-power.kicad_sch")
		(attr smd)
		(fp_rect
			(start -0.925 0.47)
			(end 0.925 -0.47)
			(stroke
				(width 0.05)
				(type default)
			)
			(fill no)
			(layer "B.CrtYd")
		)
		(fp_line
			(start 0.504 0.25)
			(end 0.504 -0.248)
			(stroke
				(width 0.15)
				(type solid)
			)
			(layer "B.Fab")
		)
		(fp_line
			(start 0.504 -0.248)
			(end -0.494 -0.248)
			(stroke
				(width 0.15)
				(type solid)
			)
			(layer "B.Fab")
		)
		(fp_line
			(start -0.494 0.25)
			(end 0.504 0.25)
			(stroke
				(width 0.15)
				(type solid)
			)
			(layer "B.Fab")
		)
		(fp_line
			(start -0.494 -0.248)
			(end -0.494 0.25)
			(stroke
				(width 0.15)
				(type solid)
			)
			(layer "B.Fab")
		)
		(fp_text user "${REFERENCE}"
			(at -0.939 -4.599 0)
			(layer "B.Fab")
			(effects
				(font
					(size 0.7 0.7)
					(thickness 0.15)
				)
				(justify left bottom mirror)
			)
		)
		(fp_text user "License: Apache-2.0"
			(at -0.939 -5.799 0)
			(layer "B.Fab")
			(effects
				(font
					(size 0.7 0.7)
					(thickness 0.15)
				)
				(justify left bottom mirror)
			)
		)
		(fp_text user "Author: Antmicro"
			(at -0.939 -3.399 0)
			(layer "B.Fab")
			(effects
				(font
					(size 0.7 0.7)
					(thickness 0.15)
				)
				(justify left bottom mirror)
			)
		)
		(pad "1" smd roundrect
			(at -0.48 0 180)
			(size 0.59 0.64)
			(layers "B.Cu" "B.Mask" "B.Paste")
			(roundrect_rratio 0.25)
			(net 23 "GND")
			(pintype "passive")
		)
		(pad "2" smd roundrect
			(at 0.48 0 180)
			(size 0.59 0.64)
			(layers "B.Cu" "B.Mask" "B.Paste")
			(roundrect_rratio 0.25)
			(net 177 "Net-(U4A-VCC3P3_ANA_PCIE)")
			(pintype "passive")
		)
	)
	(footprint "antmicro-footprints:C_0402_1005Metric"
		(layer "B.Cu")
		(at 151.181867 81.260117 180)
		(descr "Capacitor SMD 0402")
		(tags "capacitor SMD 0402")
		(property "Reference" "C224"
			(at -20.368136 -9.464883 0)
			(layer "B.SilkS")
			(effects
				(font
					(size 0.7 0.7)
					(thickness 0.15)
				)
				(justify mirror)
			)
		)
		(property "Value" "C_1u_25V_0402"
			(at -1.022927 -2.155213 0)
			(layer "B.Fab")
			(effects
				(font
					(size 0.7 0.7)
					(thickness 0.15)
				)
				(justify left bottom mirror)
			)
		)
		(property "Datasheet" "https://www.murata.com/products/productdetail?partno=GRM155R61E105KE11%23"
			(at 0 0 0)
			(layer "B.Fab")
			(hide yes)
			(effects
				(font
					(size 1.27 1.27)
					(thickness 0.15)
				)
				(justify mirror)
			)
		)
		(property "Description" "SMD Multilayer Ceramic Capacitor, 1 µF, 25 V, 0402 [1005 Metric], ± 10%, X5R, GRM Series"
			(at 0 0 0)
			(layer "B.Fab")
			(hide yes)
			(effects
				(font
					(size 1.27 1.27)
					(thickness 0.15)
				)
				(justify mirror)
			)
		)
		(property "MPN" "GRM155R61E105KE11J"
			(at 0 0 180)
			(unlocked yes)
			(layer "B.Fab")
			(hide yes)
			(effects
				(font
					(size 1 1)
					(thickness 0.15)
				)
				(justify mirror)
			)
		)
		(property "Manufacturer" "Murata"
			(at 0 0 180)
			(unlocked yes)
			(layer "B.Fab")
			(hide yes)
			(effects
				(font
					(size 1 1)
					(thickness 0.15)
				)
				(justify mirror)
			)
		)
		(property "License" "Apache-2.0"
			(at 0 0 180)
			(unlocked yes)
			(layer "B.Fab")
			(hide yes)
			(effects
				(font
					(size 1 1)
					(thickness 0.15)
				)
				(justify mirror)
			)
		)
		(property "Author" "Antmicro"
			(at 0 0 180)
			(unlocked yes)
			(layer "B.Fab")
			(hide yes)
			(effects
				(font
					(size 1 1)
					(thickness 0.15)
				)
				(justify mirror)
			)
		)
		(property "Val" "1u"
			(at 0 0 180)
			(unlocked yes)
			(layer "B.Fab")
			(hide yes)
			(effects
				(font
					(size 1 1)
					(thickness 0.15)
				)
				(justify mirror)
			)
		)
		(property "Voltage" "25V"
			(at 0 0 180)
			(unlocked yes)
			(layer "B.Fab")
			(hide yes)
			(effects
				(font
					(size 1 1)
					(thickness 0.15)
				)
				(justify mirror)
			)
		)
		(property "Dielectric" "X5R"
			(at 0 0 180)
			(unlocked yes)
			(layer "B.Fab")
			(hide yes)
			(effects
				(font
					(size 1 1)
					(thickness 0.15)
				)
				(justify mirror)
			)
		)
		(sheetname "/X710-AT2 power/")
		(sheetfile "x710-at2-power.kicad_sch")
		(attr smd)
		(fp_rect
			(start -0.925 0.47)
			(end 0.925 -0.47)
			(stroke
				(width 0.05)
				(type default)
			)
			(fill no)
			(layer "B.CrtYd")
		)
		(fp_line
			(start 0.504 0.25)
			(end 0.504 -0.248)
			(stroke
				(width 0.15)
				(type solid)
			)
			(layer "B.Fab")
		)
		(fp_line
			(start 0.504 -0.248)
			(end -0.494 -0.248)
			(stroke
				(width 0.15)
				(type solid)
			)
			(layer "B.Fab")
		)
		(fp_line
			(start -0.494 0.25)
			(end 0.504 0.25)
			(stroke
				(width 0.15)
				(type solid)
			)
			(layer "B.Fab")
		)
		(fp_line
			(start -0.494 -0.248)
			(end -0.494 0.25)
			(stroke
				(width 0.15)
				(type solid)
			)
			(layer "B.Fab")
		)
		(fp_text user "Author: Antmicro"
			(at -0.939 -3.399 0)
			(layer "B.Fab")
			(effects
				(font
					(size 0.7 0.7)
					(thickness 0.15)
				)
				(justify left bottom mirror)
			)
		)
		(fp_text user "${REFERENCE}"
			(at -0.939 -4.599 0)
			(layer "B.Fab")
			(effects
				(font
					(size 0.7 0.7)
					(thickness 0.15)
				)
				(justify left bottom mirror)
			)
		)
		(fp_text user "License: Apache-2.0"
			(at -0.939 -5.799 0)
			(layer "B.Fab")
			(effects
				(font
					(size 0.7 0.7)
					(thickness 0.15)
				)
				(justify left bottom mirror)
			)
		)
		(pad "1" smd roundrect
			(at -0.48 0 180)
			(size 0.59 0.64)
			(layers "B.Cu" "B.Mask" "B.Paste")
			(roundrect_rratio 0.25)
			(net 23 "GND")
			(pintype "passive")
		)
		(pad "2" smd roundrect
			(at 0.48 0 180)
			(size 0.59 0.64)
			(layers "B.Cu" "B.Mask" "B.Paste")
			(roundrect_rratio 0.25)
			(net 9 "VCCD")
			(pintype "passive")
		)
	)
	(footprint "antmicro-footprints:R_0402_1005Metric"
		(layer "B.Cu")
		(at 158.131866 70.035118 -90)
		(descr "Resistor SMD 0402")
		(tags "resistor SMD 0402")
		(property "Reference" "R166"
			(at 9.464883 -19.468134 90)
			(layer "B.SilkS")
			(effects
				(font
					(size 0.7 0.7)
					(thickness 0.15)
				)
				(justify mirror)
			)
		)
		(property "Value" "R_22R_0402"
			(at -1.011843 -1.772047 90)
			(layer "B.Fab")
			(effects
				(font
					(size 0.7 0.7)
					(thickness 0.15)
				)
				(justify left bottom mirror)
			)
		)
		(property "Datasheet" "https://www.bourns.com/docs/product-datasheets/cr.pdf"
			(at 0 0 90)
			(layer "B.Fab")
			(hide yes)
			(effects
				(font
					(size 1.27 1.27)
					(thickness 0.15)
				)
				(justify mirror)
			)
		)
		(property "Description" "SMD Chip Resistor, 22 ohm, ± 1%, 62.5 mW, 0402 [1005 Metric], Thick Film, General Purpose"
			(at 0 0 90)
			(layer "B.Fab")
			(hide yes)
			(effects
				(font
					(size 1.27 1.27)
					(thickness 0.15)
				)
				(justify mirror)
			)
		)
		(property "MPN" "CR0402-FX-22R0GLF"
			(at 0 0 270)
			(unlocked yes)
			(layer "B.Fab")
			(hide yes)
			(effects
				(font
					(size 1 1)
					(thickness 0.15)
				)
				(justify mirror)
			)
		)
		(property "Manufacturer" "Bourns"
			(at 0 0 270)
			(unlocked yes)
			(layer "B.Fab")
			(hide yes)
			(effects
				(font
					(size 1 1)
					(thickness 0.15)
				)
				(justify mirror)
			)
		)
		(property "License" "Apache-2.0"
			(at 0 0 270)
			(unlocked yes)
			(layer "B.Fab")
			(hide yes)
			(effects
				(font
					(size 1 1)
					(thickness 0.15)
				)
				(justify mirror)
			)
		)
		(property "Author" "Antmicro"
			(at 0 0 270)
			(unlocked yes)
			(layer "B.Fab")
			(hide yes)
			(effects
				(font
					(size 1 1)
					(thickness 0.15)
				)
				(justify mirror)
			)
		)
		(property "Val" "22R"
			(at 0 0 270)
			(unlocked yes)
			(layer "B.Fab")
			(hide yes)
			(effects
				(font
					(size 1 1)
					(thickness 0.15)
				)
				(justify mirror)
			)
		)
		(property "Tolerance" "1%"
			(at 0 0 270)
			(unlocked yes)
			(layer "B.Fab")
			(hide yes)
			(effects
				(font
					(size 1 1)
					(thickness 0.15)
				)
				(justify mirror)
			)
		)
		(sheetname "/X710-AT2 Misc/")
		(sheetfile "x710-at2-mics.kicad_sch")
		(attr smd)
		(fp_rect
			(start -0.925 0.47)
			(end 0.925 -0.47)
			(stroke
				(width 0.05)
				(type default)
			)
			(fill no)
			(layer "B.CrtYd")
		)
		(fp_rect
			(start -0.5 0.25)
			(end 0.5 -0.25)
			(stroke
				(width 0.15)
				(type solid)
			)
			(fill no)
			(layer "B.Fab")
		)
		(fp_text user "License: Apache-2.0"
			(at -0.95 -5.169 90)
			(layer "B.Fab")
			(effects
				(font
					(size 0.7 0.7)
					(thickness 0.15)
				)
				(justify left bottom mirror)
			)
		)
		(fp_text user "Author: Antmicro"
			(at -0.95 -4.169 90)
			(layer "B.Fab")
			(effects
				(font
					(size 0.7 0.7)
					(thickness 0.15)
				)
				(justify left bottom mirror)
			)
		)
		(fp_text user "${REFERENCE}"
			(at -0.95 -3.168 90)
			(layer "B.Fab")
			(effects
				(font
					(size 0.7 0.7)
					(thickness 0.15)
				)
				(justify left bottom mirror)
			)
		)
		(pad "1" smd roundrect
			(at -0.48 0 270)
			(size 0.59 0.64)
			(layers "B.Cu" "B.Mask" "B.Paste")
			(roundrect_rratio 0.25)
			(net 141 "/X710-AT2 Misc/NCSI.ARB_OUT")
			(pintype "passive")
		)
		(pad "2" smd roundrect
			(at 0.48 0 270)
			(size 0.59 0.64)
			(layers "B.Cu" "B.Mask" "B.Paste")
			(roundrect_rratio 0.25)
			(net 440 "Net-(U14D-NCSI_ARB_OUT)")
			(pintype "passive")
		)
	)
	(footprint "antmicro-footprints:R_0402_1005Metric"
		(layer "B.Cu")
		(at 157.511866 90.455117 90)
		(descr "Resistor SMD 0402")
		(tags "resistor SMD 0402")
		(property "Reference" "R209"
			(at -10.794883 19.288134 270)
			(layer "B.SilkS")
			(effects
				(font
					(size 0.7 0.7)
					(thickness 0.15)
				)
				(justify mirror)
			)
		)
		(property "Value" "R_6k04_0.1%_0402"
			(at -1.011843 -1.772047 270)
			(layer "B.Fab")
			(effects
				(font
					(size 0.7 0.7)
					(thickness 0.15)
				)
				(justify left bottom mirror)
			)
		)
		(property "Datasheet" "https://www.vishay.com/docs/28758/tnpw_e3.pdf"
			(at 0 0 270)
			(layer "B.Fab")
			(hide yes)
			(effects
				(font
					(size 1.27 1.27)
					(thickness 0.15)
				)
				(justify mirror)
			)
		)
		(property "Description" "SMD Chip Resistor, 6.49 kohm, ± 1%, 62.5 mW, 0402 [1005 Metric], Thick Film, General Purpose"
			(at 0 0 270)
			(layer "B.Fab")
			(hide yes)
			(effects
				(font
					(size 1.27 1.27)
					(thickness 0.15)
				)
				(justify mirror)
			)
		)
		(property "MPN" "TNPW04026K04BEED"
			(at 0 0 90)
			(unlocked yes)
			(layer "B.Fab")
			(hide yes)
			(effects
				(font
					(size 1 1)
					(thickness 0.15)
				)
				(justify mirror)
			)
		)
		(property "Manufacturer" "Vishay"
			(at 0 0 90)
			(unlocked yes)
			(layer "B.Fab")
			(hide yes)
			(effects
				(font
					(size 1 1)
					(thickness 0.15)
				)
				(justify mirror)
			)
		)
		(property "License" "Apache-2.0"
			(at 0 0 90)
			(unlocked yes)
			(layer "B.Fab")
			(hide yes)
			(effects
				(font
					(size 1 1)
					(thickness 0.15)
				)
				(justify mirror)
			)
		)
		(property "Author" "Antmicro"
			(at 0 0 90)
			(unlocked yes)
			(layer "B.Fab")
			(hide yes)
			(effects
				(font
					(size 1 1)
					(thickness 0.15)
				)
				(justify mirror)
			)
		)
		(property "Val" "6k04"
			(at 0 0 90)
			(unlocked yes)
			(layer "B.Fab")
			(hide yes)
			(effects
				(font
					(size 1 1)
					(thickness 0.15)
				)
				(justify mirror)
			)
		)
		(property "Tolerance" "0.1%"
			(at 0 0 90)
			(unlocked yes)
			(layer "B.Fab")
			(hide yes)
			(effects
				(font
					(size 1 1)
					(thickness 0.15)
				)
				(justify mirror)
			)
		)
		(sheetname "/X710-AT2 10GbE/")
		(sheetfile "x710-at2-10gbe.kicad_sch")
		(attr smd)
		(fp_rect
			(start -0.925 0.47)
			(end 0.925 -0.47)
			(stroke
				(width 0.05)
				(type default)
			)
			(fill no)
			(layer "B.CrtYd")
		)
		(fp_rect
			(start -0.5 0.25)
			(end 0.5 -0.25)
			(stroke
				(width 0.15)
				(type solid)
			)
			(fill no)
			(layer "B.Fab")
		)
		(fp_text user "Author: Antmicro"
			(at -0.95 -4.169 270)
			(layer "B.Fab")
			(effects
				(font
					(size 0.7 0.7)
					(thickness 0.15)
				)
				(justify left bottom mirror)
			)
		)
		(fp_text user "${REFERENCE}"
			(at -0.95 -3.168 270)
			(layer "B.Fab")
			(effects
				(font
					(size 0.7 0.7)
					(thickness 0.15)
				)
				(justify left bottom mirror)
			)
		)
		(fp_text user "License: Apache-2.0"
			(at -0.95 -5.169 270)
			(layer "B.Fab")
			(effects
				(font
					(size 0.7 0.7)
					(thickness 0.15)
				)
				(justify left bottom mirror)
			)
		)
		(pad "1" smd roundrect
			(at -0.48 0 90)
			(size 0.59 0.64)
			(layers "B.Cu" "B.Mask" "B.Paste")
			(roundrect_rratio 0.25)
			(net 23 "GND")
			(pintype "passive")
		)
		(pad "2" smd roundrect
			(at 0.48 0 90)
			(size 0.59 0.64)
			(layers "B.Cu" "B.Mask" "B.Paste")
			(roundrect_rratio 0.25)
			(net 63 "/X710-AT2 10GbE/BIAS_RDAC")
			(pintype "passive")
		)
	)
	(footprint "antmicro-footprints:C_0402_1005Metric"
		(layer "B.Cu")
		(at 126.8 142.3 -90)
		(descr "Capacitor SMD 0402")
		(tags "capacitor SMD 0402")
		(property "Reference" "C31"
			(at -1.15 -2.45 90)
			(layer "B.SilkS")
			(effects
				(font
					(size 0.7 0.7)
					(thickness 0.15)
				)
				(justify left bottom mirror)
			)
		)
		(property "Value" "C_220p_0402"
			(at -1.022927 -2.155213 90)
			(layer "B.Fab")
			(effects
				(font
					(size 0.7 0.7)
					(thickness 0.15)
				)
				(justify left bottom mirror)
			)
		)
		(property "Datasheet" "https://spicat.kyocera-avx.com/product/mlcc/chartview/04025C221JAT2A/"
			(at 0 0 90)
			(layer "B.Fab")
			(hide yes)
			(effects
				(font
					(size 1.27 1.27)
					(thickness 0.15)
				)
				(justify mirror)
			)
		)
		(property "Description" "SMD Multilayer Ceramic Capacitor, 220 pF, 50 V, 0402 [1005 Metric], ± 10%, X7R, MC"
			(at 0 0 90)
			(layer "B.Fab")
			(hide yes)
			(effects
				(font
					(size 1.27 1.27)
					(thickness 0.15)
				)
				(justify mirror)
			)
		)
		(property "MPN" "04025C221JAT2A"
			(at 0 0 270)
			(unlocked yes)
			(layer "B.Fab")
			(hide yes)
			(effects
				(font
					(size 1 1)
					(thickness 0.15)
				)
				(justify mirror)
			)
		)
		(property "Manufacturer" "KYOCERA AVX"
			(at 0 0 270)
			(unlocked yes)
			(layer "B.Fab")
			(hide yes)
			(effects
				(font
					(size 1 1)
					(thickness 0.15)
				)
				(justify mirror)
			)
		)
		(property "License" "Apache-2.0"
			(at 0 0 270)
			(unlocked yes)
			(layer "B.Fab")
			(hide yes)
			(effects
				(font
					(size 1 1)
					(thickness 0.15)
				)
				(justify mirror)
			)
		)
		(property "Val" "220p"
			(at 0 0 270)
			(unlocked yes)
			(layer "B.Fab")
			(hide yes)
			(effects
				(font
					(size 1 1)
					(thickness 0.15)
				)
				(justify mirror)
			)
		)
		(property "Voltage" ""
			(at 0 0 270)
			(unlocked yes)
			(layer "B.Fab")
			(hide yes)
			(effects
				(font
					(size 1 1)
					(thickness 0.15)
				)
				(justify mirror)
			)
		)
		(property "Dielectric" ""
			(at 0 0 270)
			(unlocked yes)
			(layer "B.Fab")
			(hide yes)
			(effects
				(font
					(size 1 1)
					(thickness 0.15)
				)
				(justify mirror)
			)
		)
		(property "Author" "Antmicro"
			(at 0 0 270)
			(unlocked yes)
			(layer "B.Fab")
			(hide yes)
			(effects
				(font
					(size 1 1)
					(thickness 0.15)
				)
				(justify mirror)
			)
		)
		(sheetname "/PD and TB DC-DC/")
		(sheetfile "PD_and_TB_DC_DC.kicad_sch")
		(attr smd)
		(fp_rect
			(start -0.925 0.47)
			(end 0.925 -0.47)
			(stroke
				(width 0.05)
				(type default)
			)
			(fill no)
			(layer "B.CrtYd")
		)
		(fp_line
			(start -0.494 0.25)
			(end 0.504 0.25)
			(stroke
				(width 0.15)
				(type solid)
			)
			(layer "B.Fab")
		)
		(fp_line
			(start 0.504 0.25)
			(end 0.504 -0.248)
			(stroke
				(width 0.15)
				(type solid)
			)
			(layer "B.Fab")
		)
		(fp_line
			(start -0.494 -0.248)
			(end -0.494 0.25)
			(stroke
				(width 0.15)
				(type solid)
			)
			(layer "B.Fab")
		)
		(fp_line
			(start 0.504 -0.248)
			(end -0.494 -0.248)
			(stroke
				(width 0.15)
				(type solid)
			)
			(layer "B.Fab")
		)
		(fp_text user "${REFERENCE}"
			(at -0.939 -4.599 90)
			(layer "B.Fab")
			(effects
				(font
					(size 0.7 0.7)
					(thickness 0.15)
				)
				(justify left bottom mirror)
			)
		)
		(fp_text user "Author: Antmicro"
			(at -0.939 -3.399 90)
			(layer "B.Fab")
			(effects
				(font
					(size 0.7 0.7)
					(thickness 0.15)
				)
				(justify left bottom mirror)
			)
		)
		(fp_text user "License: Apache-2.0"
			(at -0.939 -5.799 90)
			(layer "B.Fab")
			(effects
				(font
					(size 0.7 0.7)
					(thickness 0.15)
				)
				(justify left bottom mirror)
			)
		)
		(pad "1" smd roundrect
			(at -0.48 0 270)
			(size 0.59 0.64)
			(layers "B.Cu" "B.Mask" "B.Paste")
			(roundrect_rratio 0.25)
			(net 23 "GND")
			(pintype "passive")
		)
		(pad "2" smd roundrect
			(at 0.48 0 270)
			(size 0.59 0.64)
			(layers "B.Cu" "B.Mask" "B.Paste")
			(roundrect_rratio 0.25)
			(net 306 "/PD and TB DC-DC/USB3.CC1")
			(pintype "passive")
		)
	)
	(footprint "antmicro-footprints:C_0402_1005Metric"
		(layer "B.Cu")
		(at 125.574999 123.95 -90)
		(descr "Capacitor SMD 0402")
		(tags "capacitor SMD 0402")
		(property "Reference" "C60"
			(at -7.700002 -21.900002 90)
			(layer "B.SilkS")
			(effects
				(font
					(size 0.7 0.7)
					(thickness 0.15)
				)
				(justify mirror)
			)
		)
		(property "Value" "C_1u_0402"
			(at -1.022927 -2.155213 90)
			(layer "B.Fab")
			(effects
				(font
					(size 0.7 0.7)
					(thickness 0.15)
				)
				(justify left bottom mirror)
			)
		)
		(property "Datasheet" "https://product.tdk.com/en/search/capacitor/ceramic/mlcc/info?part_no=C1005X6S1A105K050BC"
			(at 0 0 90)
			(layer "B.Fab")
			(hide yes)
			(effects
				(font
					(size 1.27 1.27)
					(thickness 0.15)
				)
				(justify mirror)
			)
		)
		(property "Description" "SMD Multilayer Ceramic Capacitor, 1 µF, 10 V, 0402 [1005 Metric], ± 10%, X6S, C"
			(at 0 0 90)
			(layer "B.Fab")
			(hide yes)
			(effects
				(font
					(size 1.27 1.27)
					(thickness 0.15)
				)
				(justify mirror)
			)
		)
		(property "MPN" "C1005X6S1A105K050BC"
			(at 0 0 270)
			(unlocked yes)
			(layer "B.Fab")
			(hide yes)
			(effects
				(font
					(size 1 1)
					(thickness 0.15)
				)
				(justify mirror)
			)
		)
		(property "Manufacturer" "TDK"
			(at 0 0 270)
			(unlocked yes)
			(layer "B.Fab")
			(hide yes)
			(effects
				(font
					(size 1 1)
					(thickness 0.15)
				)
				(justify mirror)
			)
		)
		(property "License" "Apache-2.0"
			(at 0 0 270)
			(unlocked yes)
			(layer "B.Fab")
			(hide yes)
			(effects
				(font
					(size 1 1)
					(thickness 0.15)
				)
				(justify mirror)
			)
		)
		(property "Val" "1u"
			(at 0 0 270)
			(unlocked yes)
			(layer "B.Fab")
			(hide yes)
			(effects
				(font
					(size 1 1)
					(thickness 0.15)
				)
				(justify mirror)
			)
		)
		(property "Voltage" ""
			(at 0 0 270)
			(unlocked yes)
			(layer "B.Fab")
			(hide yes)
			(effects
				(font
					(size 1 1)
					(thickness 0.15)
				)
				(justify mirror)
			)
		)
		(property "Dielectric" ""
			(at 0 0 270)
			(unlocked yes)
			(layer "B.Fab")
			(hide yes)
			(effects
				(font
					(size 1 1)
					(thickness 0.15)
				)
				(justify mirror)
			)
		)
		(property "Author" "Antmicro"
			(at 0 0 270)
			(unlocked yes)
			(layer "B.Fab")
			(hide yes)
			(effects
				(font
					(size 1 1)
					(thickness 0.15)
				)
				(justify mirror)
			)
		)
		(sheetname "/TB Controller - Power/")
		(sheetfile "tb-power.kicad_sch")
		(attr smd)
		(fp_rect
			(start -0.925 0.47)
			(end 0.925 -0.47)
			(stroke
				(width 0.05)
				(type default)
			)
			(fill no)
			(layer "B.CrtYd")
		)
		(fp_line
			(start -0.494 0.25)
			(end 0.504 0.25)
			(stroke
				(width 0.15)
				(type solid)
			)
			(layer "B.Fab")
		)
		(fp_line
			(start 0.504 0.25)
			(end 0.504 -0.248)
			(stroke
				(width 0.15)
				(type solid)
			)
			(layer "B.Fab")
		)
		(fp_line
			(start -0.494 -0.248)
			(end -0.494 0.25)
			(stroke
				(width 0.15)
				(type solid)
			)
			(layer "B.Fab")
		)
		(fp_line
			(start 0.504 -0.248)
			(end -0.494 -0.248)
			(stroke
				(width 0.15)
				(type solid)
			)
			(layer "B.Fab")
		)
		(fp_text user "${REFERENCE}"
			(at -0.939 -4.599 90)
			(layer "B.Fab")
			(effects
				(font
					(size 0.7 0.7)
					(thickness 0.15)
				)
				(justify left bottom mirror)
			)
		)
		(fp_text user "Author: Antmicro"
			(at -0.939 -3.399 90)
			(layer "B.Fab")
			(effects
				(font
					(size 0.7 0.7)
					(thickness 0.15)
				)
				(justify left bottom mirror)
			)
		)
		(fp_text user "License: Apache-2.0"
			(at -0.939 -5.799 90)
			(layer "B.Fab")
			(effects
				(font
					(size 0.7 0.7)
					(thickness 0.15)
				)
				(justify left bottom mirror)
			)
		)
		(pad "1" smd roundrect
			(at -0.48 0 270)
			(size 0.59 0.64)
			(layers "B.Cu" "B.Mask" "B.Paste")
			(roundrect_rratio 0.25)
			(net 23 "GND")
			(pintype "passive")
		)
		(pad "2" smd roundrect
			(at 0.48 0 270)
			(size 0.59 0.64)
			(layers "B.Cu" "B.Mask" "B.Paste")
			(roundrect_rratio 0.25)
			(net 403 "Net-(C55-Pad2)")
			(pintype "passive")
		)
	)
	(footprint "antmicro-footprints:R_0402_1005Metric"
		(layer "B.Cu")
		(at 149.331866 75.285117)
		(descr "Resistor SMD 0402")
		(tags "resistor SMD 0402")
		(property "Reference" "R130"
			(at 19.468135 9.464883 180)
			(layer "B.SilkS")
			(effects
				(font
					(size 0.7 0.7)
					(thickness 0.15)
				)
				(justify mirror)
			)
		)
		(property "Value" "R_100R_0402"
			(at -1.011843 -1.772047 180)
			(layer "B.Fab")
			(effects
				(font
					(size 0.7 0.7)
					(thickness 0.15)
				)
				(justify left bottom mirror)
			)
		)
		(property "Datasheet" "https://www.bourns.com/docs/product-datasheets/cr.pdf"
			(at 0 0 180)
			(layer "B.Fab")
			(hide yes)
			(effects
				(font
					(size 1.27 1.27)
					(thickness 0.15)
				)
				(justify mirror)
			)
		)
		(property "Description" "SMD Chip Resistor, 100 ohm, ± 1%, 62.5 mW, 0402 [1005 Metric], Thick Film, General Purpose"
			(at 0 0 180)
			(layer "B.Fab")
			(hide yes)
			(effects
				(font
					(size 1.27 1.27)
					(thickness 0.15)
				)
				(justify mirror)
			)
		)
		(property "MPN" "CR0402-FX-1000GLF"
			(at 0 0 0)
			(unlocked yes)
			(layer "B.Fab")
			(hide yes)
			(effects
				(font
					(size 1 1)
					(thickness 0.15)
				)
				(justify mirror)
			)
		)
		(property "Manufacturer" "Bourns"
			(at 0 0 0)
			(unlocked yes)
			(layer "B.Fab")
			(hide yes)
			(effects
				(font
					(size 1 1)
					(thickness 0.15)
				)
				(justify mirror)
			)
		)
		(property "License" "Apache-2.0"
			(at 0 0 0)
			(unlocked yes)
			(layer "B.Fab")
			(hide yes)
			(effects
				(font
					(size 1 1)
					(thickness 0.15)
				)
				(justify mirror)
			)
		)
		(property "Author" "Antmicro"
			(at 0 0 0)
			(unlocked yes)
			(layer "B.Fab")
			(hide yes)
			(effects
				(font
					(size 1 1)
					(thickness 0.15)
				)
				(justify mirror)
			)
		)
		(property "Val" "100R"
			(at 0 0 0)
			(unlocked yes)
			(layer "B.Fab")
			(hide yes)
			(effects
				(font
					(size 1 1)
					(thickness 0.15)
				)
				(justify mirror)
			)
		)
		(property "Tolerance" "1%"
			(at 0 0 0)
			(unlocked yes)
			(layer "B.Fab")
			(hide yes)
			(effects
				(font
					(size 1 1)
					(thickness 0.15)
				)
				(justify mirror)
			)
		)
		(sheetname "/X710-AT2 RSVD/")
		(sheetfile "x710-at2-rsvd.kicad_sch")
		(attr smd)
		(fp_rect
			(start -0.925 0.47)
			(end 0.925 -0.47)
			(stroke
				(width 0.05)
				(type default)
			)
			(fill no)
			(layer "B.CrtYd")
		)
		(fp_rect
			(start -0.5 0.25)
			(end 0.5 -0.25)
			(stroke
				(width 0.15)
				(type solid)
			)
			(fill no)
			(layer "B.Fab")
		)
		(fp_text user "License: Apache-2.0"
			(at -0.95 -5.169 180)
			(layer "B.Fab")
			(effects
				(font
					(size 0.7 0.7)
					(thickness 0.15)
				)
				(justify left bottom mirror)
			)
		)
		(fp_text user "${REFERENCE}"
			(at -0.95 -3.168 180)
			(layer "B.Fab")
			(effects
				(font
					(size 0.7 0.7)
					(thickness 0.15)
				)
				(justify left bottom mirror)
			)
		)
		(fp_text user "Author: Antmicro"
			(at -0.95 -4.169 180)
			(layer "B.Fab")
			(effects
				(font
					(size 0.7 0.7)
					(thickness 0.15)
				)
				(justify left bottom mirror)
			)
		)
		(pad "1" smd roundrect
			(at -0.48 0)
			(size 0.59 0.64)
			(layers "B.Cu" "B.Mask" "B.Paste")
			(roundrect_rratio 0.25)
			(net 23 "GND")
			(pintype "passive")
		)
		(pad "2" smd roundrect
			(at 0.48 0)
			(size 0.59 0.64)
			(layers "B.Cu" "B.Mask" "B.Paste")
			(roundrect_rratio 0.25)
			(net 99 "/X710-AT2 RSVD/RSVDP8_VSS")
			(pintype "passive")
		)
	)
	(footprint "antmicro-footprints:R_0402_1005Metric"
		(layer "B.Cu")
		(at 138.450001 116.125001)
		(descr "Resistor SMD 0402")
		(tags "resistor SMD 0402")
		(property "Reference" "R46"
			(at 19.525001 -7.450001 180)
			(layer "B.SilkS")
			(effects
				(font
					(size 0.7 0.7)
					(thickness 0.15)
				)
				(justify mirror)
			)
		)
		(property "Value" "R_10k_0402"
			(at -1.011843 -1.772047 180)
			(layer "B.Fab")
			(effects
				(font
					(size 0.7 0.7)
					(thickness 0.15)
				)
				(justify left bottom mirror)
			)
		)
		(property "Datasheet" "https://www.bourns.com/docs/product-datasheets/cr.pdf"
			(at 0 0 180)
			(layer "B.Fab")
			(hide yes)
			(effects
				(font
					(size 1.27 1.27)
					(thickness 0.15)
				)
				(justify mirror)
			)
		)
		(property "Description" "SMD Chip Resistor, 10 kohm, ± 1%, 62.5 mW, 0402 [1005 Metric], Thick Film, General Purpose"
			(at 0 0 180)
			(layer "B.Fab")
			(hide yes)
			(effects
				(font
					(size 1.27 1.27)
					(thickness 0.15)
				)
				(justify mirror)
			)
		)
		(property "MPN" "CR0402-FX-1002GLF"
			(at 0 0 0)
			(unlocked yes)
			(layer "B.Fab")
			(hide yes)
			(effects
				(font
					(size 1 1)
					(thickness 0.15)
				)
				(justify mirror)
			)
		)
		(property "Manufacturer" "Bourns"
			(at 0 0 0)
			(unlocked yes)
			(layer "B.Fab")
			(hide yes)
			(effects
				(font
					(size 1 1)
					(thickness 0.15)
				)
				(justify mirror)
			)
		)
		(property "License" "Apache-2.0"
			(at 0 0 0)
			(unlocked yes)
			(layer "B.Fab")
			(hide yes)
			(effects
				(font
					(size 1 1)
					(thickness 0.15)
				)
				(justify mirror)
			)
		)
		(property "Val" "10k"
			(at 0 0 0)
			(unlocked yes)
			(layer "B.Fab")
			(hide yes)
			(effects
				(font
					(size 1 1)
					(thickness 0.15)
				)
				(justify mirror)
			)
		)
		(property "Tolerance" "1%"
			(at 0 0 0)
			(unlocked yes)
			(layer "B.Fab")
			(hide yes)
			(effects
				(font
					(size 1 1)
					(thickness 0.15)
				)
				(justify mirror)
			)
		)
		(property "Author" "Antmicro"
			(at 0 0 0)
			(unlocked yes)
			(layer "B.Fab")
			(hide yes)
			(effects
				(font
					(size 1 1)
					(thickness 0.15)
				)
				(justify mirror)
			)
		)
		(sheetname "/TB Controller/")
		(sheetfile "tb.kicad_sch")
		(attr smd)
		(fp_rect
			(start -0.925 0.47)
			(end 0.925 -0.47)
			(stroke
				(width 0.05)
				(type default)
			)
			(fill no)
			(layer "B.CrtYd")
		)
		(fp_rect
			(start -0.5 0.25)
			(end 0.5 -0.25)
			(stroke
				(width 0.15)
				(type solid)
			)
			(fill no)
			(layer "B.Fab")
		)
		(fp_text user "${REFERENCE}"
			(at -0.95 -3.168 180)
			(layer "B.Fab")
			(effects
				(font
					(size 0.7 0.7)
					(thickness 0.15)
				)
				(justify left bottom mirror)
			)
		)
		(fp_text user "Author: Antmicro"
			(at -0.95 -4.169 180)
			(layer "B.Fab")
			(effects
				(font
					(size 0.7 0.7)
					(thickness 0.15)
				)
				(justify left bottom mirror)
			)
		)
		(fp_text user "License: Apache-2.0"
			(at -0.95 -5.169 180)
			(layer "B.Fab")
			(effects
				(font
					(size 0.7 0.7)
					(thickness 0.15)
				)
				(justify left bottom mirror)
			)
		)
		(pad "1" smd roundrect
			(at -0.48 0)
			(size 0.59 0.64)
			(layers "B.Cu" "B.Mask" "B.Paste")
			(roundrect_rratio 0.25)
			(net 189 "Net-(U4C-GPIO_6)")
			(pintype "passive")
		)
		(pad "2" smd roundrect
			(at 0.48 0)
			(size 0.59 0.64)
			(layers "B.Cu" "B.Mask" "B.Paste")
			(roundrect_rratio 0.25)
			(net 23 "GND")
			(pintype "passive")
		)
	)
	(footprint "antmicro-footprints:C_0402_1005Metric"
		(layer "B.Cu")
		(at 128.499999 126.875 90)
		(descr "Capacitor SMD 0402")
		(tags "capacitor SMD 0402")
		(property "Reference" "C81"
			(at 7.700002 21.900002 270)
			(layer "B.SilkS")
			(effects
				(font
					(size 0.7 0.7)
					(thickness 0.15)
				)
				(justify mirror)
			)
		)
		(property "Value" "C_1u_0402"
			(at -1.022927 -2.155213 270)
			(layer "B.Fab")
			(effects
				(font
					(size 0.7 0.7)
					(thickness 0.15)
				)
				(justify left bottom mirror)
			)
		)
		(property "Datasheet" "https://product.tdk.com/en/search/capacitor/ceramic/mlcc/info?part_no=C1005X6S1A105K050BC"
			(at 0 0 270)
			(layer "B.Fab")
			(hide yes)
			(effects
				(font
					(size 1.27 1.27)
					(thickness 0.15)
				)
				(justify mirror)
			)
		)
		(property "Description" "SMD Multilayer Ceramic Capacitor, 1 µF, 10 V, 0402 [1005 Metric], ± 10%, X6S, C"
			(at 0 0 270)
			(layer "B.Fab")
			(hide yes)
			(effects
				(font
					(size 1.27 1.27)
					(thickness 0.15)
				)
				(justify mirror)
			)
		)
		(property "MPN" "C1005X6S1A105K050BC"
			(at 0 0 90)
			(unlocked yes)
			(layer "B.Fab")
			(hide yes)
			(effects
				(font
					(size 1 1)
					(thickness 0.15)
				)
				(justify mirror)
			)
		)
		(property "Manufacturer" "TDK"
			(at 0 0 90)
			(unlocked yes)
			(layer "B.Fab")
			(hide yes)
			(effects
				(font
					(size 1 1)
					(thickness 0.15)
				)
				(justify mirror)
			)
		)
		(property "License" "Apache-2.0"
			(at 0 0 90)
			(unlocked yes)
			(layer "B.Fab")
			(hide yes)
			(effects
				(font
					(size 1 1)
					(thickness 0.15)
				)
				(justify mirror)
			)
		)
		(property "Val" "1u"
			(at 0 0 90)
			(unlocked yes)
			(layer "B.Fab")
			(hide yes)
			(effects
				(font
					(size 1 1)
					(thickness 0.15)
				)
				(justify mirror)
			)
		)
		(property "Voltage" ""
			(at 0 0 90)
			(unlocked yes)
			(layer "B.Fab")
			(hide yes)
			(effects
				(font
					(size 1 1)
					(thickness 0.15)
				)
				(justify mirror)
			)
		)
		(property "Dielectric" ""
			(at 0 0 90)
			(unlocked yes)
			(layer "B.Fab")
			(hide yes)
			(effects
				(font
					(size 1 1)
					(thickness 0.15)
				)
				(justify mirror)
			)
		)
		(property "Author" "Antmicro"
			(at 0 0 90)
			(unlocked yes)
			(layer "B.Fab")
			(hide yes)
			(effects
				(font
					(size 1 1)
					(thickness 0.15)
				)
				(justify mirror)
			)
		)
		(sheetname "/TB Controller - Power/")
		(sheetfile "tb-power.kicad_sch")
		(attr smd)
		(fp_rect
			(start -0.925 0.47)
			(end 0.925 -0.47)
			(stroke
				(width 0.05)
				(type default)
			)
			(fill no)
			(layer "B.CrtYd")
		)
		(fp_line
			(start 0.504 -0.248)
			(end -0.494 -0.248)
			(stroke
				(width 0.15)
				(type solid)
			)
			(layer "B.Fab")
		)
		(fp_line
			(start -0.494 -0.248)
			(end -0.494 0.25)
			(stroke
				(width 0.15)
				(type solid)
			)
			(layer "B.Fab")
		)
		(fp_line
			(start 0.504 0.25)
			(end 0.504 -0.248)
			(stroke
				(width 0.15)
				(type solid)
			)
			(layer "B.Fab")
		)
		(fp_line
			(start -0.494 0.25)
			(end 0.504 0.25)
			(stroke
				(width 0.15)
				(type solid)
			)
			(layer "B.Fab")
		)
		(fp_text user "${REFERENCE}"
			(at -0.939 -4.599 270)
			(layer "B.Fab")
			(effects
				(font
					(size 0.7 0.7)
					(thickness 0.15)
				)
				(justify left bottom mirror)
			)
		)
		(fp_text user "Author: Antmicro"
			(at -0.939 -3.399 270)
			(layer "B.Fab")
			(effects
				(font
					(size 0.7 0.7)
					(thickness 0.15)
				)
				(justify left bottom mirror)
			)
		)
		(fp_text user "License: Apache-2.0"
			(at -0.939 -5.799 270)
			(layer "B.Fab")
			(effects
				(font
					(size 0.7 0.7)
					(thickness 0.15)
				)
				(justify left bottom mirror)
			)
		)
		(pad "1" smd roundrect
			(at -0.48 0 90)
			(size 0.59 0.64)
			(layers "B.Cu" "B.Mask" "B.Paste")
			(roundrect_rratio 0.25)
			(net 23 "GND")
			(pintype "passive")
		)
		(pad "2" smd roundrect
			(at 0.48 0 90)
			(size 0.59 0.64)
			(layers "B.Cu" "B.Mask" "B.Paste")
			(roundrect_rratio 0.25)
			(net 180 "Net-(U4A-VCC0P9_LVR_SENSE)")
			(pintype "passive")
		)
	)
	(footprint "antmicro-footprints:L_0402_1005Metric"
		(layer "B.Cu")
		(at 167 137.5)
		(descr "Inductor SMD 0402")
		(tags "Inductor SMD 0402")
		(property "Reference" "L13"
			(at 3 0.5 180)
			(layer "B.SilkS")
			(effects
				(font
					(size 0.7 0.7)
					(thickness 0.15)
				)
				(justify left bottom mirror)
			)
		)
		(property "Value" "L_2n4_0.85A_0402"
			(at 0 -1.4 180)
			(layer "B.Fab")
			(effects
				(font
					(size 0.7 0.7)
					(thickness 0.15)
				)
				(justify left bottom mirror)
			)
		)
		(property "Datasheet" "https://www.murata.com/products/productdetail?partno=LQW15AN2N4B00%23"
			(at 0 0 180)
			(layer "B.Fab")
			(hide yes)
			(effects
				(font
					(size 1.27 1.27)
					(thickness 0.15)
				)
				(justify mirror)
			)
		)
		(property "Description" "Wirewound Inductor, 2.4 nH, 0.05 ohm, 15 GHz, 850 mA, 0402 [1005 Metric], LQW15AN"
			(at 0 0 180)
			(layer "B.Fab")
			(hide yes)
			(effects
				(font
					(size 1.27 1.27)
					(thickness 0.15)
				)
				(justify mirror)
			)
		)
		(property "Val" "2n4/0.85A"
			(at 0 0 0)
			(unlocked yes)
			(layer "B.Fab")
			(hide yes)
			(effects
				(font
					(size 1 1)
					(thickness 0.15)
				)
				(justify mirror)
			)
		)
		(property "Manufacturer" "Murata"
			(at 0 0 0)
			(unlocked yes)
			(layer "B.Fab")
			(hide yes)
			(effects
				(font
					(size 1 1)
					(thickness 0.15)
				)
				(justify mirror)
			)
		)
		(property "MPN" "LQW15AN2N4B00D"
			(at 0 0 0)
			(unlocked yes)
			(layer "B.Fab")
			(hide yes)
			(effects
				(font
					(size 1 1)
					(thickness 0.15)
				)
				(justify mirror)
			)
		)
		(property "ISat" "0.85 A"
			(at 0 0 0)
			(unlocked yes)
			(layer "B.Fab")
			(hide yes)
			(effects
				(font
					(size 1 1)
					(thickness 0.15)
				)
				(justify mirror)
			)
		)
		(property "IMax" "0.85 A"
			(at 0 0 0)
			(unlocked yes)
			(layer "B.Fab")
			(hide yes)
			(effects
				(font
					(size 1 1)
					(thickness 0.15)
				)
				(justify mirror)
			)
		)
		(property "Size" "1.0x0.5"
			(at 0 0 0)
			(unlocked yes)
			(layer "B.Fab")
			(hide yes)
			(effects
				(font
					(size 1 1)
					(thickness 0.15)
				)
				(justify mirror)
			)
		)
		(property "Author" "Antmicro"
			(at 0 0 0)
			(unlocked yes)
			(layer "B.Fab")
			(hide yes)
			(effects
				(font
					(size 1 1)
					(thickness 0.15)
				)
				(justify mirror)
			)
		)
		(property "License" "Apache-2.0"
			(at 0 0 0)
			(unlocked yes)
			(layer "B.Fab")
			(hide yes)
			(effects
				(font
					(size 1 1)
					(thickness 0.15)
				)
				(justify mirror)
			)
		)
		(sheetname "/2xRJ45/")
		(sheetfile "2xrj45.kicad_sch")
		(attr smd)
		(fp_rect
			(start -0.925 0.47)
			(end 0.925 -0.47)
			(stroke
				(width 0.05)
				(type default)
			)
			(fill no)
			(layer "B.CrtYd")
		)
		(fp_rect
			(start -0.499 0.249)
			(end 0.499 -0.249)
			(stroke
				(width 0.15)
				(type solid)
			)
			(fill no)
			(layer "B.Fab")
		)
		(fp_text user "${REFERENCE}"
			(at -0.932 -3.168 180)
			(layer "B.Fab")
			(effects
				(font
					(size 0.7 0.7)
					(thickness 0.15)
				)
				(justify left bottom mirror)
			)
		)
		(fp_text user "License: Apache-2.0"
			(at -0.932 -5.17 180)
			(layer "B.Fab")
			(effects
				(font
					(size 0.7 0.7)
					(thickness 0.15)
				)
				(justify left bottom mirror)
			)
		)
		(fp_text user "Author: Antmicro"
			(at -0.932 -4.17 180)
			(layer "B.Fab")
			(effects
				(font
					(size 0.7 0.7)
					(thickness 0.15)
				)
				(justify left bottom mirror)
			)
		)
		(pad "1" smd roundrect
			(at -0.48 0)
			(size 0.59 0.64)
			(layers "B.Cu" "B.Mask" "B.Paste")
			(roundrect_rratio 0.25)
			(net 135 "+1V88_CT")
			(pintype "passive")
		)
		(pad "2" smd roundrect
			(at 0.48 0)
			(size 0.59 0.64)
			(layers "B.Cu" "B.Mask" "B.Paste")
			(roundrect_rratio 0.25)
			(net 134 "/2xRJ45/P1_CT")
			(pintype "passive")
		)
	)
	(footprint "antmicro-footprints:C_0402_1005Metric"
		(layer "B.Cu")
		(at 124.3 150.6 180)
		(descr "Capacitor SMD 0402")
		(tags "capacitor SMD 0402")
		(property "Reference" "C2"
			(at -0.7 -1.65 0)
			(layer "B.SilkS")
			(effects
				(font
					(size 0.7 0.7)
					(thickness 0.15)
				)
				(justify left bottom mirror)
			)
		)
		(property "Value" "C_100n_0402"
			(at -1.022927 -2.155213 0)
			(layer "B.Fab")
			(effects
				(font
					(size 0.7 0.7)
					(thickness 0.15)
				)
				(justify left bottom mirror)
			)
		)
		(property "Datasheet" "https://www.murata.com/products/productdetail?partno=GRM155R61H104KE14%23"
			(at 0 0 0)
			(layer "B.Fab")
			(hide yes)
			(effects
				(font
					(size 1.27 1.27)
					(thickness 0.15)
				)
				(justify mirror)
			)
		)
		(property "Description" "SMD Multilayer Ceramic Capacitor, 0.1 µF, 50 V, 0402 [1005 Metric], ± 10%, X5R, GRM Series"
			(at 0 0 0)
			(layer "B.Fab")
			(hide yes)
			(effects
				(font
					(size 1.27 1.27)
					(thickness 0.15)
				)
				(justify mirror)
			)
		)
		(property "MPN" "GRM155R61H104KE14D"
			(at 0 0 180)
			(unlocked yes)
			(layer "B.Fab")
			(hide yes)
			(effects
				(font
					(size 1 1)
					(thickness 0.15)
				)
				(justify mirror)
			)
		)
		(property "Manufacturer" "Murata"
			(at 0 0 180)
			(unlocked yes)
			(layer "B.Fab")
			(hide yes)
			(effects
				(font
					(size 1 1)
					(thickness 0.15)
				)
				(justify mirror)
			)
		)
		(property "License" "Apache-2.0"
			(at 0 0 180)
			(unlocked yes)
			(layer "B.Fab")
			(hide yes)
			(effects
				(font
					(size 1 1)
					(thickness 0.15)
				)
				(justify mirror)
			)
		)
		(property "Val" "100n"
			(at 0 0 180)
			(unlocked yes)
			(layer "B.Fab")
			(hide yes)
			(effects
				(font
					(size 1 1)
					(thickness 0.15)
				)
				(justify mirror)
			)
		)
		(property "Voltage" "50V"
			(at 0 0 180)
			(unlocked yes)
			(layer "B.Fab")
			(hide yes)
			(effects
				(font
					(size 1 1)
					(thickness 0.15)
				)
				(justify mirror)
			)
		)
		(property "Dielectric" "X5R"
			(at 0 0 180)
			(unlocked yes)
			(layer "B.Fab")
			(hide yes)
			(effects
				(font
					(size 1 1)
					(thickness 0.15)
				)
				(justify mirror)
			)
		)
		(property "Author" "Antmicro"
			(at 0 0 180)
			(unlocked yes)
			(layer "B.Fab")
			(hide yes)
			(effects
				(font
					(size 1 1)
					(thickness 0.15)
				)
				(justify mirror)
			)
		)
		(sheetname "/USB-C connector/")
		(sheetfile "USB-C_connector.kicad_sch")
		(attr smd)
		(fp_rect
			(start -0.925 0.47)
			(end 0.925 -0.47)
			(stroke
				(width 0.05)
				(type default)
			)
			(fill no)
			(layer "B.CrtYd")
		)
		(fp_line
			(start 0.504 0.25)
			(end 0.504 -0.248)
			(stroke
				(width 0.15)
				(type solid)
			)
			(layer "B.Fab")
		)
		(fp_line
			(start 0.504 -0.248)
			(end -0.494 -0.248)
			(stroke
				(width 0.15)
				(type solid)
			)
			(layer "B.Fab")
		)
		(fp_line
			(start -0.494 0.25)
			(end 0.504 0.25)
			(stroke
				(width 0.15)
				(type solid)
			)
			(layer "B.Fab")
		)
		(fp_line
			(start -0.494 -0.248)
			(end -0.494 0.25)
			(stroke
				(width 0.15)
				(type solid)
			)
			(layer "B.Fab")
		)
		(fp_text user "License: Apache-2.0"
			(at -0.939 -5.799 0)
			(layer "B.Fab")
			(effects
				(font
					(size 0.7 0.7)
					(thickness 0.15)
				)
				(justify left bottom mirror)
			)
		)
		(fp_text user "${REFERENCE}"
			(at -0.939 -4.599 0)
			(layer "B.Fab")
			(effects
				(font
					(size 0.7 0.7)
					(thickness 0.15)
				)
				(justify left bottom mirror)
			)
		)
		(fp_text user "Author: Antmicro"
			(at -0.939 -3.399 0)
			(layer "B.Fab")
			(effects
				(font
					(size 0.7 0.7)
					(thickness 0.15)
				)
				(justify left bottom mirror)
			)
		)
		(pad "1" smd roundrect
			(at -0.48 0 180)
			(size 0.59 0.64)
			(layers "B.Cu" "B.Mask" "B.Paste")
			(roundrect_rratio 0.25)
			(net 23 "GND")
			(pintype "passive")
		)
		(pad "2" smd roundrect
			(at 0.48 0 180)
			(size 0.59 0.64)
			(layers "B.Cu" "B.Mask" "B.Paste")
			(roundrect_rratio 0.25)
			(net 215 "/USB-C connector/VBUS")
			(pintype "passive")
		)
	)
	(footprint "antmicro-footprints:FB_0603_1608Metric"
		(layer "B.Cu")
		(at 156.481866 93.385117 90)
		(property "Reference" "FB3"
			(at -9.914883 18.318134 270)
			(layer "B.SilkS")
			(effects
				(font
					(size 0.7 0.7)
					(thickness 0.15)
				)
				(justify mirror)
			)
		)
		(property "Value" "FB_470Z_1A_Murata-BLM18PG_0603"
			(at 0 -1.5 270)
			(layer "B.Fab")
			(effects
				(font
					(size 0.7 0.7)
					(thickness 0.15)
				)
				(justify left bottom mirror)
			)
		)
		(property "Datasheet" "https://www.murata.com/en-us/products/productdata/8796738650142/ENFA0003.pdf"
			(at 0 0 270)
			(layer "B.Fab")
			(hide yes)
			(effects
				(font
					(size 1.27 1.27)
					(thickness 0.15)
				)
				(justify mirror)
			)
		)
		(property "Description" "Ferrite Bead, 0603 [1608 Metric], 470 ohm, 1 A, BLM18P, 0.2 ohm, ± 25%, DC power line"
			(at 0 0 270)
			(layer "B.Fab")
			(hide yes)
			(effects
				(font
					(size 1.27 1.27)
					(thickness 0.15)
				)
				(justify mirror)
			)
		)
		(property "Val" "470Z/1A"
			(at 0 0 90)
			(unlocked yes)
			(layer "B.Fab")
			(hide yes)
			(effects
				(font
					(size 1 1)
					(thickness 0.15)
				)
				(justify mirror)
			)
		)
		(property "MPN" "BLM18PG471SN1D"
			(at 0 0 90)
			(unlocked yes)
			(layer "B.Fab")
			(hide yes)
			(effects
				(font
					(size 1 1)
					(thickness 0.15)
				)
				(justify mirror)
			)
		)
		(property "Manufacturer" "Murata"
			(at 0 0 90)
			(unlocked yes)
			(layer "B.Fab")
			(hide yes)
			(effects
				(font
					(size 1 1)
					(thickness 0.15)
				)
				(justify mirror)
			)
		)
		(property "Current" ""
			(at 0 0 90)
			(unlocked yes)
			(layer "B.Fab")
			(hide yes)
			(effects
				(font
					(size 1 1)
					(thickness 0.15)
				)
				(justify mirror)
			)
		)
		(property "Author" "Antmicro"
			(at 0 0 90)
			(unlocked yes)
			(layer "B.Fab")
			(hide yes)
			(effects
				(font
					(size 1 1)
					(thickness 0.15)
				)
				(justify mirror)
			)
		)
		(property "License" "Apache-2.0"
			(at 0 0 90)
			(unlocked yes)
			(layer "B.Fab")
			(hide yes)
			(effects
				(font
					(size 1 1)
					(thickness 0.15)
				)
				(justify mirror)
			)
		)
		(sheetname "/X710-AT2 power/")
		(sheetfile "x710-at2-power.kicad_sch")
		(attr smd)
		(fp_line
			(start -0.15 -0.4)
			(end 0.15 -0.4)
			(stroke
				(width 0.15)
				(type solid)
			)
			(layer "B.SilkS")
		)
		(fp_line
			(start -0.15 0.4)
			(end 0.15 0.4)
			(stroke
				(width 0.15)
				(type solid)
			)
			(layer "B.SilkS")
		)
		(fp_rect
			(start -1.25 0.65)
			(end 1.25 -0.65)
			(stroke
				(width 0.05)
				(type solid)
			)
			(fill no)
			(layer "B.CrtYd")
		)
		(fp_line
			(start 0.8 -0.406)
			(end -0.803 -0.406)
			(stroke
				(width 0.15)
				(type solid)
			)
			(layer "B.Fab")
		)
		(fp_line
			(start -0.803 -0.406)
			(end -0.803 0.408)
			(stroke
				(width 0.15)
				(type solid)
			)
			(layer "B.Fab")
		)
		(fp_line
			(start 0.8 0.408)
			(end 0.8 -0.406)
			(stroke
				(width 0.15)
				(type solid)
			)
			(layer "B.Fab")
		)
		(fp_line
			(start 0.8 0.408)
			(end -0.803 0.408)
			(stroke
				(width 0.15)
				(type solid)
			)
			(layer "B.Fab")
		)
		(fp_text user "Author: Antmicro"
			(at -1.653 -3.162 270)
			(layer "B.Fab")
			(effects
				(font
					(size 0.7 0.7)
					(thickness 0.15)
				)
				(justify left bottom mirror)
			)
		)
		(fp_text user "License: Apache-2.0"
			(at -1.653 -5.9 270)
			(layer "B.Fab")
			(effects
				(font
					(size 0.7 0.7)
					(thickness 0.15)
				)
				(justify left bottom mirror)
			)
		)
		(fp_text user "${REFERENCE}"
			(at -1.653 -4.6 270)
			(layer "B.Fab")
			(effects
				(font
					(size 0.7 0.7)
					(thickness 0.15)
				)
				(justify left bottom mirror)
			)
		)
		(pad "1" smd roundrect
			(at -0.7 0 90)
			(size 0.8 1)
			(layers "B.Cu" "B.Mask" "B.Paste")
			(roundrect_rratio 0.2)
			(net 136 "+1V0")
			(pintype "passive")
		)
		(pad "2" smd roundrect
			(at 0.7 0 90)
			(size 0.8 1)
			(layers "B.Cu" "B.Mask" "B.Paste")
			(roundrect_rratio 0.2)
			(net 22 "PLL_VDD")
			(pintype "passive")
		)
	)
	(footprint "antmicro-footprints:R_0402_1005Metric"
		(layer "B.Cu")
		(at 135.600001 126.604998)
		(descr "Resistor SMD 0402")
		(tags "resistor SMD 0402")
		(property "Reference" "R59"
			(at 19.525001 -7.450001 180)
			(layer "B.SilkS")
			(effects
				(font
					(size 0.7 0.7)
					(thickness 0.15)
				)
				(justify mirror)
			)
		)
		(property "Value" "R_1M_0402"
			(at -1.011843 -1.772047 180)
			(layer "B.Fab")
			(effects
				(font
					(size 0.7 0.7)
					(thickness 0.15)
				)
				(justify left bottom mirror)
			)
		)
		(property "Datasheet" "https://www.bourns.com/docs/product-datasheets/cr.pdf"
			(at 0 0 180)
			(layer "B.Fab")
			(hide yes)
			(effects
				(font
					(size 1.27 1.27)
					(thickness 0.15)
				)
				(justify mirror)
			)
		)
		(property "Description" "SMD Chip Resistor, 1 Mohm, ± 1%, 62.5 mW, 0402 [1005 Metric], Thick Film, General Purpose"
			(at 0 0 180)
			(layer "B.Fab")
			(hide yes)
			(effects
				(font
					(size 1.27 1.27)
					(thickness 0.15)
				)
				(justify mirror)
			)
		)
		(property "MPN" "CR0402-FX-1004GLF"
			(at 0 0 0)
			(unlocked yes)
			(layer "B.Fab")
			(hide yes)
			(effects
				(font
					(size 1 1)
					(thickness 0.15)
				)
				(justify mirror)
			)
		)
		(property "Manufacturer" "Bourns"
			(at 0 0 0)
			(unlocked yes)
			(layer "B.Fab")
			(hide yes)
			(effects
				(font
					(size 1 1)
					(thickness 0.15)
				)
				(justify mirror)
			)
		)
		(property "License" "Apache-2.0"
			(at 0 0 0)
			(unlocked yes)
			(layer "B.Fab")
			(hide yes)
			(effects
				(font
					(size 1 1)
					(thickness 0.15)
				)
				(justify mirror)
			)
		)
		(property "Val" "1M"
			(at 0 0 0)
			(unlocked yes)
			(layer "B.Fab")
			(hide yes)
			(effects
				(font
					(size 1 1)
					(thickness 0.15)
				)
				(justify mirror)
			)
		)
		(property "Tolerance" "1%"
			(at 0 0 0)
			(unlocked yes)
			(layer "B.Fab")
			(hide yes)
			(effects
				(font
					(size 1 1)
					(thickness 0.15)
				)
				(justify mirror)
			)
		)
		(property "Author" "Antmicro"
			(at 0 0 0)
			(unlocked yes)
			(layer "B.Fab")
			(hide yes)
			(effects
				(font
					(size 1 1)
					(thickness 0.15)
				)
				(justify mirror)
			)
		)
		(sheetname "/TB Controller/")
		(sheetfile "tb.kicad_sch")
		(attr smd)
		(fp_rect
			(start -0.925 0.47)
			(end 0.925 -0.47)
			(stroke
				(width 0.05)
				(type default)
			)
			(fill no)
			(layer "B.CrtYd")
		)
		(fp_rect
			(start -0.5 0.25)
			(end 0.5 -0.25)
			(stroke
				(width 0.15)
				(type solid)
			)
			(fill no)
			(layer "B.Fab")
		)
		(fp_text user "License: Apache-2.0"
			(at -0.95 -5.169 180)
			(layer "B.Fab")
			(effects
				(font
					(size 0.7 0.7)
					(thickness 0.15)
				)
				(justify left bottom mirror)
			)
		)
		(fp_text user "${REFERENCE}"
			(at -0.95 -3.168 180)
			(layer "B.Fab")
			(effects
				(font
					(size 0.7 0.7)
					(thickness 0.15)
				)
				(justify left bottom mirror)
			)
		)
		(fp_text user "Author: Antmicro"
			(at -0.95 -4.169 180)
			(layer "B.Fab")
			(effects
				(font
					(size 0.7 0.7)
					(thickness 0.15)
				)
				(justify left bottom mirror)
			)
		)
		(pad "1" smd roundrect
			(at -0.48 0)
			(size 0.59 0.64)
			(layers "B.Cu" "B.Mask" "B.Paste")
			(roundrect_rratio 0.25)
			(net 232 "Net-(U4E-PB_LSRX)")
			(pintype "passive")
		)
		(pad "2" smd roundrect
			(at 0.48 0)
			(size 0.59 0.64)
			(layers "B.Cu" "B.Mask" "B.Paste")
			(roundrect_rratio 0.25)
			(net 23 "GND")
			(pintype "passive")
		)
	)
	(footprint "antmicro-footprints:C_0402_1005Metric"
		(layer "B.Cu")
		(at 127.800001 142.3 -90)
		(descr "Capacitor SMD 0402")
		(tags "capacitor SMD 0402")
		(property "Reference" "C29"
			(at -1.15 -2.45 90)
			(layer "B.SilkS")
			(effects
				(font
					(size 0.7 0.7)
					(thickness 0.15)
				)
				(justify left bottom mirror)
			)
		)
		(property "Value" "C_220p_0402"
			(at -1.022927 -2.155213 90)
			(layer "B.Fab")
			(effects
				(font
					(size 0.7 0.7)
					(thickness 0.15)
				)
				(justify left bottom mirror)
			)
		)
		(property "Datasheet" "https://spicat.kyocera-avx.com/product/mlcc/chartview/04025C221JAT2A/"
			(at 0 0 90)
			(layer "B.Fab")
			(hide yes)
			(effects
				(font
					(size 1.27 1.27)
					(thickness 0.15)
				)
				(justify mirror)
			)
		)
		(property "Description" "SMD Multilayer Ceramic Capacitor, 220 pF, 50 V, 0402 [1005 Metric], ± 10%, X7R, MC"
			(at 0 0 90)
			(layer "B.Fab")
			(hide yes)
			(effects
				(font
					(size 1.27 1.27)
					(thickness 0.15)
				)
				(justify mirror)
			)
		)
		(property "MPN" "04025C221JAT2A"
			(at 0 0 270)
			(unlocked yes)
			(layer "B.Fab")
			(hide yes)
			(effects
				(font
					(size 1 1)
					(thickness 0.15)
				)
				(justify mirror)
			)
		)
		(property "Manufacturer" "KYOCERA AVX"
			(at 0 0 270)
			(unlocked yes)
			(layer "B.Fab")
			(hide yes)
			(effects
				(font
					(size 1 1)
					(thickness 0.15)
				)
				(justify mirror)
			)
		)
		(property "License" "Apache-2.0"
			(at 0 0 270)
			(unlocked yes)
			(layer "B.Fab")
			(hide yes)
			(effects
				(font
					(size 1 1)
					(thickness 0.15)
				)
				(justify mirror)
			)
		)
		(property "Val" "220p"
			(at 0 0 270)
			(unlocked yes)
			(layer "B.Fab")
			(hide yes)
			(effects
				(font
					(size 1 1)
					(thickness 0.15)
				)
				(justify mirror)
			)
		)
		(property "Voltage" ""
			(at 0 0 270)
			(unlocked yes)
			(layer "B.Fab")
			(hide yes)
			(effects
				(font
					(size 1 1)
					(thickness 0.15)
				)
				(justify mirror)
			)
		)
		(property "Dielectric" ""
			(at 0 0 270)
			(unlocked yes)
			(layer "B.Fab")
			(hide yes)
			(effects
				(font
					(size 1 1)
					(thickness 0.15)
				)
				(justify mirror)
			)
		)
		(property "Author" "Antmicro"
			(at 0 0 270)
			(unlocked yes)
			(layer "B.Fab")
			(hide yes)
			(effects
				(font
					(size 1 1)
					(thickness 0.15)
				)
				(justify mirror)
			)
		)
		(sheetname "/PD and TB DC-DC/")
		(sheetfile "PD_and_TB_DC_DC.kicad_sch")
		(attr smd)
		(fp_rect
			(start -0.925 0.47)
			(end 0.925 -0.47)
			(stroke
				(width 0.05)
				(type default)
			)
			(fill no)
			(layer "B.CrtYd")
		)
		(fp_line
			(start -0.494 0.25)
			(end 0.504 0.25)
			(stroke
				(width 0.15)
				(type solid)
			)
			(layer "B.Fab")
		)
		(fp_line
			(start 0.504 0.25)
			(end 0.504 -0.248)
			(stroke
				(width 0.15)
				(type solid)
			)
			(layer "B.Fab")
		)
		(fp_line
			(start -0.494 -0.248)
			(end -0.494 0.25)
			(stroke
				(width 0.15)
				(type solid)
			)
			(layer "B.Fab")
		)
		(fp_line
			(start 0.504 -0.248)
			(end -0.494 -0.248)
			(stroke
				(width 0.15)
				(type solid)
			)
			(layer "B.Fab")
		)
		(fp_text user "License: Apache-2.0"
			(at -0.939 -5.799 90)
			(layer "B.Fab")
			(effects
				(font
					(size 0.7 0.7)
					(thickness 0.15)
				)
				(justify left bottom mirror)
			)
		)
		(fp_text user "Author: Antmicro"
			(at -0.939 -3.399 90)
			(layer "B.Fab")
			(effects
				(font
					(size 0.7 0.7)
					(thickness 0.15)
				)
				(justify left bottom mirror)
			)
		)
		(fp_text user "${REFERENCE}"
			(at -0.939 -4.599 90)
			(layer "B.Fab")
			(effects
				(font
					(size 0.7 0.7)
					(thickness 0.15)
				)
				(justify left bottom mirror)
			)
		)
		(pad "1" smd roundrect
			(at -0.48 0 270)
			(size 0.59 0.64)
			(layers "B.Cu" "B.Mask" "B.Paste")
			(roundrect_rratio 0.25)
			(net 23 "GND")
			(pintype "passive")
		)
		(pad "2" smd roundrect
			(at 0.48 0 270)
			(size 0.59 0.64)
			(layers "B.Cu" "B.Mask" "B.Paste")
			(roundrect_rratio 0.25)
			(net 305 "/PD and TB DC-DC/USB3.CC2")
			(pintype "passive")
		)
	)
	(footprint "antmicro-footprints:R_0402_1005Metric"
		(layer "B.Cu")
		(at 150.131866 70.035117 90)
		(descr "Resistor SMD 0402")
		(tags "resistor SMD 0402")
		(property "Reference" "R199"
			(at -9.464883 19.468134 270)
			(layer "B.SilkS")
			(effects
				(font
					(size 0.7 0.7)
					(thickness 0.15)
				)
				(justify mirror)
			)
		)
		(property "Value" "R_3k3_0402"
			(at -1.011843 -1.772047 270)
			(layer "B.Fab")
			(effects
				(font
					(size 0.7 0.7)
					(thickness 0.15)
				)
				(justify left bottom mirror)
			)
		)
		(property "Datasheet" "https://www.bourns.com/docs/product-datasheets/cr.pdf"
			(at 0 0 270)
			(layer "B.Fab")
			(hide yes)
			(effects
				(font
					(size 1.27 1.27)
					(thickness 0.15)
				)
				(justify mirror)
			)
		)
		(property "Description" "SMD Chip Resistor, 3.3 kohm, ± 1%, 63 mW, 0402 [1005 Metric], Thick Film, General Purpose"
			(at 0 0 270)
			(layer "B.Fab")
			(hide yes)
			(effects
				(font
					(size 1.27 1.27)
					(thickness 0.15)
				)
				(justify mirror)
			)
		)
		(property "MPN" "CR0402-FX-3301GLF"
			(at 0 0 90)
			(unlocked yes)
			(layer "B.Fab")
			(hide yes)
			(effects
				(font
					(size 1 1)
					(thickness 0.15)
				)
				(justify mirror)
			)
		)
		(property "Manufacturer" "Bourns"
			(at 0 0 90)
			(unlocked yes)
			(layer "B.Fab")
			(hide yes)
			(effects
				(font
					(size 1 1)
					(thickness 0.15)
				)
				(justify mirror)
			)
		)
		(property "License" "Apache-2.0"
			(at 0 0 90)
			(unlocked yes)
			(layer "B.Fab")
			(hide yes)
			(effects
				(font
					(size 1 1)
					(thickness 0.15)
				)
				(justify mirror)
			)
		)
		(property "Author" "Antmicro"
			(at 0 0 90)
			(unlocked yes)
			(layer "B.Fab")
			(hide yes)
			(effects
				(font
					(size 1 1)
					(thickness 0.15)
				)
				(justify mirror)
			)
		)
		(property "Val" "3k3"
			(at 0 0 90)
			(unlocked yes)
			(layer "B.Fab")
			(hide yes)
			(effects
				(font
					(size 1 1)
					(thickness 0.15)
				)
				(justify mirror)
			)
		)
		(property "Tolerance" "1%"
			(at 0 0 90)
			(unlocked yes)
			(layer "B.Fab")
			(hide yes)
			(effects
				(font
					(size 1 1)
					(thickness 0.15)
				)
				(justify mirror)
			)
		)
		(sheetname "/X710-AT2 10GbE/")
		(sheetfile "x710-at2-10gbe.kicad_sch")
		(attr smd)
		(fp_rect
			(start -0.925 0.47)
			(end 0.925 -0.47)
			(stroke
				(width 0.05)
				(type default)
			)
			(fill no)
			(layer "B.CrtYd")
		)
		(fp_rect
			(start -0.5 0.25)
			(end 0.5 -0.25)
			(stroke
				(width 0.15)
				(type solid)
			)
			(fill no)
			(layer "B.Fab")
		)
		(fp_text user "License: Apache-2.0"
			(at -0.95 -5.169 270)
			(layer "B.Fab")
			(effects
				(font
					(size 0.7 0.7)
					(thickness 0.15)
				)
				(justify left bottom mirror)
			)
		)
		(fp_text user "Author: Antmicro"
			(at -0.95 -4.169 270)
			(layer "B.Fab")
			(effects
				(font
					(size 0.7 0.7)
					(thickness 0.15)
				)
				(justify left bottom mirror)
			)
		)
		(fp_text user "${REFERENCE}"
			(at -0.95 -3.168 270)
			(layer "B.Fab")
			(effects
				(font
					(size 0.7 0.7)
					(thickness 0.15)
				)
				(justify left bottom mirror)
			)
		)
		(pad "1" smd roundrect
			(at -0.48 0 90)
			(size 0.59 0.64)
			(layers "B.Cu" "B.Mask" "B.Paste")
			(roundrect_rratio 0.25)
			(net 78 "/X710-AT2 10GbE/MDIO1_SDA1")
			(pintype "passive")
		)
		(pad "2" smd roundrect
			(at 0.48 0 90)
			(size 0.59 0.64)
			(layers "B.Cu" "B.Mask" "B.Paste")
			(roundrect_rratio 0.25)
			(net 7 "+3V3")
			(pintype "passive")
		)
	)
	(footprint "antmicro-footprints:R_0402_1005Metric"
		(layer "B.Cu")
		(at 145.031866 73.260117)
		(descr "Resistor SMD 0402")
		(tags "resistor SMD 0402")
		(property "Reference" "R123"
			(at 18.468134 7.539883 180)
			(layer "B.SilkS")
			(effects
				(font
					(size 0.7 0.7)
					(thickness 0.15)
				)
				(justify mirror)
			)
		)
		(property "Value" "R_100R_0402"
			(at -1.011843 -1.772047 180)
			(layer "B.Fab")
			(effects
				(font
					(size 0.7 0.7)
					(thickness 0.15)
				)
				(justify left bottom mirror)
			)
		)
		(property "Datasheet" "https://www.bourns.com/docs/product-datasheets/cr.pdf"
			(at 0 0 180)
			(layer "B.Fab")
			(hide yes)
			(effects
				(font
					(size 1.27 1.27)
					(thickness 0.15)
				)
				(justify mirror)
			)
		)
		(property "Description" "SMD Chip Resistor, 100 ohm, ± 1%, 62.5 mW, 0402 [1005 Metric], Thick Film, General Purpose"
			(at 0 0 180)
			(layer "B.Fab")
			(hide yes)
			(effects
				(font
					(size 1.27 1.27)
					(thickness 0.15)
				)
				(justify mirror)
			)
		)
		(property "MPN" "CR0402-FX-1000GLF"
			(at 0 0 0)
			(unlocked yes)
			(layer "B.Fab")
			(hide yes)
			(effects
				(font
					(size 1 1)
					(thickness 0.15)
				)
				(justify mirror)
			)
		)
		(property "Manufacturer" "Bourns"
			(at 0 0 0)
			(unlocked yes)
			(layer "B.Fab")
			(hide yes)
			(effects
				(font
					(size 1 1)
					(thickness 0.15)
				)
				(justify mirror)
			)
		)
		(property "License" "Apache-2.0"
			(at 0 0 0)
			(unlocked yes)
			(layer "B.Fab")
			(hide yes)
			(effects
				(font
					(size 1 1)
					(thickness 0.15)
				)
				(justify mirror)
			)
		)
		(property "Author" "Antmicro"
			(at 0 0 0)
			(unlocked yes)
			(layer "B.Fab")
			(hide yes)
			(effects
				(font
					(size 1 1)
					(thickness 0.15)
				)
				(justify mirror)
			)
		)
		(property "Val" "100R"
			(at 0 0 0)
			(unlocked yes)
			(layer "B.Fab")
			(hide yes)
			(effects
				(font
					(size 1 1)
					(thickness 0.15)
				)
				(justify mirror)
			)
		)
		(property "Tolerance" "1%"
			(at 0 0 0)
			(unlocked yes)
			(layer "B.Fab")
			(hide yes)
			(effects
				(font
					(size 1 1)
					(thickness 0.15)
				)
				(justify mirror)
			)
		)
		(sheetname "/X710-AT2 RSVD/")
		(sheetfile "x710-at2-rsvd.kicad_sch")
		(attr smd)
		(fp_rect
			(start -0.925 0.47)
			(end 0.925 -0.47)
			(stroke
				(width 0.05)
				(type default)
			)
			(fill no)
			(layer "B.CrtYd")
		)
		(fp_rect
			(start -0.5 0.25)
			(end 0.5 -0.25)
			(stroke
				(width 0.15)
				(type solid)
			)
			(fill no)
			(layer "B.Fab")
		)
		(fp_text user "Author: Antmicro"
			(at -0.95 -4.169 180)
			(layer "B.Fab")
			(effects
				(font
					(size 0.7 0.7)
					(thickness 0.15)
				)
				(justify left bottom mirror)
			)
		)
		(fp_text user "License: Apache-2.0"
			(at -0.95 -5.169 180)
			(layer "B.Fab")
			(effects
				(font
					(size 0.7 0.7)
					(thickness 0.15)
				)
				(justify left bottom mirror)
			)
		)
		(fp_text user "${REFERENCE}"
			(at -0.95 -3.168 180)
			(layer "B.Fab")
			(effects
				(font
					(size 0.7 0.7)
					(thickness 0.15)
				)
				(justify left bottom mirror)
			)
		)
		(pad "1" smd roundrect
			(at -0.48 0)
			(size 0.59 0.64)
			(layers "B.Cu" "B.Mask" "B.Paste")
			(roundrect_rratio 0.25)
			(net 23 "GND")
			(pintype "passive")
		)
		(pad "2" smd roundrect
			(at 0.48 0)
			(size 0.59 0.64)
			(layers "B.Cu" "B.Mask" "B.Paste")
			(roundrect_rratio 0.25)
			(net 94 "/X710-AT2 RSVD/RSVDW5_VSS")
			(pintype "passive")
		)
	)
	(footprint "antmicro-footprints:R_0402_1005Metric"
		(layer "B.Cu")
		(at 161 69.5 90)
		(descr "Resistor SMD 0402")
		(tags "resistor SMD 0402")
		(property "Reference" "R198"
			(at -2.25 0 270)
			(layer "B.SilkS")
			(effects
				(font
					(size 0.7 0.7)
					(thickness 0.15)
				)
				(justify mirror)
			)
		)
		(property "Value" "R_0R_0402"
			(at -1.011843 -1.772047 270)
			(layer "B.Fab")
			(effects
				(font
					(size 0.7 0.7)
					(thickness 0.15)
				)
				(justify left bottom mirror)
			)
		)
		(property "Datasheet" "https://industrial.panasonic.com/cdbs/www-data/pdf/RDA0000/AOA0000C301.pdf"
			(at 0 0 270)
			(layer "B.Fab")
			(hide yes)
			(effects
				(font
					(size 1.27 1.27)
					(thickness 0.15)
				)
				(justify mirror)
			)
		)
		(property "Description" "SMD Chip Resistor, Jumper, 0 ohm, 100 mW, 0402 [1005 Metric], Thick Film, General Purpose"
			(at 0 0 270)
			(layer "B.Fab")
			(hide yes)
			(effects
				(font
					(size 1.27 1.27)
					(thickness 0.15)
				)
				(justify mirror)
			)
		)
		(property "MPN" "ERJ2GE0R00X"
			(at 0 0 90)
			(unlocked yes)
			(layer "B.Fab")
			(hide yes)
			(effects
				(font
					(size 1 1)
					(thickness 0.15)
				)
				(justify mirror)
			)
		)
		(property "Manufacturer" "Panasonic"
			(at 0 0 90)
			(unlocked yes)
			(layer "B.Fab")
			(hide yes)
			(effects
				(font
					(size 1 1)
					(thickness 0.15)
				)
				(justify mirror)
			)
		)
		(property "License" "Apache-2.0"
			(at 0 0 90)
			(unlocked yes)
			(layer "B.Fab")
			(hide yes)
			(effects
				(font
					(size 1 1)
					(thickness 0.15)
				)
				(justify mirror)
			)
		)
		(property "Author" "Antmicro"
			(at 0 0 90)
			(unlocked yes)
			(layer "B.Fab")
			(hide yes)
			(effects
				(font
					(size 1 1)
					(thickness 0.15)
				)
				(justify mirror)
			)
		)
		(property "Val" "0R"
			(at 0 0 90)
			(unlocked yes)
			(layer "B.Fab")
			(hide yes)
			(effects
				(font
					(size 1 1)
					(thickness 0.15)
				)
				(justify mirror)
			)
		)
		(property "Tolerance" "~"
			(at 0 0 90)
			(unlocked yes)
			(layer "B.Fab")
			(hide yes)
			(effects
				(font
					(size 1 1)
					(thickness 0.15)
				)
				(justify mirror)
			)
		)
		(property "Current" "1A"
			(at 0 0 90)
			(unlocked yes)
			(layer "B.Fab")
			(hide yes)
			(effects
				(font
					(size 1 1)
					(thickness 0.15)
				)
				(justify mirror)
			)
		)
		(sheetname "/X710-AT2 10GbE/")
		(sheetfile "x710-at2-10gbe.kicad_sch")
		(attr smd)
		(fp_rect
			(start -0.925 0.47)
			(end 0.925 -0.47)
			(stroke
				(width 0.05)
				(type default)
			)
			(fill no)
			(layer "B.CrtYd")
		)
		(fp_rect
			(start -0.5 0.25)
			(end 0.5 -0.25)
			(stroke
				(width 0.15)
				(type solid)
			)
			(fill no)
			(layer "B.Fab")
		)
		(fp_text user "Author: Antmicro"
			(at -0.95 -4.169 270)
			(layer "B.Fab")
			(effects
				(font
					(size 0.7 0.7)
					(thickness 0.15)
				)
				(justify left bottom mirror)
			)
		)
		(fp_text user "${REFERENCE}"
			(at -0.95 -3.168 270)
			(layer "B.Fab")
			(effects
				(font
					(size 0.7 0.7)
					(thickness 0.15)
				)
				(justify left bottom mirror)
			)
		)
		(fp_text user "License: Apache-2.0"
			(at -0.95 -5.169 270)
			(layer "B.Fab")
			(effects
				(font
					(size 0.7 0.7)
					(thickness 0.15)
				)
				(justify left bottom mirror)
			)
		)
		(pad "1" smd roundrect
			(at -0.48 0 90)
			(size 0.59 0.64)
			(layers "B.Cu" "B.Mask" "B.Paste")
			(roundrect_rratio 0.25)
			(net 124 "/X710-AT2 10GbE/~{P1_INT}")
			(pintype "passive")
		)
		(pad "2" smd roundrect
			(at 0.48 0 90)
			(size 0.59 0.64)
			(layers "B.Cu" "B.Mask" "B.Paste")
			(roundrect_rratio 0.25)
			(net 123 "/X710-AT2 10GbE/~{P1_INT_R}")
			(pintype "passive")
		)
	)
	(footprint "antmicro-footprints:TP_SMD_0.75mm"
		(layer "B.Cu")
		(at 158.681865 78.760117 180)
		(property "Reference" "TP32"
			(at -20.778136 -8.839883 0)
			(layer "B.SilkS")
			(effects
				(font
					(size 0.7 0.7)
					(thickness 0.15)
				)
				(justify mirror)
			)
		)
		(property "Value" "TP_0.75mm_SMD"
			(at 0 -1.2 0)
			(layer "B.Fab")
			(effects
				(font
					(size 0.7 0.7)
					(thickness 0.15)
				)
				(justify left bottom mirror)
			)
		)
		(property "Description" "SMT test point"
			(at 0 0 0)
			(layer "B.Fab")
			(hide yes)
			(effects
				(font
					(size 1.27 1.27)
					(thickness 0.15)
				)
				(justify mirror)
			)
		)
		(property "MPN" ""
			(at 0 0 180)
			(unlocked yes)
			(layer "B.Fab")
			(hide yes)
			(effects
				(font
					(size 1 1)
					(thickness 0.15)
				)
				(justify mirror)
			)
		)
		(property "Manufacturer" ""
			(at 0 0 180)
			(unlocked yes)
			(layer "B.Fab")
			(hide yes)
			(effects
				(font
					(size 1 1)
					(thickness 0.15)
				)
				(justify mirror)
			)
		)
		(property "Author" "Antmicro"
			(at 0 0 180)
			(unlocked yes)
			(layer "B.Fab")
			(hide yes)
			(effects
				(font
					(size 1 1)
					(thickness 0.15)
				)
				(justify mirror)
			)
		)
		(property "License" "Apache-2.0"
			(at 0 0 180)
			(unlocked yes)
			(layer "B.Fab")
			(hide yes)
			(effects
				(font
					(size 1 1)
					(thickness 0.15)
				)
				(justify mirror)
			)
		)
		(sheetname "/X710-AT2 Misc/")
		(sheetfile "x710-at2-mics.kicad_sch")
		(attr exclude_from_pos_files exclude_from_bom)
		(fp_circle
			(center 0 0)
			(end 0.475 0)
			(stroke
				(width 0.05)
				(type default)
			)
			(fill no)
			(layer "B.CrtYd")
		)
		(fp_text user "License: Apache-2.0"
			(at -0.4 -5.101 0)
			(layer "B.Fab")
			(effects
				(font
					(size 0.7 0.7)
					(thickness 0.15)
				)
				(justify left bottom mirror)
			)
		)
		(fp_text user "Author: Antmicro"
			(at -0.4 -3.901 0)
			(layer "B.Fab")
			(effects
				(font
					(size 0.7 0.7)
					(thickness 0.15)
				)
				(justify left bottom mirror)
			)
		)
		(fp_text user "${REFERENCE}"
			(at -0.4 -2.7 0)
			(layer "B.Fab")
			(effects
				(font
					(size 0.7 0.7)
					(thickness 0.15)
				)
				(justify left bottom mirror)
			)
		)
		(pad "1" smd circle
			(at 0 0 180)
			(size 0.75 0.75)
			(layers "B.Cu" "B.Mask")
			(net 105 "/X710-AT2 Misc/PHY_TMS")
			(pinfunction "1")
			(pintype "passive")
		)
	)
	(footprint "antmicro-footprints:R_0402_1005Metric"
		(layer "B.Cu")
		(at 126.8 144.4 90)
		(descr "Resistor SMD 0402")
		(tags "resistor SMD 0402")
		(property "Reference" "R33"
			(at 1.15 2.45 270)
			(layer "B.SilkS")
			(effects
				(font
					(size 0.7 0.7)
					(thickness 0.15)
				)
				(justify left bottom mirror)
			)
		)
		(property "Value" "R_5k1_0402"
			(at -1.011843 -1.772047 270)
			(layer "B.Fab")
			(effects
				(font
					(size 0.7 0.7)
					(thickness 0.15)
				)
				(justify left bottom mirror)
			)
		)
		(property "Datasheet" "https://www.bourns.com/docs/product-datasheets/cr.pdf"
			(at 0 0 270)
			(layer "B.Fab")
			(hide yes)
			(effects
				(font
					(size 1.27 1.27)
					(thickness 0.15)
				)
				(justify mirror)
			)
		)
		(property "Description" "SMD Chip Resistor, 5.1 kohm, ± 1%, 63 mW, 0402 [1005 Metric], Thick Film, General Purpose"
			(at 0 0 270)
			(layer "B.Fab")
			(hide yes)
			(effects
				(font
					(size 1.27 1.27)
					(thickness 0.15)
				)
				(justify mirror)
			)
		)
		(property "MPN" "CR0402-FX-5101GLF"
			(at 0 0 90)
			(unlocked yes)
			(layer "B.Fab")
			(hide yes)
			(effects
				(font
					(size 1 1)
					(thickness 0.15)
				)
				(justify mirror)
			)
		)
		(property "Manufacturer" "Bourns"
			(at 0 0 90)
			(unlocked yes)
			(layer "B.Fab")
			(hide yes)
			(effects
				(font
					(size 1 1)
					(thickness 0.15)
				)
				(justify mirror)
			)
		)
		(property "License" "Apache-2.0"
			(at 0 0 90)
			(unlocked yes)
			(layer "B.Fab")
			(hide yes)
			(effects
				(font
					(size 1 1)
					(thickness 0.15)
				)
				(justify mirror)
			)
		)
		(property "Val" "5k1"
			(at 0 0 90)
			(unlocked yes)
			(layer "B.Fab")
			(hide yes)
			(effects
				(font
					(size 1 1)
					(thickness 0.15)
				)
				(justify mirror)
			)
		)
		(property "Tolerance" "1%"
			(at 0 0 90)
			(unlocked yes)
			(layer "B.Fab")
			(hide yes)
			(effects
				(font
					(size 1 1)
					(thickness 0.15)
				)
				(justify mirror)
			)
		)
		(property "Author" "Antmicro"
			(at 0 0 90)
			(unlocked yes)
			(layer "B.Fab")
			(hide yes)
			(effects
				(font
					(size 1 1)
					(thickness 0.15)
				)
				(justify mirror)
			)
		)
		(sheetname "/PD and TB DC-DC/")
		(sheetfile "PD_and_TB_DC_DC.kicad_sch")
		(attr smd)
		(fp_rect
			(start -0.925 0.47)
			(end 0.925 -0.47)
			(stroke
				(width 0.05)
				(type default)
			)
			(fill no)
			(layer "B.CrtYd")
		)
		(fp_rect
			(start -0.5 0.25)
			(end 0.5 -0.25)
			(stroke
				(width 0.15)
				(type solid)
			)
			(fill no)
			(layer "B.Fab")
		)
		(fp_text user "License: Apache-2.0"
			(at -0.95 -5.169 270)
			(layer "B.Fab")
			(effects
				(font
					(size 0.7 0.7)
					(thickness 0.15)
				)
				(justify left bottom mirror)
			)
		)
		(fp_text user "Author: Antmicro"
			(at -0.95 -4.169 270)
			(layer "B.Fab")
			(effects
				(font
					(size 0.7 0.7)
					(thickness 0.15)
				)
				(justify left bottom mirror)
			)
		)
		(fp_text user "${REFERENCE}"
			(at -0.95 -3.168 270)
			(layer "B.Fab")
			(effects
				(font
					(size 0.7 0.7)
					(thickness 0.15)
				)
				(justify left bottom mirror)
			)
		)
		(pad "1" smd roundrect
			(at -0.48 0 90)
			(size 0.59 0.64)
			(layers "B.Cu" "B.Mask" "B.Paste")
			(roundrect_rratio 0.25)
			(net 23 "GND")
			(pintype "passive")
		)
		(pad "2" smd roundrect
			(at 0.48 0 90)
			(size 0.59 0.64)
			(layers "B.Cu" "B.Mask" "B.Paste")
			(roundrect_rratio 0.25)
			(net 306 "/PD and TB DC-DC/USB3.CC1")
			(pintype "passive")
		)
	)
	(footprint "antmicro-footprints:FB_0603_1608Metric"
		(layer "B.Cu")
		(at 163.25 132)
		(property "Reference" "FB9"
			(at 4.5 -2.5 180)
			(layer "B.SilkS")
			(effects
				(font
					(size 0.7 0.7)
					(thickness 0.15)
				)
				(justify left bottom mirror)
			)
		)
		(property "Value" "FB_33Z_3A_Murata-BLM18PG_0603"
			(at 0 -1.5 180)
			(layer "B.Fab")
			(effects
				(font
					(size 0.7 0.7)
					(thickness 0.15)
				)
				(justify left bottom mirror)
			)
		)
		(property "Datasheet" "https://www.murata.com/products/productdata/8796737273886/QNFA9101.pdf?1649080818000"
			(at 0 0 180)
			(layer "B.Fab")
			(hide yes)
			(effects
				(font
					(size 1.27 1.27)
					(thickness 0.15)
				)
				(justify mirror)
			)
		)
		(property "Description" "Ferrite Bead, 0603 [1608 Metric], 33 ohm, 3 A, BLM18PG, 0.025 ohm, ± 25%, DC power line"
			(at 0 0 180)
			(layer "B.Fab")
			(hide yes)
			(effects
				(font
					(size 1.27 1.27)
					(thickness 0.15)
				)
				(justify mirror)
			)
		)
		(property "Val" "33Z/3A"
			(at 0 0 0)
			(unlocked yes)
			(layer "B.Fab")
			(hide yes)
			(effects
				(font
					(size 1 1)
					(thickness 0.15)
				)
				(justify mirror)
			)
		)
		(property "MPN" "BLM18PG330SH1D"
			(at 0 0 0)
			(unlocked yes)
			(layer "B.Fab")
			(hide yes)
			(effects
				(font
					(size 1 1)
					(thickness 0.15)
				)
				(justify mirror)
			)
		)
		(property "Manufacturer" "Murata"
			(at 0 0 0)
			(unlocked yes)
			(layer "B.Fab")
			(hide yes)
			(effects
				(font
					(size 1 1)
					(thickness 0.15)
				)
				(justify mirror)
			)
		)
		(property "Current" ""
			(at 0 0 0)
			(unlocked yes)
			(layer "B.Fab")
			(hide yes)
			(effects
				(font
					(size 1 1)
					(thickness 0.15)
				)
				(justify mirror)
			)
		)
		(property "Author" "Antmicro"
			(at 0 0 0)
			(unlocked yes)
			(layer "B.Fab")
			(hide yes)
			(effects
				(font
					(size 1 1)
					(thickness 0.15)
				)
				(justify mirror)
			)
		)
		(property "License" "Apache-2.0"
			(at 0 0 0)
			(unlocked yes)
			(layer "B.Fab")
			(hide yes)
			(effects
				(font
					(size 1 1)
					(thickness 0.15)
				)
				(justify mirror)
			)
		)
		(sheetname "/2xRJ45/")
		(sheetfile "2xrj45.kicad_sch")
		(attr smd)
		(fp_line
			(start -0.15 -0.4)
			(end 0.15 -0.4)
			(stroke
				(width 0.15)
				(type solid)
			)
			(layer "B.SilkS")
		)
		(fp_line
			(start -0.15 0.4)
			(end 0.15 0.4)
			(stroke
				(width 0.15)
				(type solid)
			)
			(layer "B.SilkS")
		)
		(fp_rect
			(start -1.25 0.65)
			(end 1.25 -0.65)
			(stroke
				(width 0.05)
				(type solid)
			)
			(fill no)
			(layer "B.CrtYd")
		)
		(fp_line
			(start -0.803 -0.406)
			(end -0.803 0.408)
			(stroke
				(width 0.15)
				(type solid)
			)
			(layer "B.Fab")
		)
		(fp_line
			(start 0.8 -0.406)
			(end -0.803 -0.406)
			(stroke
				(width 0.15)
				(type solid)
			)
			(layer "B.Fab")
		)
		(fp_line
			(start 0.8 0.408)
			(end -0.803 0.408)
			(stroke
				(width 0.15)
				(type solid)
			)
			(layer "B.Fab")
		)
		(fp_line
			(start 0.8 0.408)
			(end 0.8 -0.406)
			(stroke
				(width 0.15)
				(type solid)
			)
			(layer "B.Fab")
		)
		(fp_text user "License: Apache-2.0"
			(at -1.653 -5.9 180)
			(layer "B.Fab")
			(effects
				(font
					(size 0.7 0.7)
					(thickness 0.15)
				)
				(justify left bottom mirror)
			)
		)
		(fp_text user "Author: Antmicro"
			(at -1.653 -3.162 180)
			(layer "B.Fab")
			(effects
				(font
					(size 0.7 0.7)
					(thickness 0.15)
				)
				(justify left bottom mirror)
			)
		)
		(fp_text user "${REFERENCE}"
			(at -1.653 -4.6 180)
			(layer "B.Fab")
			(effects
				(font
					(size 0.7 0.7)
					(thickness 0.15)
				)
				(justify left bottom mirror)
			)
		)
		(pad "1" smd roundrect
			(at -0.7 0)
			(size 0.8 1)
			(layers "B.Cu" "B.Mask" "B.Paste")
			(roundrect_rratio 0.2)
			(net 18 "+1V88")
			(pintype "passive")
		)
		(pad "2" smd roundrect
			(at 0.7 0)
			(size 0.8 1)
			(layers "B.Cu" "B.Mask" "B.Paste")
			(roundrect_rratio 0.2)
			(net 135 "+1V88_CT")
			(pintype "passive")
		)
	)
	(footprint "antmicro-footprints:C_0402_1005Metric"
		(layer "B.Cu")
		(at 151.381865 89.535116 -90)
		(descr "Capacitor SMD 0402")
		(tags "capacitor SMD 0402")
		(property "Reference" "C185"
			(at 10.264883 -18.868134 90)
			(layer "B.SilkS")
			(effects
				(font
					(size 0.7 0.7)
					(thickness 0.15)
				)
				(justify mirror)
			)
		)
		(property "Value" "C_1u_25V_0402"
			(at -1.022927 -2.155213 90)
			(layer "B.Fab")
			(effects
				(font
					(size 0.7 0.7)
					(thickness 0.15)
				)
				(justify left bottom mirror)
			)
		)
		(property "Datasheet" "https://www.murata.com/products/productdetail?partno=GRM155R61E105KE11%23"
			(at 0 0 90)
			(layer "B.Fab")
			(hide yes)
			(effects
				(font
					(size 1.27 1.27)
					(thickness 0.15)
				)
				(justify mirror)
			)
		)
		(property "Description" "SMD Multilayer Ceramic Capacitor, 1 µF, 25 V, 0402 [1005 Metric], ± 10%, X5R, GRM Series"
			(at 0 0 90)
			(layer "B.Fab")
			(hide yes)
			(effects
				(font
					(size 1.27 1.27)
					(thickness 0.15)
				)
				(justify mirror)
			)
		)
		(property "MPN" "GRM155R61E105KE11J"
			(at 0 0 270)
			(unlocked yes)
			(layer "B.Fab")
			(hide yes)
			(effects
				(font
					(size 1 1)
					(thickness 0.15)
				)
				(justify mirror)
			)
		)
		(property "Manufacturer" "Murata"
			(at 0 0 270)
			(unlocked yes)
			(layer "B.Fab")
			(hide yes)
			(effects
				(font
					(size 1 1)
					(thickness 0.15)
				)
				(justify mirror)
			)
		)
		(property "License" "Apache-2.0"
			(at 0 0 270)
			(unlocked yes)
			(layer "B.Fab")
			(hide yes)
			(effects
				(font
					(size 1 1)
					(thickness 0.15)
				)
				(justify mirror)
			)
		)
		(property "Author" "Antmicro"
			(at 0 0 270)
			(unlocked yes)
			(layer "B.Fab")
			(hide yes)
			(effects
				(font
					(size 1 1)
					(thickness 0.15)
				)
				(justify mirror)
			)
		)
		(property "Val" "1u"
			(at 0 0 270)
			(unlocked yes)
			(layer "B.Fab")
			(hide yes)
			(effects
				(font
					(size 1 1)
					(thickness 0.15)
				)
				(justify mirror)
			)
		)
		(property "Voltage" "25V"
			(at 0 0 270)
			(unlocked yes)
			(layer "B.Fab")
			(hide yes)
			(effects
				(font
					(size 1 1)
					(thickness 0.15)
				)
				(justify mirror)
			)
		)
		(property "Dielectric" "X5R"
			(at 0 0 270)
			(unlocked yes)
			(layer "B.Fab")
			(hide yes)
			(effects
				(font
					(size 1 1)
					(thickness 0.15)
				)
				(justify mirror)
			)
		)
		(sheetname "/X710-AT2 power/")
		(sheetfile "x710-at2-power.kicad_sch")
		(attr smd)
		(fp_rect
			(start -0.925 0.47)
			(end 0.925 -0.47)
			(stroke
				(width 0.05)
				(type default)
			)
			(fill no)
			(layer "B.CrtYd")
		)
		(fp_line
			(start -0.494 0.25)
			(end 0.504 0.25)
			(stroke
				(width 0.15)
				(type solid)
			)
			(layer "B.Fab")
		)
		(fp_line
			(start 0.504 0.25)
			(end 0.504 -0.248)
			(stroke
				(width 0.15)
				(type solid)
			)
			(layer "B.Fab")
		)
		(fp_line
			(start -0.494 -0.248)
			(end -0.494 0.25)
			(stroke
				(width 0.15)
				(type solid)
			)
			(layer "B.Fab")
		)
		(fp_line
			(start 0.504 -0.248)
			(end -0.494 -0.248)
			(stroke
				(width 0.15)
				(type solid)
			)
			(layer "B.Fab")
		)
		(fp_text user "Author: Antmicro"
			(at -0.939 -3.399 90)
			(layer "B.Fab")
			(effects
				(font
					(size 0.7 0.7)
					(thickness 0.15)
				)
				(justify left bottom mirror)
			)
		)
		(fp_text user "License: Apache-2.0"
			(at -0.939 -5.799 90)
			(layer "B.Fab")
			(effects
				(font
					(size 0.7 0.7)
					(thickness 0.15)
				)
				(justify left bottom mirror)
			)
		)
		(fp_text user "${REFERENCE}"
			(at -0.939 -4.599 90)
			(layer "B.Fab")
			(effects
				(font
					(size 0.7 0.7)
					(thickness 0.15)
				)
				(justify left bottom mirror)
			)
		)
		(pad "1" smd roundrect
			(at -0.48 0 270)
			(size 0.59 0.64)
			(layers "B.Cu" "B.Mask" "B.Paste")
			(roundrect_rratio 0.25)
			(net 23 "GND")
			(pintype "passive")
		)
		(pad "2" smd roundrect
			(at 0.48 0 270)
			(size 0.59 0.64)
			(layers "B.Cu" "B.Mask" "B.Paste")
			(roundrect_rratio 0.25)
			(net 18 "+1V88")
			(pintype "passive")
		)
	)
	(footprint "antmicro-footprints:C_0402_1005Metric"
		(layer "B.Cu")
		(at 120.3 150.6)
		(descr "Capacitor SMD 0402")
		(tags "capacitor SMD 0402")
		(property "Reference" "C3"
			(at 0.7 1.65 180)
			(layer "B.SilkS")
			(effects
				(font
					(size 0.7 0.7)
					(thickness 0.15)
				)
				(justify left bottom mirror)
			)
		)
		(property "Value" "C_100n_0402"
			(at -1.022927 -2.155213 180)
			(layer "B.Fab")
			(effects
				(font
					(size 0.7 0.7)
					(thickness 0.15)
				)
				(justify left bottom mirror)
			)
		)
		(property "Datasheet" "https://www.murata.com/products/productdetail?partno=GRM155R61H104KE14%23"
			(at 0 0 180)
			(layer "B.Fab")
			(hide yes)
			(effects
				(font
					(size 1.27 1.27)
					(thickness 0.15)
				)
				(justify mirror)
			)
		)
		(property "Description" "SMD Multilayer Ceramic Capacitor, 0.1 µF, 50 V, 0402 [1005 Metric], ± 10%, X5R, GRM Series"
			(at 0 0 180)
			(layer "B.Fab")
			(hide yes)
			(effects
				(font
					(size 1.27 1.27)
					(thickness 0.15)
				)
				(justify mirror)
			)
		)
		(property "MPN" "GRM155R61H104KE14D"
			(at 0 0 0)
			(unlocked yes)
			(layer "B.Fab")
			(hide yes)
			(effects
				(font
					(size 1 1)
					(thickness 0.15)
				)
				(justify mirror)
			)
		)
		(property "Manufacturer" "Murata"
			(at 0 0 0)
			(unlocked yes)
			(layer "B.Fab")
			(hide yes)
			(effects
				(font
					(size 1 1)
					(thickness 0.15)
				)
				(justify mirror)
			)
		)
		(property "License" "Apache-2.0"
			(at 0 0 0)
			(unlocked yes)
			(layer "B.Fab")
			(hide yes)
			(effects
				(font
					(size 1 1)
					(thickness 0.15)
				)
				(justify mirror)
			)
		)
		(property "Val" "100n"
			(at 0 0 0)
			(unlocked yes)
			(layer "B.Fab")
			(hide yes)
			(effects
				(font
					(size 1 1)
					(thickness 0.15)
				)
				(justify mirror)
			)
		)
		(property "Voltage" "50V"
			(at 0 0 0)
			(unlocked yes)
			(layer "B.Fab")
			(hide yes)
			(effects
				(font
					(size 1 1)
					(thickness 0.15)
				)
				(justify mirror)
			)
		)
		(property "Dielectric" "X5R"
			(at 0 0 0)
			(unlocked yes)
			(layer "B.Fab")
			(hide yes)
			(effects
				(font
					(size 1 1)
					(thickness 0.15)
				)
				(justify mirror)
			)
		)
		(property "Author" "Antmicro"
			(at 0 0 0)
			(unlocked yes)
			(layer "B.Fab")
			(hide yes)
			(effects
				(font
					(size 1 1)
					(thickness 0.15)
				)
				(justify mirror)
			)
		)
		(sheetname "/USB-C connector/")
		(sheetfile "USB-C_connector.kicad_sch")
		(attr smd)
		(fp_rect
			(start -0.925 0.47)
			(end 0.925 -0.47)
			(stroke
				(width 0.05)
				(type default)
			)
			(fill no)
			(layer "B.CrtYd")
		)
		(fp_line
			(start -0.494 -0.248)
			(end -0.494 0.25)
			(stroke
				(width 0.15)
				(type solid)
			)
			(layer "B.Fab")
		)
		(fp_line
			(start -0.494 0.25)
			(end 0.504 0.25)
			(stroke
				(width 0.15)
				(type solid)
			)
			(layer "B.Fab")
		)
		(fp_line
			(start 0.504 -0.248)
			(end -0.494 -0.248)
			(stroke
				(width 0.15)
				(type solid)
			)
			(layer "B.Fab")
		)
		(fp_line
			(start 0.504 0.25)
			(end 0.504 -0.248)
			(stroke
				(width 0.15)
				(type solid)
			)
			(layer "B.Fab")
		)
		(fp_text user "Author: Antmicro"
			(at -0.939 -3.399 180)
			(layer "B.Fab")
			(effects
				(font
					(size 0.7 0.7)
					(thickness 0.15)
				)
				(justify left bottom mirror)
			)
		)
		(fp_text user "${REFERENCE}"
			(at -0.939 -4.599 180)
			(layer "B.Fab")
			(effects
				(font
					(size 0.7 0.7)
					(thickness 0.15)
				)
				(justify left bottom mirror)
			)
		)
		(fp_text user "License: Apache-2.0"
			(at -0.939 -5.799 180)
			(layer "B.Fab")
			(effects
				(font
					(size 0.7 0.7)
					(thickness 0.15)
				)
				(justify left bottom mirror)
			)
		)
		(pad "1" smd roundrect
			(at -0.48 0)
			(size 0.59 0.64)
			(layers "B.Cu" "B.Mask" "B.Paste")
			(roundrect_rratio 0.25)
			(net 23 "GND")
			(pintype "passive")
		)
		(pad "2" smd roundrect
			(at 0.48 0)
			(size 0.59 0.64)
			(layers "B.Cu" "B.Mask" "B.Paste")
			(roundrect_rratio 0.25)
			(net 215 "/USB-C connector/VBUS")
			(pintype "passive")
		)
	)
	(footprint "antmicro-footprints:C_0402_1005Metric"
		(layer "B.Cu")
		(at 151.181867 76.260117 180)
		(descr "Capacitor SMD 0402")
		(tags "capacitor SMD 0402")
		(property "Reference" "C211"
			(at -20.368136 -9.464883 0)
			(layer "B.SilkS")
			(effects
				(font
					(size 0.7 0.7)
					(thickness 0.15)
				)
				(justify mirror)
			)
		)
		(property "Value" "C_1u_25V_0402"
			(at -1.022927 -2.155213 0)
			(layer "B.Fab")
			(effects
				(font
					(size 0.7 0.7)
					(thickness 0.15)
				)
				(justify left bottom mirror)
			)
		)
		(property "Datasheet" "https://www.murata.com/products/productdetail?partno=GRM155R61E105KE11%23"
			(at 0 0 0)
			(layer "B.Fab")
			(hide yes)
			(effects
				(font
					(size 1.27 1.27)
					(thickness 0.15)
				)
				(justify mirror)
			)
		)
		(property "Description" "SMD Multilayer Ceramic Capacitor, 1 µF, 25 V, 0402 [1005 Metric], ± 10%, X5R, GRM Series"
			(at 0 0 0)
			(layer "B.Fab")
			(hide yes)
			(effects
				(font
					(size 1.27 1.27)
					(thickness 0.15)
				)
				(justify mirror)
			)
		)
		(property "MPN" "GRM155R61E105KE11J"
			(at 0 0 180)
			(unlocked yes)
			(layer "B.Fab")
			(hide yes)
			(effects
				(font
					(size 1 1)
					(thickness 0.15)
				)
				(justify mirror)
			)
		)
		(property "Manufacturer" "Murata"
			(at 0 0 180)
			(unlocked yes)
			(layer "B.Fab")
			(hide yes)
			(effects
				(font
					(size 1 1)
					(thickness 0.15)
				)
				(justify mirror)
			)
		)
		(property "License" "Apache-2.0"
			(at 0 0 180)
			(unlocked yes)
			(layer "B.Fab")
			(hide yes)
			(effects
				(font
					(size 1 1)
					(thickness 0.15)
				)
				(justify mirror)
			)
		)
		(property "Author" "Antmicro"
			(at 0 0 180)
			(unlocked yes)
			(layer "B.Fab")
			(hide yes)
			(effects
				(font
					(size 1 1)
					(thickness 0.15)
				)
				(justify mirror)
			)
		)
		(property "Val" "1u"
			(at 0 0 180)
			(unlocked yes)
			(layer "B.Fab")
			(hide yes)
			(effects
				(font
					(size 1 1)
					(thickness 0.15)
				)
				(justify mirror)
			)
		)
		(property "Voltage" "25V"
			(at 0 0 180)
			(unlocked yes)
			(layer "B.Fab")
			(hide yes)
			(effects
				(font
					(size 1 1)
					(thickness 0.15)
				)
				(justify mirror)
			)
		)
		(property "Dielectric" "X5R"
			(at 0 0 180)
			(unlocked yes)
			(layer "B.Fab")
			(hide yes)
			(effects
				(font
					(size 1 1)
					(thickness 0.15)
				)
				(justify mirror)
			)
		)
		(sheetname "/X710-AT2 power/")
		(sheetfile "x710-at2-power.kicad_sch")
		(attr smd)
		(fp_rect
			(start -0.925 0.47)
			(end 0.925 -0.47)
			(stroke
				(width 0.05)
				(type default)
			)
			(fill no)
			(layer "B.CrtYd")
		)
		(fp_line
			(start 0.504 0.25)
			(end 0.504 -0.248)
			(stroke
				(width 0.15)
				(type solid)
			)
			(layer "B.Fab")
		)
		(fp_line
			(start 0.504 -0.248)
			(end -0.494 -0.248)
			(stroke
				(width 0.15)
				(type solid)
			)
			(layer "B.Fab")
		)
		(fp_line
			(start -0.494 0.25)
			(end 0.504 0.25)
			(stroke
				(width 0.15)
				(type solid)
			)
			(layer "B.Fab")
		)
		(fp_line
			(start -0.494 -0.248)
			(end -0.494 0.25)
			(stroke
				(width 0.15)
				(type solid)
			)
			(layer "B.Fab")
		)
		(fp_text user "Author: Antmicro"
			(at -0.939 -3.399 0)
			(layer "B.Fab")
			(effects
				(font
					(size 0.7 0.7)
					(thickness 0.15)
				)
				(justify left bottom mirror)
			)
		)
		(fp_text user "License: Apache-2.0"
			(at -0.939 -5.799 0)
			(layer "B.Fab")
			(effects
				(font
					(size 0.7 0.7)
					(thickness 0.15)
				)
				(justify left bottom mirror)
			)
		)
		(fp_text user "${REFERENCE}"
			(at -0.939 -4.599 0)
			(layer "B.Fab")
			(effects
				(font
					(size 0.7 0.7)
					(thickness 0.15)
				)
				(justify left bottom mirror)
			)
		)
		(pad "1" smd roundrect
			(at -0.48 0 180)
			(size 0.59 0.64)
			(layers "B.Cu" "B.Mask" "B.Paste")
			(roundrect_rratio 0.25)
			(net 23 "GND")
			(pintype "passive")
		)
		(pad "2" smd roundrect
			(at 0.48 0 180)
			(size 0.59 0.64)
			(layers "B.Cu" "B.Mask" "B.Paste")
			(roundrect_rratio 0.25)
			(net 1 "VCCA")
			(pintype "passive")
		)
	)
	(footprint "antmicro-footprints:TP_SMD_0.75mm"
		(layer "B.Cu")
		(at 183.75 83.25 90)
		(property "Reference" "TP18"
			(at -12 0.75 270)
			(layer "B.SilkS")
			(effects
				(font
					(size 0.7 0.7)
					(thickness 0.15)
				)
				(justify left bottom mirror)
			)
		)
		(property "Value" "TP_0.75mm_SMD"
			(at 0 -1.2 270)
			(layer "B.Fab")
			(effects
				(font
					(size 0.7 0.7)
					(thickness 0.15)
				)
				(justify left bottom mirror)
			)
		)
		(property "Description" "SMT test point"
			(at 0 0 270)
			(layer "B.Fab")
			(hide yes)
			(effects
				(font
					(size 1.27 1.27)
					(thickness 0.15)
				)
				(justify mirror)
			)
		)
		(property "MPN" ""
			(at 0 0 90)
			(unlocked yes)
			(layer "B.Fab")
			(hide yes)
			(effects
				(font
					(size 1 1)
					(thickness 0.15)
				)
				(justify mirror)
			)
		)
		(property "Manufacturer" ""
			(at 0 0 90)
			(unlocked yes)
			(layer "B.Fab")
			(hide yes)
			(effects
				(font
					(size 1 1)
					(thickness 0.15)
				)
				(justify mirror)
			)
		)
		(property "Author" "Antmicro"
			(at 0 0 90)
			(unlocked yes)
			(layer "B.Fab")
			(hide yes)
			(effects
				(font
					(size 1 1)
					(thickness 0.15)
				)
				(justify mirror)
			)
		)
		(property "License" "Apache-2.0"
			(at 0 0 90)
			(unlocked yes)
			(layer "B.Fab")
			(hide yes)
			(effects
				(font
					(size 1 1)
					(thickness 0.15)
				)
				(justify mirror)
			)
		)
		(sheetname "/X710 DCDC converters/")
		(sheetfile "DCDC_converters_X710.kicad_sch")
		(attr exclude_from_pos_files exclude_from_bom)
		(fp_circle
			(center 0 0)
			(end 0.475 0)
			(stroke
				(width 0.05)
				(type default)
			)
			(fill no)
			(layer "B.CrtYd")
		)
		(fp_text user "${REFERENCE}"
			(at -0.4 -2.7 270)
			(layer "B.Fab")
			(effects
				(font
					(size 0.7 0.7)
					(thickness 0.15)
				)
				(justify left bottom mirror)
			)
		)
		(fp_text user "License: Apache-2.0"
			(at -0.4 -5.101 270)
			(layer "B.Fab")
			(effects
				(font
					(size 0.7 0.7)
					(thickness 0.15)
				)
				(justify left bottom mirror)
			)
		)
		(fp_text user "Author: Antmicro"
			(at -0.4 -3.901 270)
			(layer "B.Fab")
			(effects
				(font
					(size 0.7 0.7)
					(thickness 0.15)
				)
				(justify left bottom mirror)
			)
		)
		(pad "1" smd circle
			(at 0 0 90)
			(size 0.75 0.75)
			(layers "B.Cu" "B.Mask")
			(net 136 "+1V0")
			(pinfunction "1")
			(pintype "passive")
		)
	)
	(footprint "antmicro-footprints:R_0402_1005Metric"
		(layer "B.Cu")
		(at 140.600001 116.124999)
		(descr "Resistor SMD 0402")
		(tags "resistor SMD 0402")
		(property "Reference" "R35"
			(at 19.525001 -7.450001 180)
			(layer "B.SilkS")
			(effects
				(font
					(size 0.7 0.7)
					(thickness 0.15)
				)
				(justify mirror)
			)
		)
		(property "Value" "R_2k2_0402"
			(at -1.011843 -1.772047 180)
			(layer "B.Fab")
			(effects
				(font
					(size 0.7 0.7)
					(thickness 0.15)
				)
				(justify left bottom mirror)
			)
		)
		(property "Datasheet" "https://www.bourns.com/docs/product-datasheets/cr.pdf"
			(at 0 0 180)
			(layer "B.Fab")
			(hide yes)
			(effects
				(font
					(size 1.27 1.27)
					(thickness 0.15)
				)
				(justify mirror)
			)
		)
		(property "Description" "SMD Chip Resistor, 2.2 kohm, ± 1%, 62.5 mW, 0402 [1005 Metric], Thick Film, General Purpose"
			(at 0 0 180)
			(layer "B.Fab")
			(hide yes)
			(effects
				(font
					(size 1.27 1.27)
					(thickness 0.15)
				)
				(justify mirror)
			)
		)
		(property "MPN" "CR0402-FX-2201GLF"
			(at 0 0 0)
			(unlocked yes)
			(layer "B.Fab")
			(hide yes)
			(effects
				(font
					(size 1 1)
					(thickness 0.15)
				)
				(justify mirror)
			)
		)
		(property "Manufacturer" "Bourns"
			(at 0 0 0)
			(unlocked yes)
			(layer "B.Fab")
			(hide yes)
			(effects
				(font
					(size 1 1)
					(thickness 0.15)
				)
				(justify mirror)
			)
		)
		(property "License" "Apache-2.0"
			(at 0 0 0)
			(unlocked yes)
			(layer "B.Fab")
			(hide yes)
			(effects
				(font
					(size 1 1)
					(thickness 0.15)
				)
				(justify mirror)
			)
		)
		(property "Val" "2k2"
			(at 0 0 0)
			(unlocked yes)
			(layer "B.Fab")
			(hide yes)
			(effects
				(font
					(size 1 1)
					(thickness 0.15)
				)
				(justify mirror)
			)
		)
		(property "Tolerance" "1%"
			(at 0 0 0)
			(unlocked yes)
			(layer "B.Fab")
			(hide yes)
			(effects
				(font
					(size 1 1)
					(thickness 0.15)
				)
				(justify mirror)
			)
		)
		(property "Author" "Antmicro"
			(at 0 0 0)
			(unlocked yes)
			(layer "B.Fab")
			(hide yes)
			(effects
				(font
					(size 1 1)
					(thickness 0.15)
				)
				(justify mirror)
			)
		)
		(sheetname "/TB Controller/")
		(sheetfile "tb.kicad_sch")
		(attr smd)
		(fp_rect
			(start -0.925 0.47)
			(end 0.925 -0.47)
			(stroke
				(width 0.05)
				(type default)
			)
			(fill no)
			(layer "B.CrtYd")
		)
		(fp_rect
			(start -0.5 0.25)
			(end 0.5 -0.25)
			(stroke
				(width 0.15)
				(type solid)
			)
			(fill no)
			(layer "B.Fab")
		)
		(fp_text user "Author: Antmicro"
			(at -0.95 -4.169 180)
			(layer "B.Fab")
			(effects
				(font
					(size 0.7 0.7)
					(thickness 0.15)
				)
				(justify left bottom mirror)
			)
		)
		(fp_text user "${REFERENCE}"
			(at -0.95 -3.168 180)
			(layer "B.Fab")
			(effects
				(font
					(size 0.7 0.7)
					(thickness 0.15)
				)
				(justify left bottom mirror)
			)
		)
		(fp_text user "License: Apache-2.0"
			(at -0.95 -5.169 180)
			(layer "B.Fab")
			(effects
				(font
					(size 0.7 0.7)
					(thickness 0.15)
				)
				(justify left bottom mirror)
			)
		)
		(pad "1" smd roundrect
			(at -0.48 0)
			(size 0.59 0.64)
			(layers "B.Cu" "B.Mask" "B.Paste")
			(roundrect_rratio 0.25)
			(net 23 "GND")
			(pintype "passive")
		)
		(pad "2" smd roundrect
			(at 0.48 0)
			(size 0.59 0.64)
			(layers "B.Cu" "B.Mask" "B.Paste")
			(roundrect_rratio 0.25)
			(net 218 "Net-(U4C-DPSNK0_DDC_CLK)")
			(pintype "passive")
		)
	)
	(footprint "antmicro-footprints:R_0402_1005Metric"
		(layer "B.Cu")
		(at 127.8 144.4 90)
		(descr "Resistor SMD 0402")
		(tags "resistor SMD 0402")
		(property "Reference" "R30"
			(at 1.15 2.45 270)
			(layer "B.SilkS")
			(effects
				(font
					(size 0.7 0.7)
					(thickness 0.15)
				)
				(justify left bottom mirror)
			)
		)
		(property "Value" "R_5k1_0402"
			(at -1.011843 -1.772047 270)
			(layer "B.Fab")
			(effects
				(font
					(size 0.7 0.7)
					(thickness 0.15)
				)
				(justify left bottom mirror)
			)
		)
		(property "Datasheet" "https://www.bourns.com/docs/product-datasheets/cr.pdf"
			(at 0 0 270)
			(layer "B.Fab")
			(hide yes)
			(effects
				(font
					(size 1.27 1.27)
					(thickness 0.15)
				)
				(justify mirror)
			)
		)
		(property "Description" "SMD Chip Resistor, 5.1 kohm, ± 1%, 63 mW, 0402 [1005 Metric], Thick Film, General Purpose"
			(at 0 0 270)
			(layer "B.Fab")
			(hide yes)
			(effects
				(font
					(size 1.27 1.27)
					(thickness 0.15)
				)
				(justify mirror)
			)
		)
		(property "MPN" "CR0402-FX-5101GLF"
			(at 0 0 90)
			(unlocked yes)
			(layer "B.Fab")
			(hide yes)
			(effects
				(font
					(size 1 1)
					(thickness 0.15)
				)
				(justify mirror)
			)
		)
		(property "Manufacturer" "Bourns"
			(at 0 0 90)
			(unlocked yes)
			(layer "B.Fab")
			(hide yes)
			(effects
				(font
					(size 1 1)
					(thickness 0.15)
				)
				(justify mirror)
			)
		)
		(property "License" "Apache-2.0"
			(at 0 0 90)
			(unlocked yes)
			(layer "B.Fab")
			(hide yes)
			(effects
				(font
					(size 1 1)
					(thickness 0.15)
				)
				(justify mirror)
			)
		)
		(property "Val" "5k1"
			(at 0 0 90)
			(unlocked yes)
			(layer "B.Fab")
			(hide yes)
			(effects
				(font
					(size 1 1)
					(thickness 0.15)
				)
				(justify mirror)
			)
		)
		(property "Tolerance" "1%"
			(at 0 0 90)
			(unlocked yes)
			(layer "B.Fab")
			(hide yes)
			(effects
				(font
					(size 1 1)
					(thickness 0.15)
				)
				(justify mirror)
			)
		)
		(property "Author" "Antmicro"
			(at 0 0 90)
			(unlocked yes)
			(layer "B.Fab")
			(hide yes)
			(effects
				(font
					(size 1 1)
					(thickness 0.15)
				)
				(justify mirror)
			)
		)
		(sheetname "/PD and TB DC-DC/")
		(sheetfile "PD_and_TB_DC_DC.kicad_sch")
		(attr smd)
		(fp_rect
			(start -0.925 0.47)
			(end 0.925 -0.47)
			(stroke
				(width 0.05)
				(type default)
			)
			(fill no)
			(layer "B.CrtYd")
		)
		(fp_rect
			(start -0.5 0.25)
			(end 0.5 -0.25)
			(stroke
				(width 0.15)
				(type solid)
			)
			(fill no)
			(layer "B.Fab")
		)
		(fp_text user "Author: Antmicro"
			(at -0.95 -4.169 270)
			(layer "B.Fab")
			(effects
				(font
					(size 0.7 0.7)
					(thickness 0.15)
				)
				(justify left bottom mirror)
			)
		)
		(fp_text user "License: Apache-2.0"
			(at -0.95 -5.169 270)
			(layer "B.Fab")
			(effects
				(font
					(size 0.7 0.7)
					(thickness 0.15)
				)
				(justify left bottom mirror)
			)
		)
		(fp_text user "${REFERENCE}"
			(at -0.95 -3.168 270)
			(layer "B.Fab")
			(effects
				(font
					(size 0.7 0.7)
					(thickness 0.15)
				)
				(justify left bottom mirror)
			)
		)
		(pad "1" smd roundrect
			(at -0.48 0 90)
			(size 0.59 0.64)
			(layers "B.Cu" "B.Mask" "B.Paste")
			(roundrect_rratio 0.25)
			(net 23 "GND")
			(pintype "passive")
		)
		(pad "2" smd roundrect
			(at 0.48 0 90)
			(size 0.59 0.64)
			(layers "B.Cu" "B.Mask" "B.Paste")
			(roundrect_rratio 0.25)
			(net 305 "/PD and TB DC-DC/USB3.CC2")
			(pintype "passive")
		)
	)
	(footprint "antmicro-footprints:R_0402_1005Metric"
		(layer "B.Cu")
		(at 137.5 127.6)
		(descr "Resistor SMD 0402")
		(tags "resistor SMD 0402")
		(property "Reference" "R51"
			(at 19.525001 -7.450001 180)
			(layer "B.SilkS")
			(effects
				(font
					(size 0.7 0.7)
					(thickness 0.15)
				)
				(justify mirror)
			)
		)
		(property "Value" "R_10k_0402"
			(at -1.011843 -1.772047 180)
			(layer "B.Fab")
			(effects
				(font
					(size 0.7 0.7)
					(thickness 0.15)
				)
				(justify left bottom mirror)
			)
		)
		(property "Datasheet" "https://www.bourns.com/docs/product-datasheets/cr.pdf"
			(at 0 0 180)
			(layer "B.Fab")
			(hide yes)
			(effects
				(font
					(size 1.27 1.27)
					(thickness 0.15)
				)
				(justify mirror)
			)
		)
		(property "Description" "SMD Chip Resistor, 10 kohm, ± 1%, 62.5 mW, 0402 [1005 Metric], Thick Film, General Purpose"
			(at 0 0 180)
			(layer "B.Fab")
			(hide yes)
			(effects
				(font
					(size 1.27 1.27)
					(thickness 0.15)
				)
				(justify mirror)
			)
		)
		(property "MPN" "CR0402-FX-1002GLF"
			(at 0 0 0)
			(unlocked yes)
			(layer "B.Fab")
			(hide yes)
			(effects
				(font
					(size 1 1)
					(thickness 0.15)
				)
				(justify mirror)
			)
		)
		(property "Manufacturer" "Bourns"
			(at 0 0 0)
			(unlocked yes)
			(layer "B.Fab")
			(hide yes)
			(effects
				(font
					(size 1 1)
					(thickness 0.15)
				)
				(justify mirror)
			)
		)
		(property "License" "Apache-2.0"
			(at 0 0 0)
			(unlocked yes)
			(layer "B.Fab")
			(hide yes)
			(effects
				(font
					(size 1 1)
					(thickness 0.15)
				)
				(justify mirror)
			)
		)
		(property "Val" "10k"
			(at 0 0 0)
			(unlocked yes)
			(layer "B.Fab")
			(hide yes)
			(effects
				(font
					(size 1 1)
					(thickness 0.15)
				)
				(justify mirror)
			)
		)
		(property "Tolerance" "1%"
			(at 0 0 0)
			(unlocked yes)
			(layer "B.Fab")
			(hide yes)
			(effects
				(font
					(size 1 1)
					(thickness 0.15)
				)
				(justify mirror)
			)
		)
		(property "Author" "Antmicro"
			(at 0 0 0)
			(unlocked yes)
			(layer "B.Fab")
			(hide yes)
			(effects
				(font
					(size 1 1)
					(thickness 0.15)
				)
				(justify mirror)
			)
		)
		(sheetname "/TB Controller/")
		(sheetfile "tb.kicad_sch")
		(attr smd)
		(fp_rect
			(start -0.925 0.47)
			(end 0.925 -0.47)
			(stroke
				(width 0.05)
				(type default)
			)
			(fill no)
			(layer "B.CrtYd")
		)
		(fp_rect
			(start -0.5 0.25)
			(end 0.5 -0.25)
			(stroke
				(width 0.15)
				(type solid)
			)
			(fill no)
			(layer "B.Fab")
		)
		(fp_text user "License: Apache-2.0"
			(at -0.95 -5.169 180)
			(layer "B.Fab")
			(effects
				(font
					(size 0.7 0.7)
					(thickness 0.15)
				)
				(justify left bottom mirror)
			)
		)
		(fp_text user "${REFERENCE}"
			(at -0.95 -3.168 180)
			(layer "B.Fab")
			(effects
				(font
					(size 0.7 0.7)
					(thickness 0.15)
				)
				(justify left bottom mirror)
			)
		)
		(fp_text user "Author: Antmicro"
			(at -0.95 -4.169 180)
			(layer "B.Fab")
			(effects
				(font
					(size 0.7 0.7)
					(thickness 0.15)
				)
				(justify left bottom mirror)
			)
		)
		(pad "1" smd roundrect
			(at -0.48 0)
			(size 0.59 0.64)
			(layers "B.Cu" "B.Mask" "B.Paste")
			(roundrect_rratio 0.25)
			(net 194 "Net-(U4C-POC_GPIO_3)")
			(pintype "passive")
		)
		(pad "2" smd roundrect
			(at 0.48 0)
			(size 0.59 0.64)
			(layers "B.Cu" "B.Mask" "B.Paste")
			(roundrect_rratio 0.25)
			(net 23 "GND")
			(pintype "passive")
		)
	)
	(footprint "antmicro-footprints:R_0402_1005Metric"
		(layer "B.Cu")
		(at 151.181867 75.285117 180)
		(descr "Resistor SMD 0402")
		(tags "resistor SMD 0402")
		(property "Reference" "R124"
			(at -20.368136 -9.464883 0)
			(layer "B.SilkS")
			(effects
				(font
					(size 0.7 0.7)
					(thickness 0.15)
				)
				(justify mirror)
			)
		)
		(property "Value" "R_100R_0402"
			(at -1.011843 -1.772047 0)
			(layer "B.Fab")
			(effects
				(font
					(size 0.7 0.7)
					(thickness 0.15)
				)
				(justify left bottom mirror)
			)
		)
		(property "Datasheet" "https://www.bourns.com/docs/product-datasheets/cr.pdf"
			(at 0 0 0)
			(layer "B.Fab")
			(hide yes)
			(effects
				(font
					(size 1.27 1.27)
					(thickness 0.15)
				)
				(justify mirror)
			)
		)
		(property "Description" "SMD Chip Resistor, 100 ohm, ± 1%, 62.5 mW, 0402 [1005 Metric], Thick Film, General Purpose"
			(at 0 0 0)
			(layer "B.Fab")
			(hide yes)
			(effects
				(font
					(size 1.27 1.27)
					(thickness 0.15)
				)
				(justify mirror)
			)
		)
		(property "MPN" "CR0402-FX-1000GLF"
			(at 0 0 180)
			(unlocked yes)
			(layer "B.Fab")
			(hide yes)
			(effects
				(font
					(size 1 1)
					(thickness 0.15)
				)
				(justify mirror)
			)
		)
		(property "Manufacturer" "Bourns"
			(at 0 0 180)
			(unlocked yes)
			(layer "B.Fab")
			(hide yes)
			(effects
				(font
					(size 1 1)
					(thickness 0.15)
				)
				(justify mirror)
			)
		)
		(property "License" "Apache-2.0"
			(at 0 0 180)
			(unlocked yes)
			(layer "B.Fab")
			(hide yes)
			(effects
				(font
					(size 1 1)
					(thickness 0.15)
				)
				(justify mirror)
			)
		)
		(property "Author" "Antmicro"
			(at 0 0 180)
			(unlocked yes)
			(layer "B.Fab")
			(hide yes)
			(effects
				(font
					(size 1 1)
					(thickness 0.15)
				)
				(justify mirror)
			)
		)
		(property "Val" "100R"
			(at 0 0 180)
			(unlocked yes)
			(layer "B.Fab")
			(hide yes)
			(effects
				(font
					(size 1 1)
					(thickness 0.15)
				)
				(justify mirror)
			)
		)
		(property "Tolerance" "1%"
			(at 0 0 180)
			(unlocked yes)
			(layer "B.Fab")
			(hide yes)
			(effects
				(font
					(size 1 1)
					(thickness 0.15)
				)
				(justify mirror)
			)
		)
		(sheetname "/X710-AT2 RSVD/")
		(sheetfile "x710-at2-rsvd.kicad_sch")
		(attr smd)
		(fp_rect
			(start -0.925 0.47)
			(end 0.925 -0.47)
			(stroke
				(width 0.05)
				(type default)
			)
			(fill no)
			(layer "B.CrtYd")
		)
		(fp_rect
			(start -0.5 0.25)
			(end 0.5 -0.25)
			(stroke
				(width 0.15)
				(type solid)
			)
			(fill no)
			(layer "B.Fab")
		)
		(fp_text user "License: Apache-2.0"
			(at -0.95 -5.169 0)
			(layer "B.Fab")
			(effects
				(font
					(size 0.7 0.7)
					(thickness 0.15)
				)
				(justify left bottom mirror)
			)
		)
		(fp_text user "${REFERENCE}"
			(at -0.95 -3.168 0)
			(layer "B.Fab")
			(effects
				(font
					(size 0.7 0.7)
					(thickness 0.15)
				)
				(justify left bottom mirror)
			)
		)
		(fp_text user "Author: Antmicro"
			(at -0.95 -4.169 0)
			(layer "B.Fab")
			(effects
				(font
					(size 0.7 0.7)
					(thickness 0.15)
				)
				(justify left bottom mirror)
			)
		)
		(pad "1" smd roundrect
			(at -0.48 0 180)
			(size 0.59 0.64)
			(layers "B.Cu" "B.Mask" "B.Paste")
			(roundrect_rratio 0.25)
			(net 23 "GND")
			(pintype "passive")
		)
		(pad "2" smd roundrect
			(at 0.48 0 180)
			(size 0.59 0.64)
			(layers "B.Cu" "B.Mask" "B.Paste")
			(roundrect_rratio 0.25)
			(net 95 "/X710-AT2 RSVD/RSVDN9_VSS")
			(pintype "passive")
		)
	)
	(footprint "antmicro-footprints:R_0402_1005Metric"
		(layer "B.Cu")
		(at 136.5 125.15)
		(descr "Resistor SMD 0402")
		(tags "resistor SMD 0402")
		(property "Reference" "R52"
			(at 19.525001 -7.450001 180)
			(layer "B.SilkS")
			(effects
				(font
					(size 0.7 0.7)
					(thickness 0.15)
				)
				(justify mirror)
			)
		)
		(property "Value" "R_100k_0402"
			(at -1.011843 -1.772047 180)
			(layer "B.Fab")
			(effects
				(font
					(size 0.7 0.7)
					(thickness 0.15)
				)
				(justify left bottom mirror)
			)
		)
		(property "Datasheet" "https://www.bourns.com/docs/product-datasheets/cr.pdf"
			(at 0 0 180)
			(layer "B.Fab")
			(hide yes)
			(effects
				(font
					(size 1.27 1.27)
					(thickness 0.15)
				)
				(justify mirror)
			)
		)
		(property "Description" "SMD Chip Resistor, 100 kohm, ± 1%, 62.5 mW, 0402 [1005 Metric], Thick Film, General Purpose"
			(at 0 0 180)
			(layer "B.Fab")
			(hide yes)
			(effects
				(font
					(size 1.27 1.27)
					(thickness 0.15)
				)
				(justify mirror)
			)
		)
		(property "MPN" "CR0402-FX-1003GLF"
			(at 0 0 0)
			(unlocked yes)
			(layer "B.Fab")
			(hide yes)
			(effects
				(font
					(size 1 1)
					(thickness 0.15)
				)
				(justify mirror)
			)
		)
		(property "Manufacturer" "Bourns"
			(at 0 0 0)
			(unlocked yes)
			(layer "B.Fab")
			(hide yes)
			(effects
				(font
					(size 1 1)
					(thickness 0.15)
				)
				(justify mirror)
			)
		)
		(property "License" "Apache-2.0"
			(at 0 0 0)
			(unlocked yes)
			(layer "B.Fab")
			(hide yes)
			(effects
				(font
					(size 1 1)
					(thickness 0.15)
				)
				(justify mirror)
			)
		)
		(property "Val" "100k"
			(at 0 0 0)
			(unlocked yes)
			(layer "B.Fab")
			(hide yes)
			(effects
				(font
					(size 1 1)
					(thickness 0.15)
				)
				(justify mirror)
			)
		)
		(property "Tolerance" "1%"
			(at 0 0 0)
			(unlocked yes)
			(layer "B.Fab")
			(hide yes)
			(effects
				(font
					(size 1 1)
					(thickness 0.15)
				)
				(justify mirror)
			)
		)
		(property "Author" "Antmicro"
			(at 0 0 0)
			(unlocked yes)
			(layer "B.Fab")
			(hide yes)
			(effects
				(font
					(size 1 1)
					(thickness 0.15)
				)
				(justify mirror)
			)
		)
		(sheetname "/TB Controller/")
		(sheetfile "tb.kicad_sch")
		(attr smd)
		(fp_rect
			(start -0.925 0.47)
			(end 0.925 -0.47)
			(stroke
				(width 0.05)
				(type default)
			)
			(fill no)
			(layer "B.CrtYd")
		)
		(fp_rect
			(start -0.5 0.25)
			(end 0.5 -0.25)
			(stroke
				(width 0.15)
				(type solid)
			)
			(fill no)
			(layer "B.Fab")
		)
		(fp_text user "${REFERENCE}"
			(at -0.95 -3.168 180)
			(layer "B.Fab")
			(effects
				(font
					(size 0.7 0.7)
					(thickness 0.15)
				)
				(justify left bottom mirror)
			)
		)
		(fp_text user "License: Apache-2.0"
			(at -0.95 -5.169 180)
			(layer "B.Fab")
			(effects
				(font
					(size 0.7 0.7)
					(thickness 0.15)
				)
				(justify left bottom mirror)
			)
		)
		(fp_text user "Author: Antmicro"
			(at -0.95 -4.169 180)
			(layer "B.Fab")
			(effects
				(font
					(size 0.7 0.7)
					(thickness 0.15)
				)
				(justify left bottom mirror)
			)
		)
		(pad "1" smd roundrect
			(at -0.48 0)
			(size 0.59 0.64)
			(layers "B.Cu" "B.Mask" "B.Paste")
			(roundrect_rratio 0.25)
			(net 235 "Net-(U4C-POC_GPIO_5)")
			(pintype "passive")
		)
		(pad "2" smd roundrect
			(at 0.48 0)
			(size 0.59 0.64)
			(layers "B.Cu" "B.Mask" "B.Paste")
			(roundrect_rratio 0.25)
			(net 23 "GND")
			(pintype "passive")
		)
	)
	(footprint "antmicro-footprints:C_0402_1005Metric"
		(layer "B.Cu")
		(at 128.5 122 90)
		(descr "Capacitor SMD 0402")
		(tags "capacitor SMD 0402")
		(property "Reference" "C52"
			(at 7.700002 21.900002 270)
			(layer "B.SilkS")
			(effects
				(font
					(size 0.7 0.7)
					(thickness 0.15)
				)
				(justify mirror)
			)
		)
		(property "Value" "C_1u_0402"
			(at -1.022927 -2.155213 270)
			(layer "B.Fab")
			(effects
				(font
					(size 0.7 0.7)
					(thickness 0.15)
				)
				(justify left bottom mirror)
			)
		)
		(property "Datasheet" "https://product.tdk.com/en/search/capacitor/ceramic/mlcc/info?part_no=C1005X6S1A105K050BC"
			(at 0 0 270)
			(layer "B.Fab")
			(hide yes)
			(effects
				(font
					(size 1.27 1.27)
					(thickness 0.15)
				)
				(justify mirror)
			)
		)
		(property "Description" "SMD Multilayer Ceramic Capacitor, 1 µF, 10 V, 0402 [1005 Metric], ± 10%, X6S, C"
			(at 0 0 270)
			(layer "B.Fab")
			(hide yes)
			(effects
				(font
					(size 1.27 1.27)
					(thickness 0.15)
				)
				(justify mirror)
			)
		)
		(property "MPN" "C1005X6S1A105K050BC"
			(at 0 0 90)
			(unlocked yes)
			(layer "B.Fab")
			(hide yes)
			(effects
				(font
					(size 1 1)
					(thickness 0.15)
				)
				(justify mirror)
			)
		)
		(property "Manufacturer" "TDK"
			(at 0 0 90)
			(unlocked yes)
			(layer "B.Fab")
			(hide yes)
			(effects
				(font
					(size 1 1)
					(thickness 0.15)
				)
				(justify mirror)
			)
		)
		(property "License" "Apache-2.0"
			(at 0 0 90)
			(unlocked yes)
			(layer "B.Fab")
			(hide yes)
			(effects
				(font
					(size 1 1)
					(thickness 0.15)
				)
				(justify mirror)
			)
		)
		(property "Val" "1u"
			(at 0 0 90)
			(unlocked yes)
			(layer "B.Fab")
			(hide yes)
			(effects
				(font
					(size 1 1)
					(thickness 0.15)
				)
				(justify mirror)
			)
		)
		(property "Voltage" ""
			(at 0 0 90)
			(unlocked yes)
			(layer "B.Fab")
			(hide yes)
			(effects
				(font
					(size 1 1)
					(thickness 0.15)
				)
				(justify mirror)
			)
		)
		(property "Dielectric" ""
			(at 0 0 90)
			(unlocked yes)
			(layer "B.Fab")
			(hide yes)
			(effects
				(font
					(size 1 1)
					(thickness 0.15)
				)
				(justify mirror)
			)
		)
		(property "Author" "Antmicro"
			(at 0 0 90)
			(unlocked yes)
			(layer "B.Fab")
			(hide yes)
			(effects
				(font
					(size 1 1)
					(thickness 0.15)
				)
				(justify mirror)
			)
		)
		(sheetname "/TB Controller - Power/")
		(sheetfile "tb-power.kicad_sch")
		(attr smd)
		(fp_rect
			(start -0.925 0.47)
			(end 0.925 -0.47)
			(stroke
				(width 0.05)
				(type default)
			)
			(fill no)
			(layer "B.CrtYd")
		)
		(fp_line
			(start 0.504 -0.248)
			(end -0.494 -0.248)
			(stroke
				(width 0.15)
				(type solid)
			)
			(layer "B.Fab")
		)
		(fp_line
			(start -0.494 -0.248)
			(end -0.494 0.25)
			(stroke
				(width 0.15)
				(type solid)
			)
			(layer "B.Fab")
		)
		(fp_line
			(start 0.504 0.25)
			(end 0.504 -0.248)
			(stroke
				(width 0.15)
				(type solid)
			)
			(layer "B.Fab")
		)
		(fp_line
			(start -0.494 0.25)
			(end 0.504 0.25)
			(stroke
				(width 0.15)
				(type solid)
			)
			(layer "B.Fab")
		)
		(fp_text user "License: Apache-2.0"
			(at -0.939 -5.799 270)
			(layer "B.Fab")
			(effects
				(font
					(size 0.7 0.7)
					(thickness 0.15)
				)
				(justify left bottom mirror)
			)
		)
		(fp_text user "${REFERENCE}"
			(at -0.939 -4.599 270)
			(layer "B.Fab")
			(effects
				(font
					(size 0.7 0.7)
					(thickness 0.15)
				)
				(justify left bottom mirror)
			)
		)
		(fp_text user "Author: Antmicro"
			(at -0.939 -3.399 270)
			(layer "B.Fab")
			(effects
				(font
					(size 0.7 0.7)
					(thickness 0.15)
				)
				(justify left bottom mirror)
			)
		)
		(pad "1" smd roundrect
			(at -0.48 0 90)
			(size 0.59 0.64)
			(layers "B.Cu" "B.Mask" "B.Paste")
			(roundrect_rratio 0.25)
			(net 23 "GND")
			(pintype "passive")
		)
		(pad "2" smd roundrect
			(at 0.48 0 90)
			(size 0.59 0.64)
			(layers "B.Cu" "B.Mask" "B.Paste")
			(roundrect_rratio 0.25)
			(net 402 "Net-(C52-Pad2)")
			(pintype "passive")
		)
	)
	(footprint "antmicro-footprints:C_0402_1005Metric"
		(layer "B.Cu")
		(at 127.049999 127.350001)
		(descr "Capacitor SMD 0402")
		(tags "capacitor SMD 0402")
		(property "Reference" "C88"
			(at 21.900002 -7.700002 180)
			(layer "B.SilkS")
			(effects
				(font
					(size 0.7 0.7)
					(thickness 0.15)
				)
				(justify mirror)
			)
		)
		(property "Value" "C_1u_0402"
			(at -1.022927 -2.155213 180)
			(layer "B.Fab")
			(effects
				(font
					(size 0.7 0.7)
					(thickness 0.15)
				)
				(justify left bottom mirror)
			)
		)
		(property "Datasheet" "https://product.tdk.com/en/search/capacitor/ceramic/mlcc/info?part_no=C1005X6S1A105K050BC"
			(at 0 0 180)
			(layer "B.Fab")
			(hide yes)
			(effects
				(font
					(size 1.27 1.27)
					(thickness 0.15)
				)
				(justify mirror)
			)
		)
		(property "Description" "SMD Multilayer Ceramic Capacitor, 1 µF, 10 V, 0402 [1005 Metric], ± 10%, X6S, C"
			(at 0 0 180)
			(layer "B.Fab")
			(hide yes)
			(effects
				(font
					(size 1.27 1.27)
					(thickness 0.15)
				)
				(justify mirror)
			)
		)
		(property "MPN" "C1005X6S1A105K050BC"
			(at 0 0 0)
			(unlocked yes)
			(layer "B.Fab")
			(hide yes)
			(effects
				(font
					(size 1 1)
					(thickness 0.15)
				)
				(justify mirror)
			)
		)
		(property "Manufacturer" "TDK"
			(at 0 0 0)
			(unlocked yes)
			(layer "B.Fab")
			(hide yes)
			(effects
				(font
					(size 1 1)
					(thickness 0.15)
				)
				(justify mirror)
			)
		)
		(property "License" "Apache-2.0"
			(at 0 0 0)
			(unlocked yes)
			(layer "B.Fab")
			(hide yes)
			(effects
				(font
					(size 1 1)
					(thickness 0.15)
				)
				(justify mirror)
			)
		)
		(property "Val" "1u"
			(at 0 0 0)
			(unlocked yes)
			(layer "B.Fab")
			(hide yes)
			(effects
				(font
					(size 1 1)
					(thickness 0.15)
				)
				(justify mirror)
			)
		)
		(property "Voltage" ""
			(at 0 0 0)
			(unlocked yes)
			(layer "B.Fab")
			(hide yes)
			(effects
				(font
					(size 1 1)
					(thickness 0.15)
				)
				(justify mirror)
			)
		)
		(property "Dielectric" ""
			(at 0 0 0)
			(unlocked yes)
			(layer "B.Fab")
			(hide yes)
			(effects
				(font
					(size 1 1)
					(thickness 0.15)
				)
				(justify mirror)
			)
		)
		(property "Author" "Antmicro"
			(at 0 0 0)
			(unlocked yes)
			(layer "B.Fab")
			(hide yes)
			(effects
				(font
					(size 1 1)
					(thickness 0.15)
				)
				(justify mirror)
			)
		)
		(sheetname "/TB Controller - Power/")
		(sheetfile "tb-power.kicad_sch")
		(attr smd)
		(fp_rect
			(start -0.925 0.47)
			(end 0.925 -0.47)
			(stroke
				(width 0.05)
				(type default)
			)
			(fill no)
			(layer "B.CrtYd")
		)
		(fp_line
			(start -0.494 -0.248)
			(end -0.494 0.25)
			(stroke
				(width 0.15)
				(type solid)
			)
			(layer "B.Fab")
		)
		(fp_line
			(start -0.494 0.25)
			(end 0.504 0.25)
			(stroke
				(width 0.15)
				(type solid)
			)
			(layer "B.Fab")
		)
		(fp_line
			(start 0.504 -0.248)
			(end -0.494 -0.248)
			(stroke
				(width 0.15)
				(type solid)
			)
			(layer "B.Fab")
		)
		(fp_line
			(start 0.504 0.25)
			(end 0.504 -0.248)
			(stroke
				(width 0.15)
				(type solid)
			)
			(layer "B.Fab")
		)
		(fp_text user "License: Apache-2.0"
			(at -0.939 -5.799 180)
			(layer "B.Fab")
			(effects
				(font
					(size 0.7 0.7)
					(thickness 0.15)
				)
				(justify left bottom mirror)
			)
		)
		(fp_text user "${REFERENCE}"
			(at -0.939 -4.599 180)
			(layer "B.Fab")
			(effects
				(font
					(size 0.7 0.7)
					(thickness 0.15)
				)
				(justify left bottom mirror)
			)
		)
		(fp_text user "Author: Antmicro"
			(at -0.939 -3.399 180)
			(layer "B.Fab")
			(effects
				(font
					(size 0.7 0.7)
					(thickness 0.15)
				)
				(justify left bottom mirror)
			)
		)
		(pad "1" smd roundrect
			(at -0.48 0)
			(size 0.59 0.64)
			(layers "B.Cu" "B.Mask" "B.Paste")
			(roundrect_rratio 0.25)
			(net 23 "GND")
			(pintype "passive")
		)
		(pad "2" smd roundrect
			(at 0.48 0)
			(size 0.59 0.64)
			(layers "B.Cu" "B.Mask" "B.Paste")
			(roundrect_rratio 0.25)
			(net 68 "/TB Controller - Power/VCC_0P9")
			(pintype "passive")
		)
	)
	(footprint "antmicro-footprints:R_0402_1005Metric"
		(layer "B.Cu")
		(at 135.840001 135.089997 90)
		(descr "Resistor SMD 0402")
		(tags "resistor SMD 0402")
		(property "Reference" "R19"
			(at 8.339997 19.525001 270)
			(layer "B.SilkS")
			(effects
				(font
					(size 0.7 0.7)
					(thickness 0.15)
				)
				(justify mirror)
			)
		)
		(property "Value" "R_1M_0402"
			(at -1.011843 -1.772047 270)
			(layer "B.Fab")
			(effects
				(font
					(size 0.7 0.7)
					(thickness 0.15)
				)
				(justify left bottom mirror)
			)
		)
		(property "Datasheet" "https://www.bourns.com/docs/product-datasheets/cr.pdf"
			(at 0 0 270)
			(layer "B.Fab")
			(hide yes)
			(effects
				(font
					(size 1.27 1.27)
					(thickness 0.15)
				)
				(justify mirror)
			)
		)
		(property "Description" "SMD Chip Resistor, 1 Mohm, ± 1%, 62.5 mW, 0402 [1005 Metric], Thick Film, General Purpose"
			(at 0 0 270)
			(layer "B.Fab")
			(hide yes)
			(effects
				(font
					(size 1.27 1.27)
					(thickness 0.15)
				)
				(justify mirror)
			)
		)
		(property "MPN" "CR0402-FX-1004GLF"
			(at 0 0 90)
			(unlocked yes)
			(layer "B.Fab")
			(hide yes)
			(effects
				(font
					(size 1 1)
					(thickness 0.15)
				)
				(justify mirror)
			)
		)
		(property "Manufacturer" "Bourns"
			(at 0 0 90)
			(unlocked yes)
			(layer "B.Fab")
			(hide yes)
			(effects
				(font
					(size 1 1)
					(thickness 0.15)
				)
				(justify mirror)
			)
		)
		(property "License" "Apache-2.0"
			(at 0 0 90)
			(unlocked yes)
			(layer "B.Fab")
			(hide yes)
			(effects
				(font
					(size 1 1)
					(thickness 0.15)
				)
				(justify mirror)
			)
		)
		(property "Val" "1M"
			(at 0 0 90)
			(unlocked yes)
			(layer "B.Fab")
			(hide yes)
			(effects
				(font
					(size 1 1)
					(thickness 0.15)
				)
				(justify mirror)
			)
		)
		(property "Tolerance" "1%"
			(at 0 0 90)
			(unlocked yes)
			(layer "B.Fab")
			(hide yes)
			(effects
				(font
					(size 1 1)
					(thickness 0.15)
				)
				(justify mirror)
			)
		)
		(property "Author" "Antmicro"
			(at 0 0 90)
			(unlocked yes)
			(layer "B.Fab")
			(hide yes)
			(effects
				(font
					(size 1 1)
					(thickness 0.15)
				)
				(justify mirror)
			)
		)
		(sheetname "/PD and TB DC-DC/")
		(sheetfile "PD_and_TB_DC_DC.kicad_sch")
		(attr smd)
		(fp_rect
			(start -0.925 0.47)
			(end 0.925 -0.47)
			(stroke
				(width 0.05)
				(type default)
			)
			(fill no)
			(layer "B.CrtYd")
		)
		(fp_rect
			(start -0.5 0.25)
			(end 0.5 -0.25)
			(stroke
				(width 0.15)
				(type solid)
			)
			(fill no)
			(layer "B.Fab")
		)
		(fp_text user "Author: Antmicro"
			(at -0.95 -4.169 270)
			(layer "B.Fab")
			(effects
				(font
					(size 0.7 0.7)
					(thickness 0.15)
				)
				(justify left bottom mirror)
			)
		)
		(fp_text user "${REFERENCE}"
			(at -0.95 -3.168 270)
			(layer "B.Fab")
			(effects
				(font
					(size 0.7 0.7)
					(thickness 0.15)
				)
				(justify left bottom mirror)
			)
		)
		(fp_text user "License: Apache-2.0"
			(at -0.95 -5.169 270)
			(layer "B.Fab")
			(effects
				(font
					(size 0.7 0.7)
					(thickness 0.15)
				)
				(justify left bottom mirror)
			)
		)
		(pad "1" smd roundrect
			(at -0.48 0 90)
			(size 0.59 0.64)
			(layers "B.Cu" "B.Mask" "B.Paste")
			(roundrect_rratio 0.25)
			(net 23 "GND")
			(pintype "passive")
		)
		(pad "2" smd roundrect
			(at 0.48 0 90)
			(size 0.59 0.64)
			(layers "B.Cu" "B.Mask" "B.Paste")
			(roundrect_rratio 0.25)
			(net 205 "Net-(U3-UART_RX)")
			(pintype "passive")
		)
	)
	(footprint "antmicro-footprints:C_0402_1005Metric"
		(layer "B.Cu")
		(at 145.631866 76.260117 180)
		(descr "Capacitor SMD 0402")
		(tags "capacitor SMD 0402")
		(property "Reference" "C235"
			(at -17.768134 -9.464883 0)
			(layer "B.SilkS")
			(effects
				(font
					(size 0.7 0.7)
					(thickness 0.15)
				)
				(justify mirror)
			)
		)
		(property "Value" "C_1u_25V_0402"
			(at -1.022927 -2.155213 0)
			(layer "B.Fab")
			(effects
				(font
					(size 0.7 0.7)
					(thickness 0.15)
				)
				(justify left bottom mirror)
			)
		)
		(property "Datasheet" "https://www.murata.com/products/productdetail?partno=GRM155R61E105KE11%23"
			(at 0 0 0)
			(layer "B.Fab")
			(hide yes)
			(effects
				(font
					(size 1.27 1.27)
					(thickness 0.15)
				)
				(justify mirror)
			)
		)
		(property "Description" "SMD Multilayer Ceramic Capacitor, 1 µF, 25 V, 0402 [1005 Metric], ± 10%, X5R, GRM Series"
			(at 0 0 0)
			(layer "B.Fab")
			(hide yes)
			(effects
				(font
					(size 1.27 1.27)
					(thickness 0.15)
				)
				(justify mirror)
			)
		)
		(property "MPN" "GRM155R61E105KE11J"
			(at 0 0 180)
			(unlocked yes)
			(layer "B.Fab")
			(hide yes)
			(effects
				(font
					(size 1 1)
					(thickness 0.15)
				)
				(justify mirror)
			)
		)
		(property "Manufacturer" "Murata"
			(at 0 0 180)
			(unlocked yes)
			(layer "B.Fab")
			(hide yes)
			(effects
				(font
					(size 1 1)
					(thickness 0.15)
				)
				(justify mirror)
			)
		)
		(property "License" "Apache-2.0"
			(at 0 0 180)
			(unlocked yes)
			(layer "B.Fab")
			(hide yes)
			(effects
				(font
					(size 1 1)
					(thickness 0.15)
				)
				(justify mirror)
			)
		)
		(property "Author" "Antmicro"
			(at 0 0 180)
			(unlocked yes)
			(layer "B.Fab")
			(hide yes)
			(effects
				(font
					(size 1 1)
					(thickness 0.15)
				)
				(justify mirror)
			)
		)
		(property "Val" "1u"
			(at 0 0 180)
			(unlocked yes)
			(layer "B.Fab")
			(hide yes)
			(effects
				(font
					(size 1 1)
					(thickness 0.15)
				)
				(justify mirror)
			)
		)
		(property "Voltage" "25V"
			(at 0 0 180)
			(unlocked yes)
			(layer "B.Fab")
			(hide yes)
			(effects
				(font
					(size 1 1)
					(thickness 0.15)
				)
				(justify mirror)
			)
		)
		(property "Dielectric" "X5R"
			(at 0 0 180)
			(unlocked yes)
			(layer "B.Fab")
			(hide yes)
			(effects
				(font
					(size 1 1)
					(thickness 0.15)
				)
				(justify mirror)
			)
		)
		(sheetname "/X710-AT2 power/")
		(sheetfile "x710-at2-power.kicad_sch")
		(attr smd)
		(fp_rect
			(start -0.925 0.47)
			(end 0.925 -0.47)
			(stroke
				(width 0.05)
				(type default)
			)
			(fill no)
			(layer "B.CrtYd")
		)
		(fp_line
			(start 0.504 0.25)
			(end 0.504 -0.248)
			(stroke
				(width 0.15)
				(type solid)
			)
			(layer "B.Fab")
		)
		(fp_line
			(start 0.504 -0.248)
			(end -0.494 -0.248)
			(stroke
				(width 0.15)
				(type solid)
			)
			(layer "B.Fab")
		)
		(fp_line
			(start -0.494 0.25)
			(end 0.504 0.25)
			(stroke
				(width 0.15)
				(type solid)
			)
			(layer "B.Fab")
		)
		(fp_line
			(start -0.494 -0.248)
			(end -0.494 0.25)
			(stroke
				(width 0.15)
				(type solid)
			)
			(layer "B.Fab")
		)
		(fp_text user "${REFERENCE}"
			(at -0.939 -4.599 0)
			(layer "B.Fab")
			(effects
				(font
					(size 0.7 0.7)
					(thickness 0.15)
				)
				(justify left bottom mirror)
			)
		)
		(fp_text user "License: Apache-2.0"
			(at -0.939 -5.799 0)
			(layer "B.Fab")
			(effects
				(font
					(size 0.7 0.7)
					(thickness 0.15)
				)
				(justify left bottom mirror)
			)
		)
		(fp_text user "Author: Antmicro"
			(at -0.939 -3.399 0)
			(layer "B.Fab")
			(effects
				(font
					(size 0.7 0.7)
					(thickness 0.15)
				)
				(justify left bottom mirror)
			)
		)
		(pad "1" smd roundrect
			(at -0.48 0 180)
			(size 0.59 0.64)
			(layers "B.Cu" "B.Mask" "B.Paste")
			(roundrect_rratio 0.25)
			(net 23 "GND")
			(pintype "passive")
		)
		(pad "2" smd roundrect
			(at 0.48 0 180)
			(size 0.59 0.64)
			(layers "B.Cu" "B.Mask" "B.Paste")
			(roundrect_rratio 0.25)
			(net 7 "+3V3")
			(pintype "passive")
		)
	)
	(footprint "antmicro-footprints:R_0402_1005Metric"
		(layer "B.Cu")
		(at 120.500001 89.749998 90)
		(descr "Resistor SMD 0402")
		(tags "resistor SMD 0402")
		(property "Reference" "R78"
			(at -5.85 0.3 270)
			(layer "B.SilkS")
			(effects
				(font
					(size 0.7 0.7)
					(thickness 0.15)
				)
				(justify left bottom mirror)
			)
		)
		(property "Value" "R_47k_0402"
			(at -1.011843 -1.772047 270)
			(layer "B.Fab")
			(effects
				(font
					(size 0.7 0.7)
					(thickness 0.15)
				)
				(justify left bottom mirror)
			)
		)
		(property "Datasheet" "https://www.bourns.com/docs/product-datasheets/cr.pdf"
			(at 0 0 270)
			(layer "B.Fab")
			(hide yes)
			(effects
				(font
					(size 1.27 1.27)
					(thickness 0.15)
				)
				(justify mirror)
			)
		)
		(property "Description" "SMD Chip Resistor, 47 kohm, ± 1%, 62.5 mW, 0402 [1005 Metric], Thick Film, General Purpose"
			(at 0 0 270)
			(layer "B.Fab")
			(hide yes)
			(effects
				(font
					(size 1.27 1.27)
					(thickness 0.15)
				)
				(justify mirror)
			)
		)
		(property "MPN" "CR0402-FX-4702GLF"
			(at 0 0 90)
			(unlocked yes)
			(layer "B.Fab")
			(hide yes)
			(effects
				(font
					(size 1 1)
					(thickness 0.15)
				)
				(justify mirror)
			)
		)
		(property "Manufacturer" "Bourns"
			(at 0 0 90)
			(unlocked yes)
			(layer "B.Fab")
			(hide yes)
			(effects
				(font
					(size 1 1)
					(thickness 0.15)
				)
				(justify mirror)
			)
		)
		(property "License" "Apache-2.0"
			(at 0 0 90)
			(unlocked yes)
			(layer "B.Fab")
			(hide yes)
			(effects
				(font
					(size 1 1)
					(thickness 0.15)
				)
				(justify mirror)
			)
		)
		(property "Author" "Antmicro"
			(at 0 0 90)
			(unlocked yes)
			(layer "B.Fab")
			(hide yes)
			(effects
				(font
					(size 1 1)
					(thickness 0.15)
				)
				(justify mirror)
			)
		)
		(property "Val" "47k"
			(at 0 0 90)
			(unlocked yes)
			(layer "B.Fab")
			(hide yes)
			(effects
				(font
					(size 1 1)
					(thickness 0.15)
				)
				(justify mirror)
			)
		)
		(property "Tolerance" "1%"
			(at 0 0 90)
			(unlocked yes)
			(layer "B.Fab")
			(hide yes)
			(effects
				(font
					(size 1 1)
					(thickness 0.15)
				)
				(justify mirror)
			)
		)
		(sheetname "/TB Controller - Power/")
		(sheetfile "tb-power.kicad_sch")
		(attr smd)
		(fp_rect
			(start -0.925 0.47)
			(end 0.925 -0.47)
			(stroke
				(width 0.05)
				(type default)
			)
			(fill no)
			(layer "B.CrtYd")
		)
		(fp_rect
			(start -0.5 0.25)
			(end 0.5 -0.25)
			(stroke
				(width 0.15)
				(type solid)
			)
			(fill no)
			(layer "B.Fab")
		)
		(fp_text user "License: Apache-2.0"
			(at -0.95 -5.169 270)
			(layer "B.Fab")
			(effects
				(font
					(size 0.7 0.7)
					(thickness 0.15)
				)
				(justify left bottom mirror)
			)
		)
		(fp_text user "${REFERENCE}"
			(at -0.95 -3.168 270)
			(layer "B.Fab")
			(effects
				(font
					(size 0.7 0.7)
					(thickness 0.15)
				)
				(justify left bottom mirror)
			)
		)
		(fp_text user "Author: Antmicro"
			(at -0.95 -4.169 270)
			(layer "B.Fab")
			(effects
				(font
					(size 0.7 0.7)
					(thickness 0.15)
				)
				(justify left bottom mirror)
			)
		)
		(pad "1" smd roundrect
			(at -0.48 0 90)
			(size 0.59 0.64)
			(layers "B.Cu" "B.Mask" "B.Paste")
			(roundrect_rratio 0.25)
			(net 436 "Net-(R77-Pad1)")
			(pintype "passive")
		)
		(pad "2" smd roundrect
			(at 0.48 0 90)
			(size 0.59 0.64)
			(layers "B.Cu" "B.Mask" "B.Paste")
			(roundrect_rratio 0.25)
			(net 356 "/TB Controller - Power/0P9_BUFFERED")
			(pintype "passive")
		)
	)
	(footprint "antmicro-footprints:C_Pol_EIA-A"
		(layer "B.Cu")
		(at 158.8 103 -90)
		(property "Reference" "C328"
			(at -5 -0.5 90)
			(layer "B.SilkS")
			(effects
				(font
					(size 0.7 0.7)
					(thickness 0.15)
				)
				(justify left bottom mirror)
			)
		)
		(property "Value" "C_Pol_100u_6V_KEMET-T490-A"
			(at 0 -2 90)
			(layer "B.Fab")
			(effects
				(font
					(size 0.7 0.7)
					(thickness 0.15)
				)
				(justify left bottom mirror)
			)
		)
		(property "Datasheet" "https://www.kemet.com/en/us/capacitors/product/T490A107M006ATE800.html"
			(at 0 0 90)
			(layer "B.Fab")
			(hide yes)
			(effects
				(font
					(size 1.27 1.27)
					(thickness 0.15)
				)
				(justify mirror)
			)
		)
		(property "Description" "Surface Mount Tantalum Capacitor,  Solid SMD 6V 100uF 1206 20% ESR=800mOhms"
			(at 0 0 90)
			(layer "B.Fab")
			(hide yes)
			(effects
				(font
					(size 1.27 1.27)
					(thickness 0.15)
				)
				(justify mirror)
			)
		)
		(property "Val" "100u"
			(at 0 0 270)
			(unlocked yes)
			(layer "B.Fab")
			(hide yes)
			(effects
				(font
					(size 1 1)
					(thickness 0.15)
				)
				(justify mirror)
			)
		)
		(property "MPN" "T490A107M006ATE800"
			(at 0 0 270)
			(unlocked yes)
			(layer "B.Fab")
			(hide yes)
			(effects
				(font
					(size 1 1)
					(thickness 0.15)
				)
				(justify mirror)
			)
		)
		(property "Manufacturer" "KEMET"
			(at 0 0 270)
			(unlocked yes)
			(layer "B.Fab")
			(hide yes)
			(effects
				(font
					(size 1 1)
					(thickness 0.15)
				)
				(justify mirror)
			)
		)
		(property "License" "Apache-2.0"
			(at 0 0 270)
			(unlocked yes)
			(layer "B.Fab")
			(hide yes)
			(effects
				(font
					(size 1 1)
					(thickness 0.15)
				)
				(justify mirror)
			)
		)
		(property "Author" "Antmicro"
			(at 0 0 270)
			(unlocked yes)
			(layer "B.Fab")
			(hide yes)
			(effects
				(font
					(size 1 1)
					(thickness 0.15)
				)
				(justify mirror)
			)
		)
		(property "Voltage" "6V"
			(at 0 0 270)
			(unlocked yes)
			(layer "B.Fab")
			(hide yes)
			(effects
				(font
					(size 1 1)
					(thickness 0.15)
				)
				(justify mirror)
			)
		)
		(property "Dielectric" "template_dielectric"
			(at 0 0 270)
			(unlocked yes)
			(layer "B.Fab")
			(hide yes)
			(effects
				(font
					(size 1 1)
					(thickness 0.15)
				)
				(justify mirror)
			)
		)
		(sheetname "/X710-AT2 power/")
		(sheetfile "x710-at2-power.kicad_sch")
		(attr smd)
		(fp_line
			(start -1.95 1.25)
			(end -1.95 0.95)
			(stroke
				(width 0.12)
				(type solid)
			)
			(layer "B.SilkS")
		)
		(fp_line
			(start -2.1 1.1)
			(end -1.8 1.1)
			(stroke
				(width 0.12)
				(type solid)
			)
			(layer "B.SilkS")
		)
		(fp_line
			(start -1.5 0.85)
			(end 1.5 0.85)
			(stroke
				(width 0.12)
				(type solid)
			)
			(layer "B.SilkS")
		)
		(fp_line
			(start -1.5 0.75)
			(end -1.5 0.85)
			(stroke
				(width 0.12)
				(type solid)
			)
			(layer "B.SilkS")
		)
		(fp_line
			(start 1.5 0.75)
			(end 1.5 0.85)
			(stroke
				(width 0.12)
				(type solid)
			)
			(layer "B.SilkS")
		)
		(fp_line
			(start -1.5 -0.75)
			(end -1.5 -0.85)
			(stroke
				(width 0.12)
				(type solid)
			)
			(layer "B.SilkS")
		)
		(fp_line
			(start 1.5 -0.75)
			(end 1.5 -0.85)
			(stroke
				(width 0.12)
				(type solid)
			)
			(layer "B.SilkS")
		)
		(fp_line
			(start 1.5 -0.85)
			(end -1.5 -0.85)
			(stroke
				(width 0.12)
				(type solid)
			)
			(layer "B.SilkS")
		)
		(fp_line
			(start 1.7 1.05)
			(end -1.7 1.05)
			(stroke
				(width 0.05)
				(type solid)
			)
			(layer "B.CrtYd")
		)
		(fp_line
			(start -2.05 0.85)
			(end -2.05 -0.85)
			(stroke
				(width 0.05)
				(type solid)
			)
			(layer "B.CrtYd")
		)
		(fp_line
			(start -1.7 0.85)
			(end -1.7 1.05)
			(stroke
				(width 0.05)
				(type solid)
			)
			(layer "B.CrtYd")
		)
		(fp_line
			(start -1.7 0.85)
			(end -2.05 0.85)
			(stroke
				(width 0.05)
				(type solid)
			)
			(layer "B.CrtYd")
		)
		(fp_line
			(start 1.7 0.85)
			(end 1.7 1.05)
			(stroke
				(width 0.05)
				(type solid)
			)
			(layer "B.CrtYd")
		)
		(fp_line
			(start 2.05 0.85)
			(end 1.7 0.85)
			(stroke
				(width 0.05)
				(type solid)
			)
			(layer "B.CrtYd")
		)
		(fp_line
			(start 2.05 0.85)
			(end 2.05 -0.85)
			(stroke
				(width 0.05)
				(type solid)
			)
			(layer "B.CrtYd")
		)
		(fp_line
			(start -1.7 -0.85)
			(end -2.05 -0.85)
			(stroke
				(width 0.05)
				(type solid)
			)
			(layer "B.CrtYd")
		)
		(fp_line
			(start 2.05 -0.85)
			(end 1.7 -0.85)
			(stroke
				(width 0.05)
				(type solid)
			)
			(layer "B.CrtYd")
		)
		(fp_line
			(start -1.7 -1.05)
			(end -1.7 -0.85)
			(stroke
				(width 0.05)
				(type solid)
			)
			(layer "B.CrtYd")
		)
		(fp_line
			(start 1.7 -1.05)
			(end 1.7 -0.85)
			(stroke
				(width 0.05)
				(type solid)
			)
			(layer "B.CrtYd")
		)
		(fp_line
			(start 1.7 -1.05)
			(end -1.7 -1.05)
			(stroke
				(width 0.05)
				(type solid)
			)
			(layer "B.CrtYd")
		)
		(fp_rect
			(start -1.601 0.802)
			(end 1.6 -0.8)
			(stroke
				(width 0.1)
				(type solid)
			)
			(fill no)
			(layer "B.Fab")
		)
		(fp_text user "${REFERENCE}"
			(at -2.1 -4.198 90)
			(layer "B.Fab")
			(effects
				(font
					(size 0.7 0.7)
					(thickness 0.15)
				)
				(justify left bottom mirror)
			)
		)
		(fp_text user "License: Apache-2.0"
			(at -2.1 -5.198 90)
			(layer "B.Fab")
			(effects
				(font
					(size 0.7 0.7)
					(thickness 0.15)
				)
				(justify left bottom mirror)
			)
		)
		(fp_text user "Author: Antmicro"
			(at -2.1 -6.198 90)
			(layer "B.Fab")
			(effects
				(font
					(size 0.7 0.7)
					(thickness 0.15)
				)
				(justify left bottom mirror)
			)
		)
		(pad "1" smd roundrect
			(at -1.2 0 270)
			(size 1.2 1.2)
			(layers "B.Cu" "B.Mask" "B.Paste")
			(roundrect_rratio 0.1)
			(net 136 "+1V0")
			(pintype "passive")
		)
		(pad "2" smd roundrect
			(at 1.2 0 270)
			(size 1.2 1.2)
			(layers "B.Cu" "B.Mask" "B.Paste")
			(roundrect_rratio 0.1)
			(net 23 "GND")
			(pintype "passive")
		)
	)
	(footprint "antmicro-footprints:C_0402_1005Metric"
		(layer "B.Cu")
		(at 133.739999 116 180)
		(descr "Capacitor SMD 0402")
		(tags "capacitor SMD 0402")
		(property "Reference" "C35"
			(at -19.525001 7.450001 0)
			(layer "B.SilkS")
			(effects
				(font
					(size 0.7 0.7)
					(thickness 0.15)
				)
				(justify mirror)
			)
		)
		(property "Value" "C_100n_0402"
			(at -1.022927 -2.155213 0)
			(layer "B.Fab")
			(effects
				(font
					(size 0.7 0.7)
					(thickness 0.15)
				)
				(justify left bottom mirror)
			)
		)
		(property "Datasheet" "https://www.murata.com/products/productdetail?partno=GRM155R61H104KE14%23"
			(at 0 0 0)
			(layer "B.Fab")
			(hide yes)
			(effects
				(font
					(size 1.27 1.27)
					(thickness 0.15)
				)
				(justify mirror)
			)
		)
		(property "Description" "SMD Multilayer Ceramic Capacitor, 0.1 µF, 50 V, 0402 [1005 Metric], ± 10%, X5R, GRM Series"
			(at 0 0 0)
			(layer "B.Fab")
			(hide yes)
			(effects
				(font
					(size 1.27 1.27)
					(thickness 0.15)
				)
				(justify mirror)
			)
		)
		(property "MPN" "GRM155R61H104KE14D"
			(at 0 0 180)
			(unlocked yes)
			(layer "B.Fab")
			(hide yes)
			(effects
				(font
					(size 1 1)
					(thickness 0.15)
				)
				(justify mirror)
			)
		)
		(property "Manufacturer" "Murata"
			(at 0 0 180)
			(unlocked yes)
			(layer "B.Fab")
			(hide yes)
			(effects
				(font
					(size 1 1)
					(thickness 0.15)
				)
				(justify mirror)
			)
		)
		(property "License" "Apache-2.0"
			(at 0 0 180)
			(unlocked yes)
			(layer "B.Fab")
			(hide yes)
			(effects
				(font
					(size 1 1)
					(thickness 0.15)
				)
				(justify mirror)
			)
		)
		(property "Val" "100n"
			(at 0 0 180)
			(unlocked yes)
			(layer "B.Fab")
			(hide yes)
			(effects
				(font
					(size 1 1)
					(thickness 0.15)
				)
				(justify mirror)
			)
		)
		(property "Voltage" "50V"
			(at 0 0 180)
			(unlocked yes)
			(layer "B.Fab")
			(hide yes)
			(effects
				(font
					(size 1 1)
					(thickness 0.15)
				)
				(justify mirror)
			)
		)
		(property "Dielectric" "X5R"
			(at 0 0 180)
			(unlocked yes)
			(layer "B.Fab")
			(hide yes)
			(effects
				(font
					(size 1 1)
					(thickness 0.15)
				)
				(justify mirror)
			)
		)
		(property "Author" "Antmicro"
			(at 0 0 180)
			(unlocked yes)
			(layer "B.Fab")
			(hide yes)
			(effects
				(font
					(size 1 1)
					(thickness 0.15)
				)
				(justify mirror)
			)
		)
		(sheetname "/TB Controller/")
		(sheetfile "tb.kicad_sch")
		(attr smd)
		(fp_rect
			(start -0.925 0.47)
			(end 0.925 -0.47)
			(stroke
				(width 0.05)
				(type default)
			)
			(fill no)
			(layer "B.CrtYd")
		)
		(fp_line
			(start 0.504 0.25)
			(end 0.504 -0.248)
			(stroke
				(width 0.15)
				(type solid)
			)
			(layer "B.Fab")
		)
		(fp_line
			(start 0.504 -0.248)
			(end -0.494 -0.248)
			(stroke
				(width 0.15)
				(type solid)
			)
			(layer "B.Fab")
		)
		(fp_line
			(start -0.494 0.25)
			(end 0.504 0.25)
			(stroke
				(width 0.15)
				(type solid)
			)
			(layer "B.Fab")
		)
		(fp_line
			(start -0.494 -0.248)
			(end -0.494 0.25)
			(stroke
				(width 0.15)
				(type solid)
			)
			(layer "B.Fab")
		)
		(fp_text user "Author: Antmicro"
			(at -0.939 -3.399 0)
			(layer "B.Fab")
			(effects
				(font
					(size 0.7 0.7)
					(thickness 0.15)
				)
				(justify left bottom mirror)
			)
		)
		(fp_text user "License: Apache-2.0"
			(at -0.939 -5.799 0)
			(layer "B.Fab")
			(effects
				(font
					(size 0.7 0.7)
					(thickness 0.15)
				)
				(justify left bottom mirror)
			)
		)
		(fp_text user "${REFERENCE}"
			(at -0.939 -4.599 0)
			(layer "B.Fab")
			(effects
				(font
					(size 0.7 0.7)
					(thickness 0.15)
				)
				(justify left bottom mirror)
			)
		)
		(pad "1" smd roundrect
			(at -0.48 0 180)
			(size 0.59 0.64)
			(layers "B.Cu" "B.Mask" "B.Paste")
			(roundrect_rratio 0.25)
			(net 69 "/PD and TB DC-DC/AUX.+")
			(pintype "passive")
		)
		(pad "2" smd roundrect
			(at 0.48 0 180)
			(size 0.59 0.64)
			(layers "B.Cu" "B.Mask" "B.Paste")
			(roundrect_rratio 0.25)
			(net 239 "/TB Controller/PA_AUX_P")
			(pintype "passive")
		)
	)
	(footprint "antmicro-footprints:C_0402_1005Metric"
		(layer "B.Cu")
		(at 127.524999 123.950002 90)
		(descr "Capacitor SMD 0402")
		(tags "capacitor SMD 0402")
		(property "Reference" "C55"
			(at 7.700002 21.900002 270)
			(layer "B.SilkS")
			(effects
				(font
					(size 0.7 0.7)
					(thickness 0.15)
				)
				(justify mirror)
			)
		)
		(property "Value" "C_1u_0402"
			(at -1.022927 -2.155213 270)
			(layer "B.Fab")
			(effects
				(font
					(size 0.7 0.7)
					(thickness 0.15)
				)
				(justify left bottom mirror)
			)
		)
		(property "Datasheet" "https://product.tdk.com/en/search/capacitor/ceramic/mlcc/info?part_no=C1005X6S1A105K050BC"
			(at 0 0 270)
			(layer "B.Fab")
			(hide yes)
			(effects
				(font
					(size 1.27 1.27)
					(thickness 0.15)
				)
				(justify mirror)
			)
		)
		(property "Description" "SMD Multilayer Ceramic Capacitor, 1 µF, 10 V, 0402 [1005 Metric], ± 10%, X6S, C"
			(at 0 0 270)
			(layer "B.Fab")
			(hide yes)
			(effects
				(font
					(size 1.27 1.27)
					(thickness 0.15)
				)
				(justify mirror)
			)
		)
		(property "MPN" "C1005X6S1A105K050BC"
			(at 0 0 90)
			(unlocked yes)
			(layer "B.Fab")
			(hide yes)
			(effects
				(font
					(size 1 1)
					(thickness 0.15)
				)
				(justify mirror)
			)
		)
		(property "Manufacturer" "TDK"
			(at 0 0 90)
			(unlocked yes)
			(layer "B.Fab")
			(hide yes)
			(effects
				(font
					(size 1 1)
					(thickness 0.15)
				)
				(justify mirror)
			)
		)
		(property "License" "Apache-2.0"
			(at 0 0 90)
			(unlocked yes)
			(layer "B.Fab")
			(hide yes)
			(effects
				(font
					(size 1 1)
					(thickness 0.15)
				)
				(justify mirror)
			)
		)
		(property "Val" "1u"
			(at 0 0 90)
			(unlocked yes)
			(layer "B.Fab")
			(hide yes)
			(effects
				(font
					(size 1 1)
					(thickness 0.15)
				)
				(justify mirror)
			)
		)
		(property "Voltage" ""
			(at 0 0 90)
			(unlocked yes)
			(layer "B.Fab")
			(hide yes)
			(effects
				(font
					(size 1 1)
					(thickness 0.15)
				)
				(justify mirror)
			)
		)
		(property "Dielectric" ""
			(at 0 0 90)
			(unlocked yes)
			(layer "B.Fab")
			(hide yes)
			(effects
				(font
					(size 1 1)
					(thickness 0.15)
				)
				(justify mirror)
			)
		)
		(property "Author" "Antmicro"
			(at 0 0 90)
			(unlocked yes)
			(layer "B.Fab")
			(hide yes)
			(effects
				(font
					(size 1 1)
					(thickness 0.15)
				)
				(justify mirror)
			)
		)
		(sheetname "/TB Controller - Power/")
		(sheetfile "tb-power.kicad_sch")
		(attr smd)
		(fp_rect
			(start -0.925 0.47)
			(end 0.925 -0.47)
			(stroke
				(width 0.05)
				(type default)
			)
			(fill no)
			(layer "B.CrtYd")
		)
		(fp_line
			(start 0.504 -0.248)
			(end -0.494 -0.248)
			(stroke
				(width 0.15)
				(type solid)
			)
			(layer "B.Fab")
		)
		(fp_line
			(start -0.494 -0.248)
			(end -0.494 0.25)
			(stroke
				(width 0.15)
				(type solid)
			)
			(layer "B.Fab")
		)
		(fp_line
			(start 0.504 0.25)
			(end 0.504 -0.248)
			(stroke
				(width 0.15)
				(type solid)
			)
			(layer "B.Fab")
		)
		(fp_line
			(start -0.494 0.25)
			(end 0.504 0.25)
			(stroke
				(width 0.15)
				(type solid)
			)
			(layer "B.Fab")
		)
		(fp_text user "${REFERENCE}"
			(at -0.939 -4.599 270)
			(layer "B.Fab")
			(effects
				(font
					(size 0.7 0.7)
					(thickness 0.15)
				)
				(justify left bottom mirror)
			)
		)
		(fp_text user "License: Apache-2.0"
			(at -0.939 -5.799 270)
			(layer "B.Fab")
			(effects
				(font
					(size 0.7 0.7)
					(thickness 0.15)
				)
				(justify left bottom mirror)
			)
		)
		(fp_text user "Author: Antmicro"
			(at -0.939 -3.399 270)
			(layer "B.Fab")
			(effects
				(font
					(size 0.7 0.7)
					(thickness 0.15)
				)
				(justify left bottom mirror)
			)
		)
		(pad "1" smd roundrect
			(at -0.48 0 90)
			(size 0.59 0.64)
			(layers "B.Cu" "B.Mask" "B.Paste")
			(roundrect_rratio 0.25)
			(net 23 "GND")
			(pintype "passive")
		)
		(pad "2" smd roundrect
			(at 0.48 0 90)
			(size 0.59 0.64)
			(layers "B.Cu" "B.Mask" "B.Paste")
			(roundrect_rratio 0.25)
			(net 403 "Net-(C55-Pad2)")
			(pintype "passive")
		)
	)
	(footprint "antmicro-footprints:C_0402_1005Metric"
		(layer "B.Cu")
		(at 148.431866 87.935117 180)
		(descr "Capacitor SMD 0402")
		(tags "capacitor SMD 0402")
		(property "Reference" "C243"
			(at -17.975 -9.475 0)
			(layer "B.SilkS")
			(effects
				(font
					(size 0.7 0.7)
					(thickness 0.15)
				)
				(justify mirror)
			)
		)
		(property "Value" "C_1u_25V_0402"
			(at -1.022927 -2.155213 0)
			(layer "B.Fab")
			(effects
				(font
					(size 0.7 0.7)
					(thickness 0.15)
				)
				(justify left bottom mirror)
			)
		)
		(property "Datasheet" "https://www.murata.com/products/productdetail?partno=GRM155R61E105KE11%23"
			(at 0 0 0)
			(layer "B.Fab")
			(hide yes)
			(effects
				(font
					(size 1.27 1.27)
					(thickness 0.15)
				)
				(justify mirror)
			)
		)
		(property "Description" "SMD Multilayer Ceramic Capacitor, 1 µF, 25 V, 0402 [1005 Metric], ± 10%, X5R, GRM Series"
			(at 0 0 0)
			(layer "B.Fab")
			(hide yes)
			(effects
				(font
					(size 1.27 1.27)
					(thickness 0.15)
				)
				(justify mirror)
			)
		)
		(property "MPN" "GRM155R61E105KE11J"
			(at 0 0 180)
			(unlocked yes)
			(layer "B.Fab")
			(hide yes)
			(effects
				(font
					(size 1 1)
					(thickness 0.15)
				)
				(justify mirror)
			)
		)
		(property "Manufacturer" "Murata"
			(at 0 0 180)
			(unlocked yes)
			(layer "B.Fab")
			(hide yes)
			(effects
				(font
					(size 1 1)
					(thickness 0.15)
				)
				(justify mirror)
			)
		)
		(property "License" "Apache-2.0"
			(at 0 0 180)
			(unlocked yes)
			(layer "B.Fab")
			(hide yes)
			(effects
				(font
					(size 1 1)
					(thickness 0.15)
				)
				(justify mirror)
			)
		)
		(property "Author" "Antmicro"
			(at 0 0 180)
			(unlocked yes)
			(layer "B.Fab")
			(hide yes)
			(effects
				(font
					(size 1 1)
					(thickness 0.15)
				)
				(justify mirror)
			)
		)
		(property "Val" "1u"
			(at 0 0 180)
			(unlocked yes)
			(layer "B.Fab")
			(hide yes)
			(effects
				(font
					(size 1 1)
					(thickness 0.15)
				)
				(justify mirror)
			)
		)
		(property "Voltage" "25V"
			(at 0 0 180)
			(unlocked yes)
			(layer "B.Fab")
			(hide yes)
			(effects
				(font
					(size 1 1)
					(thickness 0.15)
				)
				(justify mirror)
			)
		)
		(property "Dielectric" "X5R"
			(at 0 0 180)
			(unlocked yes)
			(layer "B.Fab")
			(hide yes)
			(effects
				(font
					(size 1 1)
					(thickness 0.15)
				)
				(justify mirror)
			)
		)
		(sheetname "/X710-AT2 power/")
		(sheetfile "x710-at2-power.kicad_sch")
		(attr smd)
		(fp_rect
			(start -0.925 0.47)
			(end 0.925 -0.47)
			(stroke
				(width 0.05)
				(type default)
			)
			(fill no)
			(layer "B.CrtYd")
		)
		(fp_line
			(start 0.504 0.25)
			(end 0.504 -0.248)
			(stroke
				(width 0.15)
				(type solid)
			)
			(layer "B.Fab")
		)
		(fp_line
			(start 0.504 -0.248)
			(end -0.494 -0.248)
			(stroke
				(width 0.15)
				(type solid)
			)
			(layer "B.Fab")
		)
		(fp_line
			(start -0.494 0.25)
			(end 0.504 0.25)
			(stroke
				(width 0.15)
				(type solid)
			)
			(layer "B.Fab")
		)
		(fp_line
			(start -0.494 -0.248)
			(end -0.494 0.25)
			(stroke
				(width 0.15)
				(type solid)
			)
			(layer "B.Fab")
		)
		(fp_text user "License: Apache-2.0"
			(at -0.939 -5.799 0)
			(layer "B.Fab")
			(effects
				(font
					(size 0.7 0.7)
					(thickness 0.15)
				)
				(justify left bottom mirror)
			)
		)
		(fp_text user "${REFERENCE}"
			(at -0.939 -4.599 0)
			(layer "B.Fab")
			(effects
				(font
					(size 0.7 0.7)
					(thickness 0.15)
				)
				(justify left bottom mirror)
			)
		)
		(fp_text user "Author: Antmicro"
			(at -0.939 -3.399 0)
			(layer "B.Fab")
			(effects
				(font
					(size 0.7 0.7)
					(thickness 0.15)
				)
				(justify left bottom mirror)
			)
		)
		(pad "1" smd roundrect
			(at -0.48 0 180)
			(size 0.59 0.64)
			(layers "B.Cu" "B.Mask" "B.Paste")
			(roundrect_rratio 0.25)
			(net 23 "GND")
			(pintype "passive")
		)
		(pad "2" smd roundrect
			(at 0.48 0 180)
			(size 0.59 0.64)
			(layers "B.Cu" "B.Mask" "B.Paste")
			(roundrect_rratio 0.25)
			(net 7 "+3V3")
			(pintype "passive")
		)
	)
	(footprint "antmicro-footprints:C_0402_1005Metric"
		(layer "B.Cu")
		(at 182.05 133.25 180)
		(descr "Capacitor SMD 0402")
		(tags "capacitor SMD 0402")
		(property "Reference" "C301"
			(at -1.2 0.5 0)
			(layer "B.SilkS")
			(effects
				(font
					(size 0.7 0.7)
					(thickness 0.15)
				)
				(justify left bottom mirror)
			)
		)
		(property "Value" "C_1u_25V_0402"
			(at -1.022927 -2.155213 0)
			(layer "B.Fab")
			(effects
				(font
					(size 0.7 0.7)
					(thickness 0.15)
				)
				(justify left bottom mirror)
			)
		)
		(property "Datasheet" "https://www.murata.com/products/productdetail?partno=GRM155R61E105KE11%23"
			(at 0 0 0)
			(layer "B.Fab")
			(hide yes)
			(effects
				(font
					(size 1.27 1.27)
					(thickness 0.15)
				)
				(justify mirror)
			)
		)
		(property "Description" "SMD Multilayer Ceramic Capacitor, 1 µF, 25 V, 0402 [1005 Metric], ± 10%, X5R, GRM Series"
			(at 0 0 0)
			(layer "B.Fab")
			(hide yes)
			(effects
				(font
					(size 1.27 1.27)
					(thickness 0.15)
				)
				(justify mirror)
			)
		)
		(property "MPN" "GRM155R61E105KE11J"
			(at 0 0 180)
			(unlocked yes)
			(layer "B.Fab")
			(hide yes)
			(effects
				(font
					(size 1 1)
					(thickness 0.15)
				)
				(justify mirror)
			)
		)
		(property "Manufacturer" "Murata"
			(at 0 0 180)
			(unlocked yes)
			(layer "B.Fab")
			(hide yes)
			(effects
				(font
					(size 1 1)
					(thickness 0.15)
				)
				(justify mirror)
			)
		)
		(property "License" "Apache-2.0"
			(at 0 0 180)
			(unlocked yes)
			(layer "B.Fab")
			(hide yes)
			(effects
				(font
					(size 1 1)
					(thickness 0.15)
				)
				(justify mirror)
			)
		)
		(property "Author" "Antmicro"
			(at 0 0 180)
			(unlocked yes)
			(layer "B.Fab")
			(hide yes)
			(effects
				(font
					(size 1 1)
					(thickness 0.15)
				)
				(justify mirror)
			)
		)
		(property "Val" "1u"
			(at 0 0 180)
			(unlocked yes)
			(layer "B.Fab")
			(hide yes)
			(effects
				(font
					(size 1 1)
					(thickness 0.15)
				)
				(justify mirror)
			)
		)
		(property "Voltage" "25V"
			(at 0 0 180)
			(unlocked yes)
			(layer "B.Fab")
			(hide yes)
			(effects
				(font
					(size 1 1)
					(thickness 0.15)
				)
				(justify mirror)
			)
		)
		(property "Dielectric" "X5R"
			(at 0 0 180)
			(unlocked yes)
			(layer "B.Fab")
			(hide yes)
			(effects
				(font
					(size 1 1)
					(thickness 0.15)
				)
				(justify mirror)
			)
		)
		(sheetname "/2xRJ45/")
		(sheetfile "2xrj45.kicad_sch")
		(attr smd)
		(fp_rect
			(start -0.925 0.47)
			(end 0.925 -0.47)
			(stroke
				(width 0.05)
				(type default)
			)
			(fill no)
			(layer "B.CrtYd")
		)
		(fp_line
			(start 0.504 0.25)
			(end 0.504 -0.248)
			(stroke
				(width 0.15)
				(type solid)
			)
			(layer "B.Fab")
		)
		(fp_line
			(start 0.504 -0.248)
			(end -0.494 -0.248)
			(stroke
				(width 0.15)
				(type solid)
			)
			(layer "B.Fab")
		)
		(fp_line
			(start -0.494 0.25)
			(end 0.504 0.25)
			(stroke
				(width 0.15)
				(type solid)
			)
			(layer "B.Fab")
		)
		(fp_line
			(start -0.494 -0.248)
			(end -0.494 0.25)
			(stroke
				(width 0.15)
				(type solid)
			)
			(layer "B.Fab")
		)
		(fp_text user "Author: Antmicro"
			(at -0.939 -3.399 0)
			(layer "B.Fab")
			(effects
				(font
					(size 0.7 0.7)
					(thickness 0.15)
				)
				(justify left bottom mirror)
			)
		)
		(fp_text user "License: Apache-2.0"
			(at -0.939 -5.799 0)
			(layer "B.Fab")
			(effects
				(font
					(size 0.7 0.7)
					(thickness 0.15)
				)
				(justify left bottom mirror)
			)
		)
		(fp_text user "${REFERENCE}"
			(at -0.939 -4.599 0)
			(layer "B.Fab")
			(effects
				(font
					(size 0.7 0.7)
					(thickness 0.15)
				)
				(justify left bottom mirror)
			)
		)
		(pad "1" smd roundrect
			(at -0.48 0 180)
			(size 0.59 0.64)
			(layers "B.Cu" "B.Mask" "B.Paste")
			(roundrect_rratio 0.25)
			(net 23 "GND")
			(pintype "passive")
		)
		(pad "2" smd roundrect
			(at 0.48 0 180)
			(size 0.59 0.64)
			(layers "B.Cu" "B.Mask" "B.Paste")
			(roundrect_rratio 0.25)
			(net 134 "/2xRJ45/P1_CT")
			(pintype "passive")
		)
	)
	(footprint "antmicro-footprints:R_0402_1005Metric"
		(layer "B.Cu")
		(at 136.5 120.15)
		(descr "Resistor SMD 0402")
		(tags "resistor SMD 0402")
		(property "Reference" "R41"
			(at 19.525001 -7.450001 180)
			(layer "B.SilkS")
			(effects
				(font
					(size 0.7 0.7)
					(thickness 0.15)
				)
				(justify mirror)
			)
		)
		(property "Value" "R_100k_0402"
			(at -1.011843 -1.772047 180)
			(layer "B.Fab")
			(effects
				(font
					(size 0.7 0.7)
					(thickness 0.15)
				)
				(justify left bottom mirror)
			)
		)
		(property "Datasheet" "https://www.bourns.com/docs/product-datasheets/cr.pdf"
			(at 0 0 180)
			(layer "B.Fab")
			(hide yes)
			(effects
				(font
					(size 1.27 1.27)
					(thickness 0.15)
				)
				(justify mirror)
			)
		)
		(property "Description" "SMD Chip Resistor, 100 kohm, ± 1%, 62.5 mW, 0402 [1005 Metric], Thick Film, General Purpose"
			(at 0 0 180)
			(layer "B.Fab")
			(hide yes)
			(effects
				(font
					(size 1.27 1.27)
					(thickness 0.15)
				)
				(justify mirror)
			)
		)
		(property "MPN" "CR0402-FX-1003GLF"
			(at 0 0 0)
			(unlocked yes)
			(layer "B.Fab")
			(hide yes)
			(effects
				(font
					(size 1 1)
					(thickness 0.15)
				)
				(justify mirror)
			)
		)
		(property "Manufacturer" "Bourns"
			(at 0 0 0)
			(unlocked yes)
			(layer "B.Fab")
			(hide yes)
			(effects
				(font
					(size 1 1)
					(thickness 0.15)
				)
				(justify mirror)
			)
		)
		(property "License" "Apache-2.0"
			(at 0 0 0)
			(unlocked yes)
			(layer "B.Fab")
			(hide yes)
			(effects
				(font
					(size 1 1)
					(thickness 0.15)
				)
				(justify mirror)
			)
		)
		(property "Val" "100k"
			(at 0 0 0)
			(unlocked yes)
			(layer "B.Fab")
			(hide yes)
			(effects
				(font
					(size 1 1)
					(thickness 0.15)
				)
				(justify mirror)
			)
		)
		(property "Tolerance" "1%"
			(at 0 0 0)
			(unlocked yes)
			(layer "B.Fab")
			(hide yes)
			(effects
				(font
					(size 1 1)
					(thickness 0.15)
				)
				(justify mirror)
			)
		)
		(property "Author" "Antmicro"
			(at 0 0 0)
			(unlocked yes)
			(layer "B.Fab")
			(hide yes)
			(effects
				(font
					(size 1 1)
					(thickness 0.15)
				)
				(justify mirror)
			)
		)
		(sheetname "/TB Controller/")
		(sheetfile "tb.kicad_sch")
		(attr smd)
		(fp_rect
			(start -0.925 0.47)
			(end 0.925 -0.47)
			(stroke
				(width 0.05)
				(type default)
			)
			(fill no)
			(layer "B.CrtYd")
		)
		(fp_rect
			(start -0.5 0.25)
			(end 0.5 -0.25)
			(stroke
				(width 0.15)
				(type solid)
			)
			(fill no)
			(layer "B.Fab")
		)
		(fp_text user "${REFERENCE}"
			(at -0.95 -3.168 180)
			(layer "B.Fab")
			(effects
				(font
					(size 0.7 0.7)
					(thickness 0.15)
				)
				(justify left bottom mirror)
			)
		)
		(fp_text user "Author: Antmicro"
			(at -0.95 -4.169 180)
			(layer "B.Fab")
			(effects
				(font
					(size 0.7 0.7)
					(thickness 0.15)
				)
				(justify left bottom mirror)
			)
		)
		(fp_text user "License: Apache-2.0"
			(at -0.95 -5.169 180)
			(layer "B.Fab")
			(effects
				(font
					(size 0.7 0.7)
					(thickness 0.15)
				)
				(justify left bottom mirror)
			)
		)
		(pad "1" smd roundrect
			(at -0.48 0)
			(size 0.59 0.64)
			(layers "B.Cu" "B.Mask" "B.Paste")
			(roundrect_rratio 0.25)
			(net 184 "Net-(U4C-DPSRC_HPD)")
			(pintype "passive")
		)
		(pad "2" smd roundrect
			(at 0.48 0)
			(size 0.59 0.64)
			(layers "B.Cu" "B.Mask" "B.Paste")
			(roundrect_rratio 0.25)
			(net 23 "GND")
			(pintype "passive")
		)
	)
	(footprint "antmicro-footprints:R_0402_1005Metric"
		(layer "B.Cu")
		(at 148.425 85.925 180)
		(descr "Resistor SMD 0402")
		(tags "resistor SMD 0402")
		(property "Reference" "R180"
			(at -17.975 -9.475 0)
			(layer "B.SilkS")
			(effects
				(font
					(size 0.7 0.7)
					(thickness 0.15)
				)
				(justify mirror)
			)
		)
		(property "Value" "R_10k_0402"
			(at -1.011843 -1.772047 0)
			(layer "B.Fab")
			(effects
				(font
					(size 0.7 0.7)
					(thickness 0.15)
				)
				(justify left bottom mirror)
			)
		)
		(property "Datasheet" "https://www.bourns.com/docs/product-datasheets/cr.pdf"
			(at 0 0 0)
			(layer "B.Fab")
			(hide yes)
			(effects
				(font
					(size 1.27 1.27)
					(thickness 0.15)
				)
				(justify mirror)
			)
		)
		(property "Description" "SMD Chip Resistor, 10 kohm, ± 1%, 62.5 mW, 0402 [1005 Metric], Thick Film, General Purpose"
			(at 0 0 0)
			(layer "B.Fab")
			(hide yes)
			(effects
				(font
					(size 1.27 1.27)
					(thickness 0.15)
				)
				(justify mirror)
			)
		)
		(property "MPN" "CR0402-FX-1002GLF"
			(at 0 0 180)
			(unlocked yes)
			(layer "B.Fab")
			(hide yes)
			(effects
				(font
					(size 1 1)
					(thickness 0.15)
				)
				(justify mirror)
			)
		)
		(property "Manufacturer" "Bourns"
			(at 0 0 180)
			(unlocked yes)
			(layer "B.Fab")
			(hide yes)
			(effects
				(font
					(size 1 1)
					(thickness 0.15)
				)
				(justify mirror)
			)
		)
		(property "License" "Apache-2.0"
			(at 0 0 180)
			(unlocked yes)
			(layer "B.Fab")
			(hide yes)
			(effects
				(font
					(size 1 1)
					(thickness 0.15)
				)
				(justify mirror)
			)
		)
		(property "Author" "Antmicro"
			(at 0 0 180)
			(unlocked yes)
			(layer "B.Fab")
			(hide yes)
			(effects
				(font
					(size 1 1)
					(thickness 0.15)
				)
				(justify mirror)
			)
		)
		(property "Val" "10k"
			(at 0 0 180)
			(unlocked yes)
			(layer "B.Fab")
			(hide yes)
			(effects
				(font
					(size 1 1)
					(thickness 0.15)
				)
				(justify mirror)
			)
		)
		(property "Tolerance" "1%"
			(at 0 0 180)
			(unlocked yes)
			(layer "B.Fab")
			(hide yes)
			(effects
				(font
					(size 1 1)
					(thickness 0.15)
				)
				(justify mirror)
			)
		)
		(sheetname "/X710-AT2 Misc/")
		(sheetfile "x710-at2-mics.kicad_sch")
		(attr smd)
		(fp_rect
			(start -0.925 0.47)
			(end 0.925 -0.47)
			(stroke
				(width 0.05)
				(type default)
			)
			(fill no)
			(layer "B.CrtYd")
		)
		(fp_rect
			(start -0.5 0.25)
			(end 0.5 -0.25)
			(stroke
				(width 0.15)
				(type solid)
			)
			(fill no)
			(layer "B.Fab")
		)
		(fp_text user "Author: Antmicro"
			(at -0.95 -4.169 0)
			(layer "B.Fab")
			(effects
				(font
					(size 0.7 0.7)
					(thickness 0.15)
				)
				(justify left bottom mirror)
			)
		)
		(fp_text user "${REFERENCE}"
			(at -0.95 -3.168 0)
			(layer "B.Fab")
			(effects
				(font
					(size 0.7 0.7)
					(thickness 0.15)
				)
				(justify left bottom mirror)
			)
		)
		(fp_text user "License: Apache-2.0"
			(at -0.95 -5.169 0)
			(layer "B.Fab")
			(effects
				(font
					(size 0.7 0.7)
					(thickness 0.15)
				)
				(justify left bottom mirror)
			)
		)
		(pad "1" smd roundrect
			(at -0.48 0 180)
			(size 0.59 0.64)
			(layers "B.Cu" "B.Mask" "B.Paste")
			(roundrect_rratio 0.25)
			(net 445 "Net-(U14D-SMBD)")
			(pintype "passive")
		)
		(pad "2" smd roundrect
			(at 0.48 0 180)
			(size 0.59 0.64)
			(layers "B.Cu" "B.Mask" "B.Paste")
			(roundrect_rratio 0.25)
			(net 7 "+3V3")
			(pintype "passive")
		)
	)
	(footprint "antmicro-footprints:C_0402_1005Metric"
		(layer "B.Cu")
		(at 153.031866 80.260117 180)
		(descr "Capacitor SMD 0402")
		(tags "capacitor SMD 0402")
		(property "Reference" "C264"
			(at -21.168135 -9.464883 0)
			(layer "B.SilkS")
			(effects
				(font
					(size 0.7 0.7)
					(thickness 0.15)
				)
				(justify mirror)
			)
		)
		(property "Value" "C_1u_25V_0402"
			(at -1.022927 -2.155213 0)
			(layer "B.Fab")
			(effects
				(font
					(size 0.7 0.7)
					(thickness 0.15)
				)
				(justify left bottom mirror)
			)
		)
		(property "Datasheet" "https://www.murata.com/products/productdetail?partno=GRM155R61E105KE11%23"
			(at 0 0 0)
			(layer "B.Fab")
			(hide yes)
			(effects
				(font
					(size 1.27 1.27)
					(thickness 0.15)
				)
				(justify mirror)
			)
		)
		(property "Description" "SMD Multilayer Ceramic Capacitor, 1 µF, 25 V, 0402 [1005 Metric], ± 10%, X5R, GRM Series"
			(at 0 0 0)
			(layer "B.Fab")
			(hide yes)
			(effects
				(font
					(size 1.27 1.27)
					(thickness 0.15)
				)
				(justify mirror)
			)
		)
		(property "MPN" "GRM155R61E105KE11J"
			(at 0 0 180)
			(unlocked yes)
			(layer "B.Fab")
			(hide yes)
			(effects
				(font
					(size 1 1)
					(thickness 0.15)
				)
				(justify mirror)
			)
		)
		(property "Manufacturer" "Murata"
			(at 0 0 180)
			(unlocked yes)
			(layer "B.Fab")
			(hide yes)
			(effects
				(font
					(size 1 1)
					(thickness 0.15)
				)
				(justify mirror)
			)
		)
		(property "License" "Apache-2.0"
			(at 0 0 180)
			(unlocked yes)
			(layer "B.Fab")
			(hide yes)
			(effects
				(font
					(size 1 1)
					(thickness 0.15)
				)
				(justify mirror)
			)
		)
		(property "Author" "Antmicro"
			(at 0 0 180)
			(unlocked yes)
			(layer "B.Fab")
			(hide yes)
			(effects
				(font
					(size 1 1)
					(thickness 0.15)
				)
				(justify mirror)
			)
		)
		(property "Val" "1u"
			(at 0 0 180)
			(unlocked yes)
			(layer "B.Fab")
			(hide yes)
			(effects
				(font
					(size 1 1)
					(thickness 0.15)
				)
				(justify mirror)
			)
		)
		(property "Voltage" "25V"
			(at 0 0 180)
			(unlocked yes)
			(layer "B.Fab")
			(hide yes)
			(effects
				(font
					(size 1 1)
					(thickness 0.15)
				)
				(justify mirror)
			)
		)
		(property "Dielectric" "X5R"
			(at 0 0 180)
			(unlocked yes)
			(layer "B.Fab")
			(hide yes)
			(effects
				(font
					(size 1 1)
					(thickness 0.15)
				)
				(justify mirror)
			)
		)
		(sheetname "/X710-AT2 power/")
		(sheetfile "x710-at2-power.kicad_sch")
		(attr smd)
		(fp_rect
			(start -0.925 0.47)
			(end 0.925 -0.47)
			(stroke
				(width 0.05)
				(type default)
			)
			(fill no)
			(layer "B.CrtYd")
		)
		(fp_line
			(start 0.504 0.25)
			(end 0.504 -0.248)
			(stroke
				(width 0.15)
				(type solid)
			)
			(layer "B.Fab")
		)
		(fp_line
			(start 0.504 -0.248)
			(end -0.494 -0.248)
			(stroke
				(width 0.15)
				(type solid)
			)
			(layer "B.Fab")
		)
		(fp_line
			(start -0.494 0.25)
			(end 0.504 0.25)
			(stroke
				(width 0.15)
				(type solid)
			)
			(layer "B.Fab")
		)
		(fp_line
			(start -0.494 -0.248)
			(end -0.494 0.25)
			(stroke
				(width 0.15)
				(type solid)
			)
			(layer "B.Fab")
		)
		(fp_text user "Author: Antmicro"
			(at -0.939 -3.399 0)
			(layer "B.Fab")
			(effects
				(font
					(size 0.7 0.7)
					(thickness 0.15)
				)
				(justify left bottom mirror)
			)
		)
		(fp_text user "${REFERENCE}"
			(at -0.939 -4.599 0)
			(layer "B.Fab")
			(effects
				(font
					(size 0.7 0.7)
					(thickness 0.15)
				)
				(justify left bottom mirror)
			)
		)
		(fp_text user "License: Apache-2.0"
			(at -0.939 -5.799 0)
			(layer "B.Fab")
			(effects
				(font
					(size 0.7 0.7)
					(thickness 0.15)
				)
				(justify left bottom mirror)
			)
		)
		(pad "1" smd roundrect
			(at -0.48 0 180)
			(size 0.59 0.64)
			(layers "B.Cu" "B.Mask" "B.Paste")
			(roundrect_rratio 0.25)
			(net 23 "GND")
			(pintype "passive")
		)
		(pad "2" smd roundrect
			(at 0.48 0 180)
			(size 0.59 0.64)
			(layers "B.Cu" "B.Mask" "B.Paste")
			(roundrect_rratio 0.25)
			(net 9 "VCCD")
			(pintype "passive")
		)
	)
	(footprint "antmicro-footprints:R_0402_1005Metric"
		(layer "B.Cu")
		(at 122.75 127.025)
		(descr "Resistor SMD 0402")
		(tags "resistor SMD 0402")
		(property "Reference" "R56"
			(at -2.25 0 180)
			(layer "B.SilkS")
			(effects
				(font
					(size 0.7 0.7)
					(thickness 0.15)
				)
				(justify mirror)
			)
		)
		(property "Value" "R_499R_0402"
			(at -1.011843 -1.772047 180)
			(layer "B.Fab")
			(effects
				(font
					(size 0.7 0.7)
					(thickness 0.15)
				)
				(justify left bottom mirror)
			)
		)
		(property "Datasheet" "https://www.mouser.com/datasheet/2/54/cr-1858361.pdf"
			(at 0 0 180)
			(layer "B.Fab")
			(hide yes)
			(effects
				(font
					(size 1.27 1.27)
					(thickness 0.15)
				)
				(justify mirror)
			)
		)
		(property "Description" "SMD Chip Resistor, 499 ohm, ± 1%, 63 mW, 0402 [1005 Metric], Thick Film, General Purpose"
			(at 0 0 180)
			(layer "B.Fab")
			(hide yes)
			(effects
				(font
					(size 1.27 1.27)
					(thickness 0.15)
				)
				(justify mirror)
			)
		)
		(property "MPN" "CR0402-FX-4990GLF"
			(at 0 0 0)
			(unlocked yes)
			(layer "B.Fab")
			(hide yes)
			(effects
				(font
					(size 1 1)
					(thickness 0.15)
				)
				(justify mirror)
			)
		)
		(property "Manufacturer" "Bourns"
			(at 0 0 0)
			(unlocked yes)
			(layer "B.Fab")
			(hide yes)
			(effects
				(font
					(size 1 1)
					(thickness 0.15)
				)
				(justify mirror)
			)
		)
		(property "License" "Apache-2.0"
			(at 0 0 0)
			(unlocked yes)
			(layer "B.Fab")
			(hide yes)
			(effects
				(font
					(size 1 1)
					(thickness 0.15)
				)
				(justify mirror)
			)
		)
		(property "Val" "499R"
			(at 0 0 0)
			(unlocked yes)
			(layer "B.Fab")
			(hide yes)
			(effects
				(font
					(size 1 1)
					(thickness 0.15)
				)
				(justify mirror)
			)
		)
		(property "Tolerance" "1%"
			(at 0 0 0)
			(unlocked yes)
			(layer "B.Fab")
			(hide yes)
			(effects
				(font
					(size 1 1)
					(thickness 0.15)
				)
				(justify mirror)
			)
		)
		(property "Author" "Antmicro"
			(at 0 0 0)
			(unlocked yes)
			(layer "B.Fab")
			(hide yes)
			(effects
				(font
					(size 1 1)
					(thickness 0.15)
				)
				(justify mirror)
			)
		)
		(sheetname "/TB Controller/")
		(sheetfile "tb.kicad_sch")
		(attr smd)
		(fp_rect
			(start -0.925 0.47)
			(end 0.925 -0.47)
			(stroke
				(width 0.05)
				(type default)
			)
			(fill no)
			(layer "B.CrtYd")
		)
		(fp_rect
			(start -0.5 0.25)
			(end 0.5 -0.25)
			(stroke
				(width 0.15)
				(type solid)
			)
			(fill no)
			(layer "B.Fab")
		)
		(fp_text user "Author: Antmicro"
			(at -0.95 -4.169 180)
			(layer "B.Fab")
			(effects
				(font
					(size 0.7 0.7)
					(thickness 0.15)
				)
				(justify left bottom mirror)
			)
		)
		(fp_text user "License: Apache-2.0"
			(at -0.95 -5.169 180)
			(layer "B.Fab")
			(effects
				(font
					(size 0.7 0.7)
					(thickness 0.15)
				)
				(justify left bottom mirror)
			)
		)
		(fp_text user "${REFERENCE}"
			(at -0.95 -3.168 180)
			(layer "B.Fab")
			(effects
				(font
					(size 0.7 0.7)
					(thickness 0.15)
				)
				(justify left bottom mirror)
			)
		)
		(pad "1" smd roundrect
			(at -0.48 0)
			(size 0.59 0.64)
			(layers "B.Cu" "B.Mask" "B.Paste")
			(roundrect_rratio 0.25)
			(net 23 "GND")
			(pintype "passive")
		)
		(pad "2" smd roundrect
			(at 0.48 0)
			(size 0.59 0.64)
			(layers "B.Cu" "B.Mask" "B.Paste")
			(roundrect_rratio 0.25)
			(net 228 "Net-(U4E-PA_USB2_RBIAS)")
			(pintype "passive")
		)
	)
	(footprint "antmicro-footprints:R_0402_1005Metric"
		(layer "B.Cu")
		(at 136.5 124.15)
		(descr "Resistor SMD 0402")
		(tags "resistor SMD 0402")
		(property "Reference" "R68"
			(at 19.525001 -7.450001 180)
			(layer "B.SilkS")
			(effects
				(font
					(size 0.7 0.7)
					(thickness 0.15)
				)
				(justify mirror)
			)
		)
		(property "Value" "R_100R_0402"
			(at -1.011843 -1.772047 180)
			(layer "B.Fab")
			(effects
				(font
					(size 0.7 0.7)
					(thickness 0.15)
				)
				(justify left bottom mirror)
			)
		)
		(property "Datasheet" "https://www.bourns.com/docs/product-datasheets/cr.pdf"
			(at 0 0 180)
			(layer "B.Fab")
			(hide yes)
			(effects
				(font
					(size 1.27 1.27)
					(thickness 0.15)
				)
				(justify mirror)
			)
		)
		(property "Description" "SMD Chip Resistor, 100 ohm, ± 1%, 62.5 mW, 0402 [1005 Metric], Thick Film, General Purpose"
			(at 0 0 180)
			(layer "B.Fab")
			(hide yes)
			(effects
				(font
					(size 1.27 1.27)
					(thickness 0.15)
				)
				(justify mirror)
			)
		)
		(property "MPN" "CR0402-FX-1000GLF"
			(at 0 0 0)
			(unlocked yes)
			(layer "B.Fab")
			(hide yes)
			(effects
				(font
					(size 1 1)
					(thickness 0.15)
				)
				(justify mirror)
			)
		)
		(property "Manufacturer" "Bourns"
			(at 0 0 0)
			(unlocked yes)
			(layer "B.Fab")
			(hide yes)
			(effects
				(font
					(size 1 1)
					(thickness 0.15)
				)
				(justify mirror)
			)
		)
		(property "License" "Apache-2.0"
			(at 0 0 0)
			(unlocked yes)
			(layer "B.Fab")
			(hide yes)
			(effects
				(font
					(size 1 1)
					(thickness 0.15)
				)
				(justify mirror)
			)
		)
		(property "Val" "100R"
			(at 0 0 0)
			(unlocked yes)
			(layer "B.Fab")
			(hide yes)
			(effects
				(font
					(size 1 1)
					(thickness 0.15)
				)
				(justify mirror)
			)
		)
		(property "Tolerance" "1%"
			(at 0 0 0)
			(unlocked yes)
			(layer "B.Fab")
			(hide yes)
			(effects
				(font
					(size 1 1)
					(thickness 0.15)
				)
				(justify mirror)
			)
		)
		(property "Author" "Antmicro"
			(at 0 0 0)
			(unlocked yes)
			(layer "B.Fab")
			(hide yes)
			(effects
				(font
					(size 1 1)
					(thickness 0.15)
				)
				(justify mirror)
			)
		)
		(sheetname "/TB Controller/")
		(sheetfile "tb.kicad_sch")
		(attr smd)
		(fp_rect
			(start -0.925 0.47)
			(end 0.925 -0.47)
			(stroke
				(width 0.05)
				(type default)
			)
			(fill no)
			(layer "B.CrtYd")
		)
		(fp_rect
			(start -0.5 0.25)
			(end 0.5 -0.25)
			(stroke
				(width 0.15)
				(type solid)
			)
			(fill no)
			(layer "B.Fab")
		)
		(fp_text user "License: Apache-2.0"
			(at -0.95 -5.169 180)
			(layer "B.Fab")
			(effects
				(font
					(size 0.7 0.7)
					(thickness 0.15)
				)
				(justify left bottom mirror)
			)
		)
		(fp_text user "Author: Antmicro"
			(at -0.95 -4.169 180)
			(layer "B.Fab")
			(effects
				(font
					(size 0.7 0.7)
					(thickness 0.15)
				)
				(justify left bottom mirror)
			)
		)
		(fp_text user "${REFERENCE}"
			(at -0.95 -3.168 180)
			(layer "B.Fab")
			(effects
				(font
					(size 0.7 0.7)
					(thickness 0.15)
				)
				(justify left bottom mirror)
			)
		)
		(pad "1" smd roundrect
			(at -0.48 0)
			(size 0.59 0.64)
			(layers "B.Cu" "B.Mask" "B.Paste")
			(roundrect_rratio 0.25)
			(net 237 "Net-(U4D-TEST_EN)")
			(pintype "passive")
		)
		(pad "2" smd roundrect
			(at 0.48 0)
			(size 0.59 0.64)
			(layers "B.Cu" "B.Mask" "B.Paste")
			(roundrect_rratio 0.25)
			(net 23 "GND")
			(pintype "passive")
		)
	)
	(footprint "antmicro-footprints:C_0402_1005Metric"
		(layer "B.Cu")
		(at 128.499999 120.050001 -90)
		(descr "Capacitor SMD 0402")
		(tags "capacitor SMD 0402")
		(property "Reference" "C54"
			(at -7.700002 -21.900002 90)
			(layer "B.SilkS")
			(effects
				(font
					(size 0.7 0.7)
					(thickness 0.15)
				)
				(justify mirror)
			)
		)
		(property "Value" "C_1u_0402"
			(at -1.022927 -2.155213 90)
			(layer "B.Fab")
			(effects
				(font
					(size 0.7 0.7)
					(thickness 0.15)
				)
				(justify left bottom mirror)
			)
		)
		(property "Datasheet" "https://product.tdk.com/en/search/capacitor/ceramic/mlcc/info?part_no=C1005X6S1A105K050BC"
			(at 0 0 90)
			(layer "B.Fab")
			(hide yes)
			(effects
				(font
					(size 1.27 1.27)
					(thickness 0.15)
				)
				(justify mirror)
			)
		)
		(property "Description" "SMD Multilayer Ceramic Capacitor, 1 µF, 10 V, 0402 [1005 Metric], ± 10%, X6S, C"
			(at 0 0 90)
			(layer "B.Fab")
			(hide yes)
			(effects
				(font
					(size 1.27 1.27)
					(thickness 0.15)
				)
				(justify mirror)
			)
		)
		(property "MPN" "C1005X6S1A105K050BC"
			(at 0 0 270)
			(unlocked yes)
			(layer "B.Fab")
			(hide yes)
			(effects
				(font
					(size 1 1)
					(thickness 0.15)
				)
				(justify mirror)
			)
		)
		(property "Manufacturer" "TDK"
			(at 0 0 270)
			(unlocked yes)
			(layer "B.Fab")
			(hide yes)
			(effects
				(font
					(size 1 1)
					(thickness 0.15)
				)
				(justify mirror)
			)
		)
		(property "License" "Apache-2.0"
			(at 0 0 270)
			(unlocked yes)
			(layer "B.Fab")
			(hide yes)
			(effects
				(font
					(size 1 1)
					(thickness 0.15)
				)
				(justify mirror)
			)
		)
		(property "Val" "1u"
			(at 0 0 270)
			(unlocked yes)
			(layer "B.Fab")
			(hide yes)
			(effects
				(font
					(size 1 1)
					(thickness 0.15)
				)
				(justify mirror)
			)
		)
		(property "Voltage" ""
			(at 0 0 270)
			(unlocked yes)
			(layer "B.Fab")
			(hide yes)
			(effects
				(font
					(size 1 1)
					(thickness 0.15)
				)
				(justify mirror)
			)
		)
		(property "Dielectric" ""
			(at 0 0 270)
			(unlocked yes)
			(layer "B.Fab")
			(hide yes)
			(effects
				(font
					(size 1 1)
					(thickness 0.15)
				)
				(justify mirror)
			)
		)
		(property "Author" "Antmicro"
			(at 0 0 270)
			(unlocked yes)
			(layer "B.Fab")
			(hide yes)
			(effects
				(font
					(size 1 1)
					(thickness 0.15)
				)
				(justify mirror)
			)
		)
		(sheetname "/TB Controller - Power/")
		(sheetfile "tb-power.kicad_sch")
		(attr smd)
		(fp_rect
			(start -0.925 0.47)
			(end 0.925 -0.47)
			(stroke
				(width 0.05)
				(type default)
			)
			(fill no)
			(layer "B.CrtYd")
		)
		(fp_line
			(start -0.494 0.25)
			(end 0.504 0.25)
			(stroke
				(width 0.15)
				(type solid)
			)
			(layer "B.Fab")
		)
		(fp_line
			(start 0.504 0.25)
			(end 0.504 -0.248)
			(stroke
				(width 0.15)
				(type solid)
			)
			(layer "B.Fab")
		)
		(fp_line
			(start -0.494 -0.248)
			(end -0.494 0.25)
			(stroke
				(width 0.15)
				(type solid)
			)
			(layer "B.Fab")
		)
		(fp_line
			(start 0.504 -0.248)
			(end -0.494 -0.248)
			(stroke
				(width 0.15)
				(type solid)
			)
			(layer "B.Fab")
		)
		(fp_text user "Author: Antmicro"
			(at -0.939 -3.399 90)
			(layer "B.Fab")
			(effects
				(font
					(size 0.7 0.7)
					(thickness 0.15)
				)
				(justify left bottom mirror)
			)
		)
		(fp_text user "License: Apache-2.0"
			(at -0.939 -5.799 90)
			(layer "B.Fab")
			(effects
				(font
					(size 0.7 0.7)
					(thickness 0.15)
				)
				(justify left bottom mirror)
			)
		)
		(fp_text user "${REFERENCE}"
			(at -0.939 -4.599 90)
			(layer "B.Fab")
			(effects
				(font
					(size 0.7 0.7)
					(thickness 0.15)
				)
				(justify left bottom mirror)
			)
		)
		(pad "1" smd roundrect
			(at -0.48 0 270)
			(size 0.59 0.64)
			(layers "B.Cu" "B.Mask" "B.Paste")
			(roundrect_rratio 0.25)
			(net 23 "GND")
			(pintype "passive")
		)
		(pad "2" smd roundrect
			(at 0.48 0 270)
			(size 0.59 0.64)
			(layers "B.Cu" "B.Mask" "B.Paste")
			(roundrect_rratio 0.25)
			(net 402 "Net-(C52-Pad2)")
			(pintype "passive")
		)
	)
	(footprint "antmicro-footprints:R_0402_1005Metric"
		(layer "B.Cu")
		(at 176.58 146.66 90)
		(descr "Resistor SMD 0402")
		(tags "resistor SMD 0402")
		(property "Reference" "R213"
			(at -1.09 0.42 270)
			(layer "B.SilkS")
			(effects
				(font
					(size 0.7 0.7)
					(thickness 0.15)
				)
				(justify left bottom mirror)
			)
		)
		(property "Value" "R_220R_0402"
			(at -1.011843 -1.772047 270)
			(layer "B.Fab")
			(effects
				(font
					(size 0.7 0.7)
					(thickness 0.15)
				)
				(justify left bottom mirror)
			)
		)
		(property "Datasheet" "https://www.bourns.com/docs/product-datasheets/cr.pdf"
			(at 0 0 270)
			(layer "B.Fab")
			(hide yes)
			(effects
				(font
					(size 1.27 1.27)
					(thickness 0.15)
				)
				(justify mirror)
			)
		)
		(property "Description" "SMD Chip Resistor, 220 ohm, ± 1%, 62.5 mW, 0402 [1005 Metric], Thick Film, General Purpose"
			(at 0 0 270)
			(layer "B.Fab")
			(hide yes)
			(effects
				(font
					(size 1.27 1.27)
					(thickness 0.15)
				)
				(justify mirror)
			)
		)
		(property "MPN" "CR0402-FX-2200GLF"
			(at 0 0 90)
			(unlocked yes)
			(layer "B.Fab")
			(hide yes)
			(effects
				(font
					(size 1 1)
					(thickness 0.15)
				)
				(justify mirror)
			)
		)
		(property "Manufacturer" "Bourns"
			(at 0 0 90)
			(unlocked yes)
			(layer "B.Fab")
			(hide yes)
			(effects
				(font
					(size 1 1)
					(thickness 0.15)
				)
				(justify mirror)
			)
		)
		(property "License" "Apache-2.0"
			(at 0 0 90)
			(unlocked yes)
			(layer "B.Fab")
			(hide yes)
			(effects
				(font
					(size 1 1)
					(thickness 0.15)
				)
				(justify mirror)
			)
		)
		(property "Author" "Antmicro"
			(at 0 0 90)
			(unlocked yes)
			(layer "B.Fab")
			(hide yes)
			(effects
				(font
					(size 1 1)
					(thickness 0.15)
				)
				(justify mirror)
			)
		)
		(property "Val" "220R"
			(at 0 0 90)
			(unlocked yes)
			(layer "B.Fab")
			(hide yes)
			(effects
				(font
					(size 1 1)
					(thickness 0.15)
				)
				(justify mirror)
			)
		)
		(property "Tolerance" "1%"
			(at 0 0 90)
			(unlocked yes)
			(layer "B.Fab")
			(hide yes)
			(effects
				(font
					(size 1 1)
					(thickness 0.15)
				)
				(justify mirror)
			)
		)
		(sheetname "/2xRJ45/")
		(sheetfile "2xrj45.kicad_sch")
		(attr smd)
		(fp_rect
			(start -0.925 0.47)
			(end 0.925 -0.47)
			(stroke
				(width 0.05)
				(type default)
			)
			(fill no)
			(layer "B.CrtYd")
		)
		(fp_rect
			(start -0.5 0.25)
			(end 0.5 -0.25)
			(stroke
				(width 0.15)
				(type solid)
			)
			(fill no)
			(layer "B.Fab")
		)
		(fp_text user "Author: Antmicro"
			(at -0.95 -4.169 270)
			(layer "B.Fab")
			(effects
				(font
					(size 0.7 0.7)
					(thickness 0.15)
				)
				(justify left bottom mirror)
			)
		)
		(fp_text user "${REFERENCE}"
			(at -0.95 -3.168 270)
			(layer "B.Fab")
			(effects
				(font
					(size 0.7 0.7)
					(thickness 0.15)
				)
				(justify left bottom mirror)
			)
		)
		(fp_text user "License: Apache-2.0"
			(at -0.95 -5.169 270)
			(layer "B.Fab")
			(effects
				(font
					(size 0.7 0.7)
					(thickness 0.15)
				)
				(justify left bottom mirror)
			)
		)
		(pad "1" smd roundrect
			(at -0.48 0 90)
			(size 0.59 0.64)
			(layers "B.Cu" "B.Mask" "B.Paste")
			(roundrect_rratio 0.25)
			(net 407 "Net-(J4-LED_YG_Y-)")
			(pintype "passive")
		)
		(pad "2" smd roundrect
			(at 0.48 0 90)
			(size 0.59 0.64)
			(layers "B.Cu" "B.Mask" "B.Paste")
			(roundrect_rratio 0.25)
			(net 65 "/2xRJ45/~{P1_LINK_LESS_THAN_10G}")
			(pintype "passive")
		)
	)
	(footprint "antmicro-footprints:R_0402_1005Metric"
		(layer "B.Cu")
		(at 135.6 127.6)
		(descr "Resistor SMD 0402")
		(tags "resistor SMD 0402")
		(property "Reference" "R58"
			(at 19.525001 -7.450001 180)
			(layer "B.SilkS")
			(effects
				(font
					(size 0.7 0.7)
					(thickness 0.15)
				)
				(justify mirror)
			)
		)
		(property "Value" "R_1M_0402"
			(at -1.011843 -1.772047 180)
			(layer "B.Fab")
			(effects
				(font
					(size 0.7 0.7)
					(thickness 0.15)
				)
				(justify left bottom mirror)
			)
		)
		(property "Datasheet" "https://www.bourns.com/docs/product-datasheets/cr.pdf"
			(at 0 0 180)
			(layer "B.Fab")
			(hide yes)
			(effects
				(font
					(size 1.27 1.27)
					(thickness 0.15)
				)
				(justify mirror)
			)
		)
		(property "Description" "SMD Chip Resistor, 1 Mohm, ± 1%, 62.5 mW, 0402 [1005 Metric], Thick Film, General Purpose"
			(at 0 0 180)
			(layer "B.Fab")
			(hide yes)
			(effects
				(font
					(size 1.27 1.27)
					(thickness 0.15)
				)
				(justify mirror)
			)
		)
		(property "MPN" "CR0402-FX-1004GLF"
			(at 0 0 0)
			(unlocked yes)
			(layer "B.Fab")
			(hide yes)
			(effects
				(font
					(size 1 1)
					(thickness 0.15)
				)
				(justify mirror)
			)
		)
		(property "Manufacturer" "Bourns"
			(at 0 0 0)
			(unlocked yes)
			(layer "B.Fab")
			(hide yes)
			(effects
				(font
					(size 1 1)
					(thickness 0.15)
				)
				(justify mirror)
			)
		)
		(property "License" "Apache-2.0"
			(at 0 0 0)
			(unlocked yes)
			(layer "B.Fab")
			(hide yes)
			(effects
				(font
					(size 1 1)
					(thickness 0.15)
				)
				(justify mirror)
			)
		)
		(property "Val" "1M"
			(at 0 0 0)
			(unlocked yes)
			(layer "B.Fab")
			(hide yes)
			(effects
				(font
					(size 1 1)
					(thickness 0.15)
				)
				(justify mirror)
			)
		)
		(property "Tolerance" "1%"
			(at 0 0 0)
			(unlocked yes)
			(layer "B.Fab")
			(hide yes)
			(effects
				(font
					(size 1 1)
					(thickness 0.15)
				)
				(justify mirror)
			)
		)
		(property "Author" "Antmicro"
			(at 0 0 0)
			(unlocked yes)
			(layer "B.Fab")
			(hide yes)
			(effects
				(font
					(size 1 1)
					(thickness 0.15)
				)
				(justify mirror)
			)
		)
		(sheetname "/TB Controller/")
		(sheetfile "tb.kicad_sch")
		(attr smd)
		(fp_rect
			(start -0.925 0.47)
			(end 0.925 -0.47)
			(stroke
				(width 0.05)
				(type default)
			)
			(fill no)
			(layer "B.CrtYd")
		)
		(fp_rect
			(start -0.5 0.25)
			(end 0.5 -0.25)
			(stroke
				(width 0.15)
				(type solid)
			)
			(fill no)
			(layer "B.Fab")
		)
		(fp_text user "License: Apache-2.0"
			(at -0.95 -5.169 180)
			(layer "B.Fab")
			(effects
				(font
					(size 0.7 0.7)
					(thickness 0.15)
				)
				(justify left bottom mirror)
			)
		)
		(fp_text user "Author: Antmicro"
			(at -0.95 -4.169 180)
			(layer "B.Fab")
			(effects
				(font
					(size 0.7 0.7)
					(thickness 0.15)
				)
				(justify left bottom mirror)
			)
		)
		(fp_text user "${REFERENCE}"
			(at -0.95 -3.168 180)
			(layer "B.Fab")
			(effects
				(font
					(size 0.7 0.7)
					(thickness 0.15)
				)
				(justify left bottom mirror)
			)
		)
		(pad "1" smd roundrect
			(at -0.48 0)
			(size 0.59 0.64)
			(layers "B.Cu" "B.Mask" "B.Paste")
			(roundrect_rratio 0.25)
			(net 231 "Net-(U4E-PB_LSTX)")
			(pintype "passive")
		)
		(pad "2" smd roundrect
			(at 0.48 0)
			(size 0.59 0.64)
			(layers "B.Cu" "B.Mask" "B.Paste")
			(roundrect_rratio 0.25)
			(net 23 "GND")
			(pintype "passive")
		)
	)
	(footprint "antmicro-footprints:SOT-323"
		(layer "B.Cu")
		(at 119.5 92.2 90)
		(property "Reference" "Q1"
			(at -5.6 0.7 270)
			(layer "B.SilkS")
			(effects
				(font
					(size 0.7 0.7)
					(thickness 0.15)
				)
				(justify left bottom mirror)
			)
		)
		(property "Value" "BC817-25W"
			(at 0 -2.749 270)
			(layer "B.Fab")
			(effects
				(font
					(size 0.7 0.7)
					(thickness 0.15)
				)
				(justify left bottom mirror)
			)
		)
		(property "Datasheet" "https://assets.nexperia.com/documents/data-sheet/BC817W_SER.pdf"
			(at 0 0 270)
			(layer "B.Fab")
			(hide yes)
			(effects
				(font
					(size 1.27 1.27)
					(thickness 0.15)
				)
				(justify mirror)
			)
		)
		(property "Description" "Bipolar (BJT) Single Transistor, NPN, 45 V, 500 mA, 200 mW, SOT-323, Surface Mount"
			(at 0 0 270)
			(layer "B.Fab")
			(hide yes)
			(effects
				(font
					(size 1.27 1.27)
					(thickness 0.15)
				)
				(justify mirror)
			)
		)
		(property "MPN" "BC817-25W,115"
			(at 0 0 90)
			(unlocked yes)
			(layer "B.Fab")
			(hide yes)
			(effects
				(font
					(size 1 1)
					(thickness 0.15)
				)
				(justify mirror)
			)
		)
		(property "Manufacturer" "Nexperia"
			(at 0 0 90)
			(unlocked yes)
			(layer "B.Fab")
			(hide yes)
			(effects
				(font
					(size 1 1)
					(thickness 0.15)
				)
				(justify mirror)
			)
		)
		(property "License" "Apache-2.0"
			(at 0 0 90)
			(unlocked yes)
			(layer "B.Fab")
			(hide yes)
			(effects
				(font
					(size 1 1)
					(thickness 0.15)
				)
				(justify mirror)
			)
		)
		(property "Author" "Antmicro"
			(at 0 0 90)
			(unlocked yes)
			(layer "B.Fab")
			(hide yes)
			(effects
				(font
					(size 1 1)
					(thickness 0.15)
				)
				(justify mirror)
			)
		)
		(property ki_fp_filters "SOT?323*")
		(sheetname "/TB Controller - Power/")
		(sheetfile "tb-power.kicad_sch")
		(attr smd)
		(fp_line
			(start 0.8 -1.199)
			(end 0.8 -0.9)
			(stroke
				(width 0.15)
				(type solid)
			)
			(layer "B.SilkS")
		)
		(fp_line
			(start 0.498 -1.199)
			(end 0.8 -1.199)
			(stroke
				(width 0.15)
				(type solid)
			)
			(layer "B.SilkS")
		)
		(fp_line
			(start -0.802 -1.199)
			(end -0.5 -1.199)
			(stroke
				(width 0.15)
				(type solid)
			)
			(layer "B.SilkS")
		)
		(fp_line
			(start -0.802 -1.05)
			(end -0.802 -1.199)
			(stroke
				(width 0.15)
				(type solid)
			)
			(layer "B.SilkS")
		)
		(fp_line
			(start 0.8 1.2)
			(end 0.8 0.902)
			(stroke
				(width 0.15)
				(type solid)
			)
			(layer "B.SilkS")
		)
		(fp_line
			(start 0.498 1.2)
			(end 0.8 1.2)
			(stroke
				(width 0.15)
				(type solid)
			)
			(layer "B.SilkS")
		)
		(fp_line
			(start -0.402 1.2)
			(end -0.802 1.2)
			(stroke
				(width 0.15)
				(type solid)
			)
			(layer "B.SilkS")
		)
		(fp_line
			(start -0.802 1.2)
			(end -0.802 1.05)
			(stroke
				(width 0.15)
				(type solid)
			)
			(layer "B.SilkS")
		)
		(fp_circle
			(center -1.05 1.156824)
			(end -1 1.129824)
			(stroke
				(width 0.15)
				(type solid)
			)
			(fill no)
			(layer "B.SilkS")
		)
		(fp_rect
			(start -1.35 1.35)
			(end 1.35 -1.35)
			(stroke
				(width 0.05)
				(type solid)
			)
			(fill no)
			(layer "B.CrtYd")
		)
		(fp_line
			(start -0.677 -1.1)
			(end 0.675 -1.1)
			(stroke
				(width 0.15)
				(type solid)
			)
			(layer "B.Fab")
		)
		(fp_line
			(start 0.675 1.101)
			(end 0.675 -1.1)
			(stroke
				(width 0.15)
				(type solid)
			)
			(layer "B.Fab")
		)
		(fp_line
			(start -0.677 1.101)
			(end -0.677 -1.1)
			(stroke
				(width 0.15)
				(type solid)
			)
			(layer "B.Fab")
		)
		(fp_line
			(start -0.677 1.101)
			(end 0.675 1.101)
			(stroke
				(width 0.15)
				(type solid)
			)
			(layer "B.Fab")
		)
		(fp_text user "${REFERENCE}"
			(at -1.35 -4.749 270)
			(layer "B.Fab")
			(effects
				(font
					(size 0.7 0.7)
					(thickness 0.15)
				)
				(justify left bottom mirror)
			)
		)
		(fp_text user "License: Apache-2.0"
			(at -1.35 -5.949 270)
			(layer "B.Fab")
			(effects
				(font
					(size 0.7 0.7)
					(thickness 0.15)
				)
				(justify left bottom mirror)
			)
		)
		(fp_text user "Author: Antmicro"
			(at -1.35 -7.149 270)
			(layer "B.Fab")
			(effects
				(font
					(size 0.7 0.7)
					(thickness 0.15)
				)
				(justify left bottom mirror)
			)
		)
		(pad "1" smd rect
			(at -0.927 0.652 90)
			(size 0.55 0.6)
			(layers "B.Cu" "B.Mask" "B.Paste")
			(net 196 "Net-(Q1-B)")
			(pinfunction "B")
			(pintype "input")
		)
		(pad "2" smd rect
			(at -0.927 -0.65 90)
			(size 0.55 0.6)
			(layers "B.Cu" "B.Mask" "B.Paste")
			(net 23 "GND")
			(pinfunction "E")
			(pintype "passive")
		)
		(pad "3" smd rect
			(at 0.925 0 90)
			(size 0.55 0.6)
			(layers "B.Cu" "B.Mask" "B.Paste")
			(net 197 "Net-(Q1-C)")
			(pinfunction "C")
			(pintype "passive")
		)
	)
	(footprint "antmicro-footprints:C_0402_1005Metric"
		(layer "B.Cu")
		(at 166.1 133.25)
		(descr "Capacitor SMD 0402")
		(tags "capacitor SMD 0402")
		(property "Reference" "C295"
			(at 1.4 -0.5 180)
			(layer "B.SilkS")
			(effects
				(font
					(size 0.7 0.7)
					(thickness 0.15)
				)
				(justify left bottom mirror)
			)
		)
		(property "Value" "C_1u_25V_0402"
			(at -1.022927 -2.155213 180)
			(layer "B.Fab")
			(effects
				(font
					(size 0.7 0.7)
					(thickness 0.15)
				)
				(justify left bottom mirror)
			)
		)
		(property "Datasheet" "https://www.murata.com/products/productdetail?partno=GRM155R61E105KE11%23"
			(at 0 0 180)
			(layer "B.Fab")
			(hide yes)
			(effects
				(font
					(size 1.27 1.27)
					(thickness 0.15)
				)
				(justify mirror)
			)
		)
		(property "Description" "SMD Multilayer Ceramic Capacitor, 1 µF, 25 V, 0402 [1005 Metric], ± 10%, X5R, GRM Series"
			(at 0 0 180)
			(layer "B.Fab")
			(hide yes)
			(effects
				(font
					(size 1.27 1.27)
					(thickness 0.15)
				)
				(justify mirror)
			)
		)
		(property "MPN" "GRM155R61E105KE11J"
			(at 0 0 0)
			(unlocked yes)
			(layer "B.Fab")
			(hide yes)
			(effects
				(font
					(size 1 1)
					(thickness 0.15)
				)
				(justify mirror)
			)
		)
		(property "Manufacturer" "Murata"
			(at 0 0 0)
			(unlocked yes)
			(layer "B.Fab")
			(hide yes)
			(effects
				(font
					(size 1 1)
					(thickness 0.15)
				)
				(justify mirror)
			)
		)
		(property "License" "Apache-2.0"
			(at 0 0 0)
			(unlocked yes)
			(layer "B.Fab")
			(hide yes)
			(effects
				(font
					(size 1 1)
					(thickness 0.15)
				)
				(justify mirror)
			)
		)
		(property "Author" "Antmicro"
			(at 0 0 0)
			(unlocked yes)
			(layer "B.Fab")
			(hide yes)
			(effects
				(font
					(size 1 1)
					(thickness 0.15)
				)
				(justify mirror)
			)
		)
		(property "Val" "1u"
			(at 0 0 0)
			(unlocked yes)
			(layer "B.Fab")
			(hide yes)
			(effects
				(font
					(size 1 1)
					(thickness 0.15)
				)
				(justify mirror)
			)
		)
		(property "Voltage" "25V"
			(at 0 0 0)
			(unlocked yes)
			(layer "B.Fab")
			(hide yes)
			(effects
				(font
					(size 1 1)
					(thickness 0.15)
				)
				(justify mirror)
			)
		)
		(property "Dielectric" "X5R"
			(at 0 0 0)
			(unlocked yes)
			(layer "B.Fab")
			(hide yes)
			(effects
				(font
					(size 1 1)
					(thickness 0.15)
				)
				(justify mirror)
			)
		)
		(sheetname "/2xRJ45/")
		(sheetfile "2xrj45.kicad_sch")
		(attr smd)
		(fp_rect
			(start -0.925 0.47)
			(end 0.925 -0.47)
			(stroke
				(width 0.05)
				(type default)
			)
			(fill no)
			(layer "B.CrtYd")
		)
		(fp_line
			(start -0.494 -0.248)
			(end -0.494 0.25)
			(stroke
				(width 0.15)
				(type solid)
			)
			(layer "B.Fab")
		)
		(fp_line
			(start -0.494 0.25)
			(end 0.504 0.25)
			(stroke
				(width 0.15)
				(type solid)
			)
			(layer "B.Fab")
		)
		(fp_line
			(start 0.504 -0.248)
			(end -0.494 -0.248)
			(stroke
				(width 0.15)
				(type solid)
			)
			(layer "B.Fab")
		)
		(fp_line
			(start 0.504 0.25)
			(end 0.504 -0.248)
			(stroke
				(width 0.15)
				(type solid)
			)
			(layer "B.Fab")
		)
		(fp_text user "Author: Antmicro"
			(at -0.939 -3.399 180)
			(layer "B.Fab")
			(effects
				(font
					(size 0.7 0.7)
					(thickness 0.15)
				)
				(justify left bottom mirror)
			)
		)
		(fp_text user "License: Apache-2.0"
			(at -0.939 -5.799 180)
			(layer "B.Fab")
			(effects
				(font
					(size 0.7 0.7)
					(thickness 0.15)
				)
				(justify left bottom mirror)
			)
		)
		(fp_text user "${REFERENCE}"
			(at -0.939 -4.599 180)
			(layer "B.Fab")
			(effects
				(font
					(size 0.7 0.7)
					(thickness 0.15)
				)
				(justify left bottom mirror)
			)
		)
		(pad "1" smd roundrect
			(at -0.48 0)
			(size 0.59 0.64)
			(layers "B.Cu" "B.Mask" "B.Paste")
			(roundrect_rratio 0.25)
			(net 23 "GND")
			(pintype "passive")
		)
		(pad "2" smd roundrect
			(at 0.48 0)
			(size 0.59 0.64)
			(layers "B.Cu" "B.Mask" "B.Paste")
			(roundrect_rratio 0.25)
			(net 134 "/2xRJ45/P1_CT")
			(pintype "passive")
		)
	)
	(footprint "antmicro-footprints:R_0402_1005Metric"
		(layer "B.Cu")
		(at 149.131866 70.035118 90)
		(descr "Resistor SMD 0402")
		(tags "resistor SMD 0402")
		(property "Reference" "R195"
			(at -9.464883 19.468134 270)
			(layer "B.SilkS")
			(effects
				(font
					(size 0.7 0.7)
					(thickness 0.15)
				)
				(justify mirror)
			)
		)
		(property "Value" "R_3k3_0402"
			(at -1.011843 -1.772047 270)
			(layer "B.Fab")
			(effects
				(font
					(size 0.7 0.7)
					(thickness 0.15)
				)
				(justify left bottom mirror)
			)
		)
		(property "Datasheet" "https://www.bourns.com/docs/product-datasheets/cr.pdf"
			(at 0 0 270)
			(layer "B.Fab")
			(hide yes)
			(effects
				(font
					(size 1.27 1.27)
					(thickness 0.15)
				)
				(justify mirror)
			)
		)
		(property "Description" "SMD Chip Resistor, 3.3 kohm, ± 1%, 63 mW, 0402 [1005 Metric], Thick Film, General Purpose"
			(at 0 0 270)
			(layer "B.Fab")
			(hide yes)
			(effects
				(font
					(size 1.27 1.27)
					(thickness 0.15)
				)
				(justify mirror)
			)
		)
		(property "MPN" "CR0402-FX-3301GLF"
			(at 0 0 90)
			(unlocked yes)
			(layer "B.Fab")
			(hide yes)
			(effects
				(font
					(size 1 1)
					(thickness 0.15)
				)
				(justify mirror)
			)
		)
		(property "Manufacturer" "Bourns"
			(at 0 0 90)
			(unlocked yes)
			(layer "B.Fab")
			(hide yes)
			(effects
				(font
					(size 1 1)
					(thickness 0.15)
				)
				(justify mirror)
			)
		)
		(property "License" "Apache-2.0"
			(at 0 0 90)
			(unlocked yes)
			(layer "B.Fab")
			(hide yes)
			(effects
				(font
					(size 1 1)
					(thickness 0.15)
				)
				(justify mirror)
			)
		)
		(property "Author" "Antmicro"
			(at 0 0 90)
			(unlocked yes)
			(layer "B.Fab")
			(hide yes)
			(effects
				(font
					(size 1 1)
					(thickness 0.15)
				)
				(justify mirror)
			)
		)
		(property "Val" "3k3"
			(at 0 0 90)
			(unlocked yes)
			(layer "B.Fab")
			(hide yes)
			(effects
				(font
					(size 1 1)
					(thickness 0.15)
				)
				(justify mirror)
			)
		)
		(property "Tolerance" "1%"
			(at 0 0 90)
			(unlocked yes)
			(layer "B.Fab")
			(hide yes)
			(effects
				(font
					(size 1 1)
					(thickness 0.15)
				)
				(justify mirror)
			)
		)
		(sheetname "/X710-AT2 10GbE/")
		(sheetfile "x710-at2-10gbe.kicad_sch")
		(attr smd)
		(fp_rect
			(start -0.925 0.47)
			(end 0.925 -0.47)
			(stroke
				(width 0.05)
				(type default)
			)
			(fill no)
			(layer "B.CrtYd")
		)
		(fp_rect
			(start -0.5 0.25)
			(end 0.5 -0.25)
			(stroke
				(width 0.15)
				(type solid)
			)
			(fill no)
			(layer "B.Fab")
		)
		(fp_text user "Author: Antmicro"
			(at -0.95 -4.169 270)
			(layer "B.Fab")
			(effects
				(font
					(size 0.7 0.7)
					(thickness 0.15)
				)
				(justify left bottom mirror)
			)
		)
		(fp_text user "License: Apache-2.0"
			(at -0.95 -5.169 270)
			(layer "B.Fab")
			(effects
				(font
					(size 0.7 0.7)
					(thickness 0.15)
				)
				(justify left bottom mirror)
			)
		)
		(fp_text user "${REFERENCE}"
			(at -0.95 -3.168 270)
			(layer "B.Fab")
			(effects
				(font
					(size 0.7 0.7)
					(thickness 0.15)
				)
				(justify left bottom mirror)
			)
		)
		(pad "1" smd roundrect
			(at -0.48 0 90)
			(size 0.59 0.64)
			(layers "B.Cu" "B.Mask" "B.Paste")
			(roundrect_rratio 0.25)
			(net 77 "/X710-AT2 10GbE/MDC1_SCL1")
			(pintype "passive")
		)
		(pad "2" smd roundrect
			(at 0.48 0 90)
			(size 0.59 0.64)
			(layers "B.Cu" "B.Mask" "B.Paste")
			(roundrect_rratio 0.25)
			(net 7 "+3V3")
			(pintype "passive")
		)
	)
	(footprint "antmicro-footprints:R_0402_1005Metric"
		(layer "B.Cu")
		(at 122.75 128.025001 180)
		(descr "Resistor SMD 0402")
		(tags "resistor SMD 0402")
		(property "Reference" "R61"
			(at 2.25 0 0)
			(layer "B.SilkS")
			(effects
				(font
					(size 0.7 0.7)
					(thickness 0.15)
				)
				(justify mirror)
			)
		)
		(property "Value" "R_499R_0402"
			(at -1.011843 -1.772047 0)
			(layer "B.Fab")
			(effects
				(font
					(size 0.7 0.7)
					(thickness 0.15)
				)
				(justify left bottom mirror)
			)
		)
		(property "Datasheet" "https://www.mouser.com/datasheet/2/54/cr-1858361.pdf"
			(at 0 0 0)
			(layer "B.Fab")
			(hide yes)
			(effects
				(font
					(size 1.27 1.27)
					(thickness 0.15)
				)
				(justify mirror)
			)
		)
		(property "Description" "SMD Chip Resistor, 499 ohm, ± 1%, 63 mW, 0402 [1005 Metric], Thick Film, General Purpose"
			(at 0 0 0)
			(layer "B.Fab")
			(hide yes)
			(effects
				(font
					(size 1.27 1.27)
					(thickness 0.15)
				)
				(justify mirror)
			)
		)
		(property "MPN" "CR0402-FX-4990GLF"
			(at 0 0 180)
			(unlocked yes)
			(layer "B.Fab")
			(hide yes)
			(effects
				(font
					(size 1 1)
					(thickness 0.15)
				)
				(justify mirror)
			)
		)
		(property "Manufacturer" "Bourns"
			(at 0 0 180)
			(unlocked yes)
			(layer "B.Fab")
			(hide yes)
			(effects
				(font
					(size 1 1)
					(thickness 0.15)
				)
				(justify mirror)
			)
		)
		(property "License" "Apache-2.0"
			(at 0 0 180)
			(unlocked yes)
			(layer "B.Fab")
			(hide yes)
			(effects
				(font
					(size 1 1)
					(thickness 0.15)
				)
				(justify mirror)
			)
		)
		(property "Val" "499R"
			(at 0 0 180)
			(unlocked yes)
			(layer "B.Fab")
			(hide yes)
			(effects
				(font
					(size 1 1)
					(thickness 0.15)
				)
				(justify mirror)
			)
		)
		(property "Tolerance" "1%"
			(at 0 0 180)
			(unlocked yes)
			(layer "B.Fab")
			(hide yes)
			(effects
				(font
					(size 1 1)
					(thickness 0.15)
				)
				(justify mirror)
			)
		)
		(property "Author" "Antmicro"
			(at 0 0 180)
			(unlocked yes)
			(layer "B.Fab")
			(hide yes)
			(effects
				(font
					(size 1 1)
					(thickness 0.15)
				)
				(justify mirror)
			)
		)
		(sheetname "/TB Controller/")
		(sheetfile "tb.kicad_sch")
		(attr smd)
		(fp_rect
			(start -0.925 0.47)
			(end 0.925 -0.47)
			(stroke
				(width 0.05)
				(type default)
			)
			(fill no)
			(layer "B.CrtYd")
		)
		(fp_rect
			(start -0.5 0.25)
			(end 0.5 -0.25)
			(stroke
				(width 0.15)
				(type solid)
			)
			(fill no)
			(layer "B.Fab")
		)
		(fp_text user "${REFERENCE}"
			(at -0.95 -3.168 0)
			(layer "B.Fab")
			(effects
				(font
					(size 0.7 0.7)
					(thickness 0.15)
				)
				(justify left bottom mirror)
			)
		)
		(fp_text user "License: Apache-2.0"
			(at -0.95 -5.169 0)
			(layer "B.Fab")
			(effects
				(font
					(size 0.7 0.7)
					(thickness 0.15)
				)
				(justify left bottom mirror)
			)
		)
		(fp_text user "Author: Antmicro"
			(at -0.95 -4.169 0)
			(layer "B.Fab")
			(effects
				(font
					(size 0.7 0.7)
					(thickness 0.15)
				)
				(justify left bottom mirror)
			)
		)
		(pad "1" smd roundrect
			(at -0.48 0 180)
			(size 0.59 0.64)
			(layers "B.Cu" "B.Mask" "B.Paste")
			(roundrect_rratio 0.25)
			(net 234 "Net-(U4E-PB_USB2_RBIAS)")
			(pintype "passive")
		)
		(pad "2" smd roundrect
			(at 0.48 0 180)
			(size 0.59 0.64)
			(layers "B.Cu" "B.Mask" "B.Paste")
			(roundrect_rratio 0.25)
			(net 23 "GND")
			(pintype "passive")
		)
	)
	(footprint "antmicro-footprints:R_0402_1005Metric"
		(layer "B.Cu")
		(at 136.5 121.15)
		(descr "Resistor SMD 0402")
		(tags "resistor SMD 0402")
		(property "Reference" "R57"
			(at 19.525001 -7.450001 180)
			(layer "B.SilkS")
			(effects
				(font
					(size 0.7 0.7)
					(thickness 0.15)
				)
				(justify mirror)
			)
		)
		(property "Value" "R_100k_0402"
			(at -1.011843 -1.772047 180)
			(layer "B.Fab")
			(effects
				(font
					(size 0.7 0.7)
					(thickness 0.15)
				)
				(justify left bottom mirror)
			)
		)
		(property "Datasheet" "https://www.bourns.com/docs/product-datasheets/cr.pdf"
			(at 0 0 180)
			(layer "B.Fab")
			(hide yes)
			(effects
				(font
					(size 1.27 1.27)
					(thickness 0.15)
				)
				(justify mirror)
			)
		)
		(property "Description" "SMD Chip Resistor, 100 kohm, ± 1%, 62.5 mW, 0402 [1005 Metric], Thick Film, General Purpose"
			(at 0 0 180)
			(layer "B.Fab")
			(hide yes)
			(effects
				(font
					(size 1.27 1.27)
					(thickness 0.15)
				)
				(justify mirror)
			)
		)
		(property "MPN" "CR0402-FX-1003GLF"
			(at 0 0 0)
			(unlocked yes)
			(layer "B.Fab")
			(hide yes)
			(effects
				(font
					(size 1 1)
					(thickness 0.15)
				)
				(justify mirror)
			)
		)
		(property "Manufacturer" "Bourns"
			(at 0 0 0)
			(unlocked yes)
			(layer "B.Fab")
			(hide yes)
			(effects
				(font
					(size 1 1)
					(thickness 0.15)
				)
				(justify mirror)
			)
		)
		(property "License" "Apache-2.0"
			(at 0 0 0)
			(unlocked yes)
			(layer "B.Fab")
			(hide yes)
			(effects
				(font
					(size 1 1)
					(thickness 0.15)
				)
				(justify mirror)
			)
		)
		(property "Val" "100k"
			(at 0 0 0)
			(unlocked yes)
			(layer "B.Fab")
			(hide yes)
			(effects
				(font
					(size 1 1)
					(thickness 0.15)
				)
				(justify mirror)
			)
		)
		(property "Tolerance" "1%"
			(at 0 0 0)
			(unlocked yes)
			(layer "B.Fab")
			(hide yes)
			(effects
				(font
					(size 1 1)
					(thickness 0.15)
				)
				(justify mirror)
			)
		)
		(property "Author" "Antmicro"
			(at 0 0 0)
			(unlocked yes)
			(layer "B.Fab")
			(hide yes)
			(effects
				(font
					(size 1 1)
					(thickness 0.15)
				)
				(justify mirror)
			)
		)
		(sheetname "/TB Controller/")
		(sheetfile "tb.kicad_sch")
		(attr smd)
		(fp_rect
			(start -0.925 0.47)
			(end 0.925 -0.47)
			(stroke
				(width 0.05)
				(type default)
			)
			(fill no)
			(layer "B.CrtYd")
		)
		(fp_rect
			(start -0.5 0.25)
			(end 0.5 -0.25)
			(stroke
				(width 0.15)
				(type solid)
			)
			(fill no)
			(layer "B.Fab")
		)
		(fp_text user "${REFERENCE}"
			(at -0.95 -3.168 180)
			(layer "B.Fab")
			(effects
				(font
					(size 0.7 0.7)
					(thickness 0.15)
				)
				(justify left bottom mirror)
			)
		)
		(fp_text user "Author: Antmicro"
			(at -0.95 -4.169 180)
			(layer "B.Fab")
			(effects
				(font
					(size 0.7 0.7)
					(thickness 0.15)
				)
				(justify left bottom mirror)
			)
		)
		(fp_text user "License: Apache-2.0"
			(at -0.95 -5.169 180)
			(layer "B.Fab")
			(effects
				(font
					(size 0.7 0.7)
					(thickness 0.15)
				)
				(justify left bottom mirror)
			)
		)
		(pad "1" smd roundrect
			(at -0.48 0)
			(size 0.59 0.64)
			(layers "B.Cu" "B.Mask" "B.Paste")
			(roundrect_rratio 0.25)
			(net 371 "/TB Controller/~{PE_WAKE}")
			(pintype "passive")
		)
		(pad "2" smd roundrect
			(at 0.48 0)
			(size 0.59 0.64)
			(layers "B.Cu" "B.Mask" "B.Paste")
			(roundrect_rratio 0.25)
			(net 57 "+3V3_TB")
			(pintype "passive")
		)
	)
	(footprint "antmicro-footprints:TP_SMD_0.75mm"
		(layer "B.Cu")
		(at 183.75 78.75 90)
		(property "Reference" "TP15"
			(at -8.75 0.75 270)
			(layer "B.SilkS")
			(effects
				(font
					(size 0.7 0.7)
					(thickness 0.15)
				)
				(justify left bottom mirror)
			)
		)
		(property "Value" "TP_0.75mm_SMD"
			(at 0 -1.2 270)
			(layer "B.Fab")
			(effects
				(font
					(size 0.7 0.7)
					(thickness 0.15)
				)
				(justify left bottom mirror)
			)
		)
		(property "Description" "SMT test point"
			(at 0 0 270)
			(layer "B.Fab")
			(hide yes)
			(effects
				(font
					(size 1.27 1.27)
					(thickness 0.15)
				)
				(justify mirror)
			)
		)
		(property "MPN" ""
			(at 0 0 90)
			(unlocked yes)
			(layer "B.Fab")
			(hide yes)
			(effects
				(font
					(size 1 1)
					(thickness 0.15)
				)
				(justify mirror)
			)
		)
		(property "Manufacturer" ""
			(at 0 0 90)
			(unlocked yes)
			(layer "B.Fab")
			(hide yes)
			(effects
				(font
					(size 1 1)
					(thickness 0.15)
				)
				(justify mirror)
			)
		)
		(property "Author" "Antmicro"
			(at 0 0 90)
			(unlocked yes)
			(layer "B.Fab")
			(hide yes)
			(effects
				(font
					(size 1 1)
					(thickness 0.15)
				)
				(justify mirror)
			)
		)
		(property "License" "Apache-2.0"
			(at 0 0 90)
			(unlocked yes)
			(layer "B.Fab")
			(hide yes)
			(effects
				(font
					(size 1 1)
					(thickness 0.15)
				)
				(justify mirror)
			)
		)
		(sheetname "/X710 DCDC converters/")
		(sheetfile "DCDC_converters_X710.kicad_sch")
		(attr exclude_from_pos_files exclude_from_bom)
		(fp_circle
			(center 0 0)
			(end 0.475 0)
			(stroke
				(width 0.05)
				(type default)
			)
			(fill no)
			(layer "B.CrtYd")
		)
		(fp_text user "Author: Antmicro"
			(at -0.4 -3.901 270)
			(layer "B.Fab")
			(effects
				(font
					(size 0.7 0.7)
					(thickness 0.15)
				)
				(justify left bottom mirror)
			)
		)
		(fp_text user "License: Apache-2.0"
			(at -0.4 -5.101 270)
			(layer "B.Fab")
			(effects
				(font
					(size 0.7 0.7)
					(thickness 0.15)
				)
				(justify left bottom mirror)
			)
		)
		(fp_text user "${REFERENCE}"
			(at -0.4 -2.7 270)
			(layer "B.Fab")
			(effects
				(font
					(size 0.7 0.7)
					(thickness 0.15)
				)
				(justify left bottom mirror)
			)
		)
		(pad "1" smd circle
			(at 0 0 90)
			(size 0.75 0.75)
			(layers "B.Cu" "B.Mask")
			(net 7 "+3V3")
			(pinfunction "1")
			(pintype "passive")
		)
	)
	(footprint "antmicro-footprints:C_0805_2012Metric"
		(layer "B.Cu")
		(at 159.5 139.25 180)
		(descr "Capacitor SMD 0805")
		(tags "capacitor SMD 0805")
		(property "Reference" "C292"
			(at 2 -0.5 0)
			(layer "B.SilkS")
			(effects
				(font
					(size 0.7 0.7)
					(thickness 0.15)
				)
				(justify left bottom mirror)
			)
		)
		(property "Value" "C_100u_0805"
			(at -2.055717 -1.963152 0)
			(layer "B.Fab")
			(effects
				(font
					(size 0.7 0.7)
					(thickness 0.15)
				)
				(justify left bottom mirror)
			)
		)
		(property "Datasheet" "https://www.murata.com/products/productdetail?partno=GRM21BR60J107ME15%23"
			(at 0 0 0)
			(layer "B.Fab")
			(hide yes)
			(effects
				(font
					(size 1.27 1.27)
					(thickness 0.15)
				)
				(justify mirror)
			)
		)
		(property "Description" "SMD Multilayer Ceramic Capacitor, 100 µF, 6.3 V, 0805 [2012 Metric], ± 20%, X5R, GRM Series"
			(at 0 0 0)
			(layer "B.Fab")
			(hide yes)
			(effects
				(font
					(size 1.27 1.27)
					(thickness 0.15)
				)
				(justify mirror)
			)
		)
		(property "MPN" "GRM21BR60J107ME15L"
			(at 0 0 180)
			(unlocked yes)
			(layer "B.Fab")
			(hide yes)
			(effects
				(font
					(size 1 1)
					(thickness 0.15)
				)
				(justify mirror)
			)
		)
		(property "Manufacturer" "Murata"
			(at 0 0 180)
			(unlocked yes)
			(layer "B.Fab")
			(hide yes)
			(effects
				(font
					(size 1 1)
					(thickness 0.15)
				)
				(justify mirror)
			)
		)
		(property "License" "Apache-2.0"
			(at 0 0 180)
			(unlocked yes)
			(layer "B.Fab")
			(hide yes)
			(effects
				(font
					(size 1 1)
					(thickness 0.15)
				)
				(justify mirror)
			)
		)
		(property "Author" "Antmicro"
			(at 0 0 180)
			(unlocked yes)
			(layer "B.Fab")
			(hide yes)
			(effects
				(font
					(size 1 1)
					(thickness 0.15)
				)
				(justify mirror)
			)
		)
		(property "Val" "100u"
			(at 0 0 180)
			(unlocked yes)
			(layer "B.Fab")
			(hide yes)
			(effects
				(font
					(size 1 1)
					(thickness 0.15)
				)
				(justify mirror)
			)
		)
		(property "Voltage" ""
			(at 0 0 180)
			(unlocked yes)
			(layer "B.Fab")
			(hide yes)
			(effects
				(font
					(size 1 1)
					(thickness 0.15)
				)
				(justify mirror)
			)
		)
		(property "Dielectric" ""
			(at 0 0 180)
			(unlocked yes)
			(layer "B.Fab")
			(hide yes)
			(effects
				(font
					(size 1 1)
					(thickness 0.15)
				)
				(justify mirror)
			)
		)
		(property "Public" "False"
			(at 0 0 180)
			(unlocked yes)
			(layer "B.Fab")
			(hide yes)
			(effects
				(font
					(size 1 1)
					(thickness 0.15)
				)
				(justify mirror)
			)
		)
		(sheetname "/2xRJ45/")
		(sheetfile "2xrj45.kicad_sch")
		(attr smd)
		(fp_line
			(start -0.3 0.7)
			(end 0.3 0.7)
			(stroke
				(width 0.15)
				(type solid)
			)
			(layer "B.SilkS")
		)
		(fp_line
			(start -0.3 -0.7)
			(end 0.3 -0.7)
			(stroke
				(width 0.15)
				(type solid)
			)
			(layer "B.SilkS")
		)
		(fp_rect
			(start 1.95 0.9)
			(end -1.95 -0.9)
			(stroke
				(width 0.05)
				(type default)
			)
			(fill no)
			(layer "B.CrtYd")
		)
		(fp_rect
			(start -0.95 0.675)
			(end 0.95 -0.675)
			(stroke
				(width 0.15)
				(type solid)
			)
			(fill no)
			(layer "B.Fab")
		)
		(fp_text user "${REFERENCE}"
			(at -1.9 -3.947 0)
			(layer "B.Fab")
			(effects
				(font
					(size 0.7 0.7)
					(thickness 0.15)
				)
				(justify left bottom mirror)
			)
		)
		(fp_text user "Author: Antmicro"
			(at -1.9 -5.947 0)
			(layer "B.Fab")
			(effects
				(font
					(size 0.7 0.7)
					(thickness 0.15)
				)
				(justify left bottom mirror)
			)
		)
		(fp_text user "License: Apache-2.0"
			(at -1.9 -4.947 0)
			(layer "B.Fab")
			(effects
				(font
					(size 0.7 0.7)
					(thickness 0.15)
				)
				(justify left bottom mirror)
			)
		)
		(pad "1" smd roundrect
			(at -1.1 0 180)
			(size 1.2 1.3)
			(layers "B.Cu" "B.Mask" "B.Paste")
			(roundrect_rratio 0.25)
			(net 23 "GND")
			(pintype "passive")
		)
		(pad "2" smd roundrect
			(at 1.1 0 180)
			(size 1.2 1.3)
			(layers "B.Cu" "B.Mask" "B.Paste")
			(roundrect_rratio 0.25)
			(net 133 "/2xRJ45/P0_CT")
			(pintype "passive")
		)
	)
	(footprint "antmicro-footprints:SOD-523"
		(layer "B.Cu")
		(at 122.3 150.6 180)
		(property "Reference" "D1"
			(at -0.7 -1.65 0)
			(layer "B.SilkS")
			(effects
				(font
					(size 0.7 0.7)
					(thickness 0.15)
				)
				(justify left bottom mirror)
			)
		)
		(property "Value" "PESD5Z5.0F"
			(at 0 -1.499 0)
			(layer "B.Fab")
			(effects
				(font
					(size 0.7 0.7)
					(thickness 0.15)
				)
				(justify left bottom mirror)
			)
		)
		(property "Datasheet" "https://assets.nexperia.com/documents/data-sheet/PESD5Z5_0.pdf"
			(at 0 0 0)
			(layer "B.Fab")
			(hide yes)
			(effects
				(font
					(size 1.27 1.27)
					(thickness 0.15)
				)
				(justify mirror)
			)
		)
		(property "Description" "Unidirectional TVS, 30 kV,  SOD-523, 5 V, 89 pF"
			(at 0 0 0)
			(layer "B.Fab")
			(hide yes)
			(effects
				(font
					(size 1.27 1.27)
					(thickness 0.15)
				)
				(justify mirror)
			)
		)
		(property "Manufacturer" "Nexperia"
			(at 0 0 180)
			(unlocked yes)
			(layer "B.Fab")
			(hide yes)
			(effects
				(font
					(size 1 1)
					(thickness 0.15)
				)
				(justify mirror)
			)
		)
		(property "MPN" "PESD5Z5.0F"
			(at 0 0 180)
			(unlocked yes)
			(layer "B.Fab")
			(hide yes)
			(effects
				(font
					(size 1 1)
					(thickness 0.15)
				)
				(justify mirror)
			)
		)
		(property "Author" "Antmicro"
			(at 0 0 180)
			(unlocked yes)
			(layer "B.Fab")
			(hide yes)
			(effects
				(font
					(size 1 1)
					(thickness 0.15)
				)
				(justify mirror)
			)
		)
		(property "License" "Apache-2.0"
			(at 0 0 180)
			(unlocked yes)
			(layer "B.Fab")
			(hide yes)
			(effects
				(font
					(size 1 1)
					(thickness 0.15)
				)
				(justify mirror)
			)
		)
		(sheetname "/USB-C connector/")
		(sheetfile "USB-C_connector.kicad_sch")
		(attr smd)
		(fp_line
			(start -0.35 0.5)
			(end -0.35 -0.5)
			(stroke
				(width 0.15)
				(type solid)
			)
			(layer "B.SilkS")
		)
		(fp_rect
			(start -1 0.6)
			(end 1 -0.6)
			(stroke
				(width 0.05)
				(type solid)
			)
			(fill no)
			(layer "B.CrtYd")
		)
		(fp_line
			(start 0.65 0.425)
			(end 0.65 -0.423)
			(stroke
				(width 0.15)
				(type solid)
			)
			(layer "B.Fab")
		)
		(fp_line
			(start -0.35 0.4)
			(end -0.35 -0.4)
			(stroke
				(width 0.15)
				(type solid)
			)
			(layer "B.Fab")
		)
		(fp_line
			(start -0.652 0.425)
			(end 0.65 0.425)
			(stroke
				(width 0.15)
				(type solid)
			)
			(layer "B.Fab")
		)
		(fp_line
			(start -0.652 -0.423)
			(end 0.65 -0.423)
			(stroke
				(width 0.15)
				(type solid)
			)
			(layer "B.Fab")
		)
		(fp_line
			(start -0.652 -0.423)
			(end -0.652 0.425)
			(stroke
				(width 0.15)
				(type solid)
			)
			(layer "B.Fab")
		)
		(fp_text user "Author: Antmicro"
			(at -1.276 -4.7 0)
			(layer "B.Fab")
			(effects
				(font
					(size 0.7 0.7)
					(thickness 0.15)
				)
				(justify left bottom mirror)
			)
		)
		(fp_text user "${REFERENCE}"
			(at -1.276 -3.499 0)
			(layer "B.Fab")
			(effects
				(font
					(size 0.7 0.7)
					(thickness 0.15)
				)
				(justify left bottom mirror)
			)
		)
		(fp_text user "License: Apache-2.0"
			(at -1.276 -5.9 0)
			(layer "B.Fab")
			(effects
				(font
					(size 0.7 0.7)
					(thickness 0.15)
				)
				(justify left bottom mirror)
			)
		)
		(pad "1" smd roundrect
			(at -0.701 0 180)
			(size 0.5 0.6)
			(layers "B.Cu" "B.Mask" "B.Paste")
			(roundrect_rratio 0.25)
			(net 215 "/USB-C connector/VBUS")
			(pinfunction "C")
			(pintype "passive")
		)
		(pad "2" smd roundrect
			(at 0.699 0 180)
			(size 0.5 0.6)
			(layers "B.Cu" "B.Mask" "B.Paste")
			(roundrect_rratio 0.25)
			(net 23 "GND")
			(pinfunction "A")
			(pintype "passive")
		)
	)
	(footprint "antmicro-footprints:C_Pol_EIA-A"
		(layer "B.Cu")
		(at 143.2 103.7 -90)
		(property "Reference" "C330"
			(at 2.2 -0.4 90)
			(layer "B.SilkS")
			(effects
				(font
					(size 0.7 0.7)
					(thickness 0.15)
				)
				(justify left bottom mirror)
			)
		)
		(property "Value" "C_Pol_100u_6V_KEMET-T490-A"
			(at 0 -2 90)
			(layer "B.Fab")
			(effects
				(font
					(size 0.7 0.7)
					(thickness 0.15)
				)
				(justify left bottom mirror)
			)
		)
		(property "Datasheet" "https://www.kemet.com/en/us/capacitors/product/T490A107M006ATE800.html"
			(at 0 0 90)
			(layer "B.Fab")
			(hide yes)
			(effects
				(font
					(size 1.27 1.27)
					(thickness 0.15)
				)
				(justify mirror)
			)
		)
		(property "Description" "Surface Mount Tantalum Capacitor,  Solid SMD 6V 100uF 1206 20% ESR=800mOhms"
			(at 0 0 90)
			(layer "B.Fab")
			(hide yes)
			(effects
				(font
					(size 1.27 1.27)
					(thickness 0.15)
				)
				(justify mirror)
			)
		)
		(property "Val" "100u"
			(at 0 0 270)
			(unlocked yes)
			(layer "B.Fab")
			(hide yes)
			(effects
				(font
					(size 1 1)
					(thickness 0.15)
				)
				(justify mirror)
			)
		)
		(property "MPN" "T490A107M006ATE800"
			(at 0 0 270)
			(unlocked yes)
			(layer "B.Fab")
			(hide yes)
			(effects
				(font
					(size 1 1)
					(thickness 0.15)
				)
				(justify mirror)
			)
		)
		(property "Manufacturer" "KEMET"
			(at 0 0 270)
			(unlocked yes)
			(layer "B.Fab")
			(hide yes)
			(effects
				(font
					(size 1 1)
					(thickness 0.15)
				)
				(justify mirror)
			)
		)
		(property "License" "Apache-2.0"
			(at 0 0 270)
			(unlocked yes)
			(layer "B.Fab")
			(hide yes)
			(effects
				(font
					(size 1 1)
					(thickness 0.15)
				)
				(justify mirror)
			)
		)
		(property "Author" "Antmicro"
			(at 0 0 270)
			(unlocked yes)
			(layer "B.Fab")
			(hide yes)
			(effects
				(font
					(size 1 1)
					(thickness 0.15)
				)
				(justify mirror)
			)
		)
		(property "Voltage" "6V"
			(at 0 0 270)
			(unlocked yes)
			(layer "B.Fab")
			(hide yes)
			(effects
				(font
					(size 1 1)
					(thickness 0.15)
				)
				(justify mirror)
			)
		)
		(property "Dielectric" "template_dielectric"
			(at 0 0 270)
			(unlocked yes)
			(layer "B.Fab")
			(hide yes)
			(effects
				(font
					(size 1 1)
					(thickness 0.15)
				)
				(justify mirror)
			)
		)
		(sheetname "/X710-AT2 power/")
		(sheetfile "x710-at2-power.kicad_sch")
		(attr smd)
		(fp_line
			(start -1.95 1.25)
			(end -1.95 0.95)
			(stroke
				(width 0.12)
				(type solid)
			)
			(layer "B.SilkS")
		)
		(fp_line
			(start -2.1 1.1)
			(end -1.8 1.1)
			(stroke
				(width 0.12)
				(type solid)
			)
			(layer "B.SilkS")
		)
		(fp_line
			(start -1.5 0.85)
			(end 1.5 0.85)
			(stroke
				(width 0.12)
				(type solid)
			)
			(layer "B.SilkS")
		)
		(fp_line
			(start -1.5 0.75)
			(end -1.5 0.85)
			(stroke
				(width 0.12)
				(type solid)
			)
			(layer "B.SilkS")
		)
		(fp_line
			(start 1.5 0.75)
			(end 1.5 0.85)
			(stroke
				(width 0.12)
				(type solid)
			)
			(layer "B.SilkS")
		)
		(fp_line
			(start -1.5 -0.75)
			(end -1.5 -0.85)
			(stroke
				(width 0.12)
				(type solid)
			)
			(layer "B.SilkS")
		)
		(fp_line
			(start 1.5 -0.75)
			(end 1.5 -0.85)
			(stroke
				(width 0.12)
				(type solid)
			)
			(layer "B.SilkS")
		)
		(fp_line
			(start 1.5 -0.85)
			(end -1.5 -0.85)
			(stroke
				(width 0.12)
				(type solid)
			)
			(layer "B.SilkS")
		)
		(fp_line
			(start 1.7 1.05)
			(end -1.7 1.05)
			(stroke
				(width 0.05)
				(type solid)
			)
			(layer "B.CrtYd")
		)
		(fp_line
			(start -2.05 0.85)
			(end -2.05 -0.85)
			(stroke
				(width 0.05)
				(type solid)
			)
			(layer "B.CrtYd")
		)
		(fp_line
			(start -1.7 0.85)
			(end -1.7 1.05)
			(stroke
				(width 0.05)
				(type solid)
			)
			(layer "B.CrtYd")
		)
		(fp_line
			(start -1.7 0.85)
			(end -2.05 0.85)
			(stroke
				(width 0.05)
				(type solid)
			)
			(layer "B.CrtYd")
		)
		(fp_line
			(start 1.7 0.85)
			(end 1.7 1.05)
			(stroke
				(width 0.05)
				(type solid)
			)
			(layer "B.CrtYd")
		)
		(fp_line
			(start 2.05 0.85)
			(end 1.7 0.85)
			(stroke
				(width 0.05)
				(type solid)
			)
			(layer "B.CrtYd")
		)
		(fp_line
			(start 2.05 0.85)
			(end 2.05 -0.85)
			(stroke
				(width 0.05)
				(type solid)
			)
			(layer "B.CrtYd")
		)
		(fp_line
			(start -1.7 -0.85)
			(end -2.05 -0.85)
			(stroke
				(width 0.05)
				(type solid)
			)
			(layer "B.CrtYd")
		)
		(fp_line
			(start 2.05 -0.85)
			(end 1.7 -0.85)
			(stroke
				(width 0.05)
				(type solid)
			)
			(layer "B.CrtYd")
		)
		(fp_line
			(start -1.7 -1.05)
			(end -1.7 -0.85)
			(stroke
				(width 0.05)
				(type solid)
			)
			(layer "B.CrtYd")
		)
		(fp_line
			(start 1.7 -1.05)
			(end 1.7 -0.85)
			(stroke
				(width 0.05)
				(type solid)
			)
			(layer "B.CrtYd")
		)
		(fp_line
			(start 1.7 -1.05)
			(end -1.7 -1.05)
			(stroke
				(width 0.05)
				(type solid)
			)
			(layer "B.CrtYd")
		)
		(fp_rect
			(start -1.601 0.802)
			(end 1.6 -0.8)
			(stroke
				(width 0.1)
				(type solid)
			)
			(fill no)
			(layer "B.Fab")
		)
		(fp_text user "License: Apache-2.0"
			(at -2.1 -5.198 90)
			(layer "B.Fab")
			(effects
				(font
					(size 0.7 0.7)
					(thickness 0.15)
				)
				(justify left bottom mirror)
			)
		)
		(fp_text user "${REFERENCE}"
			(at -2.1 -4.198 90)
			(layer "B.Fab")
			(effects
				(font
					(size 0.7 0.7)
					(thickness 0.15)
				)
				(justify left bottom mirror)
			)
		)
		(fp_text user "Author: Antmicro"
			(at -2.1 -6.198 90)
			(layer "B.Fab")
			(effects
				(font
					(size 0.7 0.7)
					(thickness 0.15)
				)
				(justify left bottom mirror)
			)
		)
		(pad "1" smd roundrect
			(at -1.2 0 270)
			(size 1.2 1.2)
			(layers "B.Cu" "B.Mask" "B.Paste")
			(roundrect_rratio 0.1)
			(net 6 "DVDD")
			(pintype "passive")
		)
		(pad "2" smd roundrect
			(at 1.2 0 270)
			(size 1.2 1.2)
			(layers "B.Cu" "B.Mask" "B.Paste")
			(roundrect_rratio 0.1)
			(net 23 "GND")
			(pintype "passive")
		)
	)
	(footprint "antmicro-footprints:R_0402_1005Metric"
		(layer "B.Cu")
		(at 149.331865 82.260117)
		(descr "Resistor SMD 0402")
		(tags "resistor SMD 0402")
		(property "Reference" "R126"
			(at 19.468135 9.464883 180)
			(layer "B.SilkS")
			(effects
				(font
					(size 0.7 0.7)
					(thickness 0.15)
				)
				(justify mirror)
			)
		)
		(property "Value" "R_100R_0402"
			(at -1.011843 -1.772047 180)
			(layer "B.Fab")
			(effects
				(font
					(size 0.7 0.7)
					(thickness 0.15)
				)
				(justify left bottom mirror)
			)
		)
		(property "Datasheet" "https://www.bourns.com/docs/product-datasheets/cr.pdf"
			(at 0 0 180)
			(layer "B.Fab")
			(hide yes)
			(effects
				(font
					(size 1.27 1.27)
					(thickness 0.15)
				)
				(justify mirror)
			)
		)
		(property "Description" "SMD Chip Resistor, 100 ohm, ± 1%, 62.5 mW, 0402 [1005 Metric], Thick Film, General Purpose"
			(at 0 0 180)
			(layer "B.Fab")
			(hide yes)
			(effects
				(font
					(size 1.27 1.27)
					(thickness 0.15)
				)
				(justify mirror)
			)
		)
		(property "MPN" "CR0402-FX-1000GLF"
			(at 0 0 0)
			(unlocked yes)
			(layer "B.Fab")
			(hide yes)
			(effects
				(font
					(size 1 1)
					(thickness 0.15)
				)
				(justify mirror)
			)
		)
		(property "Manufacturer" "Bourns"
			(at 0 0 0)
			(unlocked yes)
			(layer "B.Fab")
			(hide yes)
			(effects
				(font
					(size 1 1)
					(thickness 0.15)
				)
				(justify mirror)
			)
		)
		(property "License" "Apache-2.0"
			(at 0 0 0)
			(unlocked yes)
			(layer "B.Fab")
			(hide yes)
			(effects
				(font
					(size 1 1)
					(thickness 0.15)
				)
				(justify mirror)
			)
		)
		(property "Author" "Antmicro"
			(at 0 0 0)
			(unlocked yes)
			(layer "B.Fab")
			(hide yes)
			(effects
				(font
					(size 1 1)
					(thickness 0.15)
				)
				(justify mirror)
			)
		)
		(property "Val" "100R"
			(at 0 0 0)
			(unlocked yes)
			(layer "B.Fab")
			(hide yes)
			(effects
				(font
					(size 1 1)
					(thickness 0.15)
				)
				(justify mirror)
			)
		)
		(property "Tolerance" "1%"
			(at 0 0 0)
			(unlocked yes)
			(layer "B.Fab")
			(hide yes)
			(effects
				(font
					(size 1 1)
					(thickness 0.15)
				)
				(justify mirror)
			)
		)
		(sheetname "/X710-AT2 RSVD/")
		(sheetfile "x710-at2-rsvd.kicad_sch")
		(attr smd)
		(fp_rect
			(start -0.925 0.47)
			(end 0.925 -0.47)
			(stroke
				(width 0.05)
				(type default)
			)
			(fill no)
			(layer "B.CrtYd")
		)
		(fp_rect
			(start -0.5 0.25)
			(end 0.5 -0.25)
			(stroke
				(width 0.15)
				(type solid)
			)
			(fill no)
			(layer "B.Fab")
		)
		(fp_text user "Author: Antmicro"
			(at -0.95 -4.169 180)
			(layer "B.Fab")
			(effects
				(font
					(size 0.7 0.7)
					(thickness 0.15)
				)
				(justify left bottom mirror)
			)
		)
		(fp_text user "License: Apache-2.0"
			(at -0.95 -5.169 180)
			(layer "B.Fab")
			(effects
				(font
					(size 0.7 0.7)
					(thickness 0.15)
				)
				(justify left bottom mirror)
			)
		)
		(fp_text user "${REFERENCE}"
			(at -0.95 -3.168 180)
			(layer "B.Fab")
			(effects
				(font
					(size 0.7 0.7)
					(thickness 0.15)
				)
				(justify left bottom mirror)
			)
		)
		(pad "1" smd roundrect
			(at -0.48 0)
			(size 0.59 0.64)
			(layers "B.Cu" "B.Mask" "B.Paste")
			(roundrect_rratio 0.25)
			(net 23 "GND")
			(pintype "passive")
		)
		(pad "2" smd roundrect
			(at 0.48 0)
			(size 0.59 0.64)
			(layers "B.Cu" "B.Mask" "B.Paste")
			(roundrect_rratio 0.25)
			(net 97 "/X710-AT2 RSVD/RSVDP22_VSS")
			(pintype "passive")
		)
	)
	(footprint "antmicro-footprints:C_0402_1005Metric"
		(layer "B.Cu")
		(at 129.474999 123.950001 -90)
		(descr "Capacitor SMD 0402")
		(tags "capacitor SMD 0402")
		(property "Reference" "C76"
			(at -7.700002 -21.900002 90)
			(layer "B.SilkS")
			(effects
				(font
					(size 0.7 0.7)
					(thickness 0.15)
				)
				(justify mirror)
			)
		)
		(property "Value" "C_1u_0402"
			(at -1.022927 -2.155213 90)
			(layer "B.Fab")
			(effects
				(font
					(size 0.7 0.7)
					(thickness 0.15)
				)
				(justify left bottom mirror)
			)
		)
		(property "Datasheet" "https://product.tdk.com/en/search/capacitor/ceramic/mlcc/info?part_no=C1005X6S1A105K050BC"
			(at 0 0 90)
			(layer "B.Fab")
			(hide yes)
			(effects
				(font
					(size 1.27 1.27)
					(thickness 0.15)
				)
				(justify mirror)
			)
		)
		(property "Description" "SMD Multilayer Ceramic Capacitor, 1 µF, 10 V, 0402 [1005 Metric], ± 10%, X6S, C"
			(at 0 0 90)
			(layer "B.Fab")
			(hide yes)
			(effects
				(font
					(size 1.27 1.27)
					(thickness 0.15)
				)
				(justify mirror)
			)
		)
		(property "MPN" "C1005X6S1A105K050BC"
			(at 0 0 270)
			(unlocked yes)
			(layer "B.Fab")
			(hide yes)
			(effects
				(font
					(size 1 1)
					(thickness 0.15)
				)
				(justify mirror)
			)
		)
		(property "Manufacturer" "TDK"
			(at 0 0 270)
			(unlocked yes)
			(layer "B.Fab")
			(hide yes)
			(effects
				(font
					(size 1 1)
					(thickness 0.15)
				)
				(justify mirror)
			)
		)
		(property "License" "Apache-2.0"
			(at 0 0 270)
			(unlocked yes)
			(layer "B.Fab")
			(hide yes)
			(effects
				(font
					(size 1 1)
					(thickness 0.15)
				)
				(justify mirror)
			)
		)
		(property "Val" "1u"
			(at 0 0 270)
			(unlocked yes)
			(layer "B.Fab")
			(hide yes)
			(effects
				(font
					(size 1 1)
					(thickness 0.15)
				)
				(justify mirror)
			)
		)
		(property "Voltage" ""
			(at 0 0 270)
			(unlocked yes)
			(layer "B.Fab")
			(hide yes)
			(effects
				(font
					(size 1 1)
					(thickness 0.15)
				)
				(justify mirror)
			)
		)
		(property "Dielectric" ""
			(at 0 0 270)
			(unlocked yes)
			(layer "B.Fab")
			(hide yes)
			(effects
				(font
					(size 1 1)
					(thickness 0.15)
				)
				(justify mirror)
			)
		)
		(property "Author" "Antmicro"
			(at 0 0 270)
			(unlocked yes)
			(layer "B.Fab")
			(hide yes)
			(effects
				(font
					(size 1 1)
					(thickness 0.15)
				)
				(justify mirror)
			)
		)
		(sheetname "/TB Controller - Power/")
		(sheetfile "tb-power.kicad_sch")
		(attr smd)
		(fp_rect
			(start -0.925 0.47)
			(end 0.925 -0.47)
			(stroke
				(width 0.05)
				(type default)
			)
			(fill no)
			(layer "B.CrtYd")
		)
		(fp_line
			(start -0.494 0.25)
			(end 0.504 0.25)
			(stroke
				(width 0.15)
				(type solid)
			)
			(layer "B.Fab")
		)
		(fp_line
			(start 0.504 0.25)
			(end 0.504 -0.248)
			(stroke
				(width 0.15)
				(type solid)
			)
			(layer "B.Fab")
		)
		(fp_line
			(start -0.494 -0.248)
			(end -0.494 0.25)
			(stroke
				(width 0.15)
				(type solid)
			)
			(layer "B.Fab")
		)
		(fp_line
			(start 0.504 -0.248)
			(end -0.494 -0.248)
			(stroke
				(width 0.15)
				(type solid)
			)
			(layer "B.Fab")
		)
		(fp_text user "Author: Antmicro"
			(at -0.939 -3.399 90)
			(layer "B.Fab")
			(effects
				(font
					(size 0.7 0.7)
					(thickness 0.15)
				)
				(justify left bottom mirror)
			)
		)
		(fp_text user "License: Apache-2.0"
			(at -0.939 -5.799 90)
			(layer "B.Fab")
			(effects
				(font
					(size 0.7 0.7)
					(thickness 0.15)
				)
				(justify left bottom mirror)
			)
		)
		(fp_text user "${REFERENCE}"
			(at -0.939 -4.599 90)
			(layer "B.Fab")
			(effects
				(font
					(size 0.7 0.7)
					(thickness 0.15)
				)
				(justify left bottom mirror)
			)
		)
		(pad "1" smd roundrect
			(at -0.48 0 270)
			(size 0.59 0.64)
			(layers "B.Cu" "B.Mask" "B.Paste")
			(roundrect_rratio 0.25)
			(net 23 "GND")
			(pintype "passive")
		)
		(pad "2" smd roundrect
			(at 0.48 0 270)
			(size 0.59 0.64)
			(layers "B.Cu" "B.Mask" "B.Paste")
			(roundrect_rratio 0.25)
			(net 68 "/TB Controller - Power/VCC_0P9")
			(pintype "passive")
		)
	)
	(footprint "antmicro-footprints:C_0402_1005Metric"
		(layer "B.Cu")
		(at 156.111865 88.045116 180)
		(descr "Capacitor SMD 0402")
		(tags "capacitor SMD 0402")
		(property "Reference" "C182"
			(at -19.873134 -9.464883 0)
			(layer "B.SilkS")
			(effects
				(font
					(size 0.7 0.7)
					(thickness 0.15)
				)
				(justify mirror)
			)
		)
		(property "Value" "C_1u_25V_0402"
			(at -1.022927 -2.155213 0)
			(layer "B.Fab")
			(effects
				(font
					(size 0.7 0.7)
					(thickness 0.15)
				)
				(justify left bottom mirror)
			)
		)
		(property "Datasheet" "https://www.murata.com/products/productdetail?partno=GRM155R61E105KE11%23"
			(at 0 0 0)
			(layer "B.Fab")
			(hide yes)
			(effects
				(font
					(size 1.27 1.27)
					(thickness 0.15)
				)
				(justify mirror)
			)
		)
		(property "Description" "SMD Multilayer Ceramic Capacitor, 1 µF, 25 V, 0402 [1005 Metric], ± 10%, X5R, GRM Series"
			(at 0 0 0)
			(layer "B.Fab")
			(hide yes)
			(effects
				(font
					(size 1.27 1.27)
					(thickness 0.15)
				)
				(justify mirror)
			)
		)
		(property "MPN" "GRM155R61E105KE11J"
			(at 0 0 180)
			(unlocked yes)
			(layer "B.Fab")
			(hide yes)
			(effects
				(font
					(size 1 1)
					(thickness 0.15)
				)
				(justify mirror)
			)
		)
		(property "Manufacturer" "Murata"
			(at 0 0 180)
			(unlocked yes)
			(layer "B.Fab")
			(hide yes)
			(effects
				(font
					(size 1 1)
					(thickness 0.15)
				)
				(justify mirror)
			)
		)
		(property "License" "Apache-2.0"
			(at 0 0 180)
			(unlocked yes)
			(layer "B.Fab")
			(hide yes)
			(effects
				(font
					(size 1 1)
					(thickness 0.15)
				)
				(justify mirror)
			)
		)
		(property "Author" "Antmicro"
			(at 0 0 180)
			(unlocked yes)
			(layer "B.Fab")
			(hide yes)
			(effects
				(font
					(size 1 1)
					(thickness 0.15)
				)
				(justify mirror)
			)
		)
		(property "Val" "1u"
			(at 0 0 180)
			(unlocked yes)
			(layer "B.Fab")
			(hide yes)
			(effects
				(font
					(size 1 1)
					(thickness 0.15)
				)
				(justify mirror)
			)
		)
		(property "Voltage" "25V"
			(at 0 0 180)
			(unlocked yes)
			(layer "B.Fab")
			(hide yes)
			(effects
				(font
					(size 1 1)
					(thickness 0.15)
				)
				(justify mirror)
			)
		)
		(property "Dielectric" "X5R"
			(at 0 0 180)
			(unlocked yes)
			(layer "B.Fab")
			(hide yes)
			(effects
				(font
					(size 1 1)
					(thickness 0.15)
				)
				(justify mirror)
			)
		)
		(sheetname "/X710-AT2 power/")
		(sheetfile "x710-at2-power.kicad_sch")
		(attr smd)
		(fp_rect
			(start -0.925 0.47)
			(end 0.925 -0.47)
			(stroke
				(width 0.05)
				(type default)
			)
			(fill no)
			(layer "B.CrtYd")
		)
		(fp_line
			(start 0.504 0.25)
			(end 0.504 -0.248)
			(stroke
				(width 0.15)
				(type solid)
			)
			(layer "B.Fab")
		)
		(fp_line
			(start 0.504 -0.248)
			(end -0.494 -0.248)
			(stroke
				(width 0.15)
				(type solid)
			)
			(layer "B.Fab")
		)
		(fp_line
			(start -0.494 0.25)
			(end 0.504 0.25)
			(stroke
				(width 0.15)
				(type solid)
			)
			(layer "B.Fab")
		)
		(fp_line
			(start -0.494 -0.248)
			(end -0.494 0.25)
			(stroke
				(width 0.15)
				(type solid)
			)
			(layer "B.Fab")
		)
		(fp_text user "${REFERENCE}"
			(at -0.939 -4.599 0)
			(layer "B.Fab")
			(effects
				(font
					(size 0.7 0.7)
					(thickness 0.15)
				)
				(justify left bottom mirror)
			)
		)
		(fp_text user "License: Apache-2.0"
			(at -0.939 -5.799 0)
			(layer "B.Fab")
			(effects
				(font
					(size 0.7 0.7)
					(thickness 0.15)
				)
				(justify left bottom mirror)
			)
		)
		(fp_text user "Author: Antmicro"
			(at -0.939 -3.399 0)
			(layer "B.Fab")
			(effects
				(font
					(size 0.7 0.7)
					(thickness 0.15)
				)
				(justify left bottom mirror)
			)
		)
		(pad "1" smd roundrect
			(at -0.48 0 180)
			(size 0.59 0.64)
			(layers "B.Cu" "B.Mask" "B.Paste")
			(roundrect_rratio 0.25)
			(net 23 "GND")
			(pintype "passive")
		)
		(pad "2" smd roundrect
			(at 0.48 0 180)
			(size 0.59 0.64)
			(layers "B.Cu" "B.Mask" "B.Paste")
			(roundrect_rratio 0.25)
			(net 6 "DVDD")
			(pintype "passive")
		)
	)
	(footprint "antmicro-footprints:R_0402_1005Metric"
		(layer "B.Cu")
		(at 142.5 119.2 180)
		(descr "Resistor SMD 0402")
		(tags "resistor SMD 0402")
		(property "Reference" "R39"
			(at -19.75 7.450001 0)
			(layer "B.SilkS")
			(effects
				(font
					(size 0.7 0.7)
					(thickness 0.15)
				)
				(justify mirror)
			)
		)
		(property "Value" "R_2k2_0402"
			(at -1.011843 -1.772047 0)
			(layer "B.Fab")
			(effects
				(font
					(size 0.7 0.7)
					(thickness 0.15)
				)
				(justify left bottom mirror)
			)
		)
		(property "Datasheet" "https://www.bourns.com/docs/product-datasheets/cr.pdf"
			(at 0 0 0)
			(layer "B.Fab")
			(hide yes)
			(effects
				(font
					(size 1.27 1.27)
					(thickness 0.15)
				)
				(justify mirror)
			)
		)
		(property "Description" "SMD Chip Resistor, 2.2 kohm, ± 1%, 62.5 mW, 0402 [1005 Metric], Thick Film, General Purpose"
			(at 0 0 0)
			(layer "B.Fab")
			(hide yes)
			(effects
				(font
					(size 1.27 1.27)
					(thickness 0.15)
				)
				(justify mirror)
			)
		)
		(property "MPN" "CR0402-FX-2201GLF"
			(at 0 0 180)
			(unlocked yes)
			(layer "B.Fab")
			(hide yes)
			(effects
				(font
					(size 1 1)
					(thickness 0.15)
				)
				(justify mirror)
			)
		)
		(property "Manufacturer" "Bourns"
			(at 0 0 180)
			(unlocked yes)
			(layer "B.Fab")
			(hide yes)
			(effects
				(font
					(size 1 1)
					(thickness 0.15)
				)
				(justify mirror)
			)
		)
		(property "License" "Apache-2.0"
			(at 0 0 180)
			(unlocked yes)
			(layer "B.Fab")
			(hide yes)
			(effects
				(font
					(size 1 1)
					(thickness 0.15)
				)
				(justify mirror)
			)
		)
		(property "Val" "2k2"
			(at 0 0 180)
			(unlocked yes)
			(layer "B.Fab")
			(hide yes)
			(effects
				(font
					(size 1 1)
					(thickness 0.15)
				)
				(justify mirror)
			)
		)
		(property "Tolerance" "1%"
			(at 0 0 180)
			(unlocked yes)
			(layer "B.Fab")
			(hide yes)
			(effects
				(font
					(size 1 1)
					(thickness 0.15)
				)
				(justify mirror)
			)
		)
		(property "Author" "Antmicro"
			(at 0 0 180)
			(unlocked yes)
			(layer "B.Fab")
			(hide yes)
			(effects
				(font
					(size 1 1)
					(thickness 0.15)
				)
				(justify mirror)
			)
		)
		(sheetname "/TB Controller/")
		(sheetfile "tb.kicad_sch")
		(attr smd)
		(fp_rect
			(start -0.925 0.47)
			(end 0.925 -0.47)
			(stroke
				(width 0.05)
				(type default)
			)
			(fill no)
			(layer "B.CrtYd")
		)
		(fp_rect
			(start -0.5 0.25)
			(end 0.5 -0.25)
			(stroke
				(width 0.15)
				(type solid)
			)
			(fill no)
			(layer "B.Fab")
		)
		(fp_text user "Author: Antmicro"
			(at -0.95 -4.169 0)
			(layer "B.Fab")
			(effects
				(font
					(size 0.7 0.7)
					(thickness 0.15)
				)
				(justify left bottom mirror)
			)
		)
		(fp_text user "${REFERENCE}"
			(at -0.95 -3.168 0)
			(layer "B.Fab")
			(effects
				(font
					(size 0.7 0.7)
					(thickness 0.15)
				)
				(justify left bottom mirror)
			)
		)
		(fp_text user "License: Apache-2.0"
			(at -0.95 -5.169 0)
			(layer "B.Fab")
			(effects
				(font
					(size 0.7 0.7)
					(thickness 0.15)
				)
				(justify left bottom mirror)
			)
		)
		(pad "1" smd roundrect
			(at -0.48 0 180)
			(size 0.59 0.64)
			(layers "B.Cu" "B.Mask" "B.Paste")
			(roundrect_rratio 0.25)
			(net 23 "GND")
			(pintype "passive")
		)
		(pad "2" smd roundrect
			(at 0.48 0 180)
			(size 0.59 0.64)
			(layers "B.Cu" "B.Mask" "B.Paste")
			(roundrect_rratio 0.25)
			(net 222 "Net-(U4C-DPSNK1_DDC_DATA)")
			(pintype "passive")
		)
	)
	(footprint "antmicro-footprints:R_0402_1005Metric"
		(layer "B.Cu")
		(at 145.631866 84.260117 180)
		(descr "Resistor SMD 0402")
		(tags "resistor SMD 0402")
		(property "Reference" "R128"
			(at -17.768134 -9.464883 0)
			(layer "B.SilkS")
			(effects
				(font
					(size 0.7 0.7)
					(thickness 0.15)
				)
				(justify mirror)
			)
		)
		(property "Value" "R_100R_0402"
			(at -1.011843 -1.772047 0)
			(layer "B.Fab")
			(effects
				(font
					(size 0.7 0.7)
					(thickness 0.15)
				)
				(justify left bottom mirror)
			)
		)
		(property "Datasheet" "https://www.bourns.com/docs/product-datasheets/cr.pdf"
			(at 0 0 0)
			(layer "B.Fab")
			(hide yes)
			(effects
				(font
					(size 1.27 1.27)
					(thickness 0.15)
				)
				(justify mirror)
			)
		)
		(property "Description" "SMD Chip Resistor, 100 ohm, ± 1%, 62.5 mW, 0402 [1005 Metric], Thick Film, General Purpose"
			(at 0 0 0)
			(layer "B.Fab")
			(hide yes)
			(effects
				(font
					(size 1.27 1.27)
					(thickness 0.15)
				)
				(justify mirror)
			)
		)
		(property "MPN" "CR0402-FX-1000GLF"
			(at 0 0 180)
			(unlocked yes)
			(layer "B.Fab")
			(hide yes)
			(effects
				(font
					(size 1 1)
					(thickness 0.15)
				)
				(justify mirror)
			)
		)
		(property "Manufacturer" "Bourns"
			(at 0 0 180)
			(unlocked yes)
			(layer "B.Fab")
			(hide yes)
			(effects
				(font
					(size 1 1)
					(thickness 0.15)
				)
				(justify mirror)
			)
		)
		(property "License" "Apache-2.0"
			(at 0 0 180)
			(unlocked yes)
			(layer "B.Fab")
			(hide yes)
			(effects
				(font
					(size 1 1)
					(thickness 0.15)
				)
				(justify mirror)
			)
		)
		(property "Author" "Antmicro"
			(at 0 0 180)
			(unlocked yes)
			(layer "B.Fab")
			(hide yes)
			(effects
				(font
					(size 1 1)
					(thickness 0.15)
				)
				(justify mirror)
			)
		)
		(property "Val" "100R"
			(at 0 0 180)
			(unlocked yes)
			(layer "B.Fab")
			(hide yes)
			(effects
				(font
					(size 1 1)
					(thickness 0.15)
				)
				(justify mirror)
			)
		)
		(property "Tolerance" "1%"
			(at 0 0 180)
			(unlocked yes)
			(layer "B.Fab")
			(hide yes)
			(effects
				(font
					(size 1 1)
					(thickness 0.15)
				)
				(justify mirror)
			)
		)
		(sheetname "/X710-AT2 RSVD/")
		(sheetfile "x710-at2-rsvd.kicad_sch")
		(attr smd)
		(fp_rect
			(start -0.925 0.47)
			(end 0.925 -0.47)
			(stroke
				(width 0.05)
				(type default)
			)
			(fill no)
			(layer "B.CrtYd")
		)
		(fp_rect
			(start -0.5 0.25)
			(end 0.5 -0.25)
			(stroke
				(width 0.15)
				(type solid)
			)
			(fill no)
			(layer "B.Fab")
		)
		(fp_text user "License: Apache-2.0"
			(at -0.95 -5.169 0)
			(layer "B.Fab")
			(effects
				(font
					(size 0.7 0.7)
					(thickness 0.15)
				)
				(justify left bottom mirror)
			)
		)
		(fp_text user "Author: Antmicro"
			(at -0.95 -4.169 0)
			(layer "B.Fab")
			(effects
				(font
					(size 0.7 0.7)
					(thickness 0.15)
				)
				(justify left bottom mirror)
			)
		)
		(fp_text user "${REFERENCE}"
			(at -0.95 -3.168 0)
			(layer "B.Fab")
			(effects
				(font
					(size 0.7 0.7)
					(thickness 0.15)
				)
				(justify left bottom mirror)
			)
		)
		(pad "1" smd roundrect
			(at -0.48 0 180)
			(size 0.59 0.64)
			(layers "B.Cu" "B.Mask" "B.Paste")
			(roundrect_rratio 0.25)
			(net 23 "GND")
			(pintype "passive")
		)
		(pad "2" smd roundrect
			(at 0.48 0 180)
			(size 0.59 0.64)
			(layers "B.Cu" "B.Mask" "B.Paste")
			(roundrect_rratio 0.25)
			(net 98 "/X710-AT2 RSVD/RSVDY18_VSS")
			(pintype "passive")
		)
	)
	(footprint "antmicro-footprints:C_Pol_EIA-A"
		(layer "B.Cu")
		(at 146.7 100.5)
		(property "Reference" "C154"
			(at 2.2 -0.4 0)
			(layer "B.SilkS")
			(effects
				(font
					(size 0.7 0.7)
					(thickness 0.15)
				)
				(justify right top mirror)
			)
		)
		(property "Value" "C_Pol_100u_6V_KEMET-T490-A"
			(at 0 -2 0)
			(layer "B.Fab")
			(effects
				(font
					(size 0.7 0.7)
					(thickness 0.15)
				)
				(justify right top mirror)
			)
		)
		(property "Datasheet" "https://www.kemet.com/en/us/capacitors/product/T490A107M006ATE800.html"
			(at 0 0 0)
			(layer "B.Fab")
			(hide yes)
			(effects
				(font
					(size 1.27 1.27)
					(thickness 0.15)
				)
				(justify mirror)
			)
		)
		(property "Description" "Surface Mount Tantalum Capacitor,  Solid SMD 6V 100uF 1206 20% ESR=800mOhms"
			(at 0 0 0)
			(layer "B.Fab")
			(hide yes)
			(effects
				(font
					(size 1.27 1.27)
					(thickness 0.15)
				)
				(justify mirror)
			)
		)
		(property "Val" "100u"
			(at 0 0 0)
			(unlocked yes)
			(layer "B.Fab")
			(hide yes)
			(effects
				(font
					(size 1 1)
					(thickness 0.15)
				)
				(justify mirror)
			)
		)
		(property "MPN" "T490A107M006ATE800"
			(at 0 0 0)
			(unlocked yes)
			(layer "B.Fab")
			(hide yes)
			(effects
				(font
					(size 1 1)
					(thickness 0.15)
				)
				(justify mirror)
			)
		)
		(property "Manufacturer" "KEMET"
			(at 0 0 0)
			(unlocked yes)
			(layer "B.Fab")
			(hide yes)
			(effects
				(font
					(size 1 1)
					(thickness 0.15)
				)
				(justify mirror)
			)
		)
		(property "License" "Apache-2.0"
			(at 0 0 0)
			(unlocked yes)
			(layer "B.Fab")
			(hide yes)
			(effects
				(font
					(size 1 1)
					(thickness 0.15)
				)
				(justify mirror)
			)
		)
		(property "Author" "Antmicro"
			(at 0 0 0)
			(unlocked yes)
			(layer "B.Fab")
			(hide yes)
			(effects
				(font
					(size 1 1)
					(thickness 0.15)
				)
				(justify mirror)
			)
		)
		(property "Voltage" "6V"
			(at 0 0 0)
			(unlocked yes)
			(layer "B.Fab")
			(hide yes)
			(effects
				(font
					(size 1 1)
					(thickness 0.15)
				)
				(justify mirror)
			)
		)
		(property "Dielectric" "template_dielectric"
			(at 0 0 0)
			(unlocked yes)
			(layer "B.Fab")
			(hide yes)
			(effects
				(font
					(size 1 1)
					(thickness 0.15)
				)
				(justify mirror)
			)
		)
		(sheetname "/X710-AT2 power/")
		(sheetfile "x710-at2-power.kicad_sch")
		(attr smd)
		(fp_line
			(start -2.1 1.1)
			(end -1.8 1.1)
			(stroke
				(width 0.12)
				(type solid)
			)
			(layer "B.SilkS")
		)
		(fp_line
			(start -1.95 1.25)
			(end -1.95 0.95)
			(stroke
				(width 0.12)
				(type solid)
			)
			(layer "B.SilkS")
		)
		(fp_line
			(start -1.5 -0.75)
			(end -1.5 -0.85)
			(stroke
				(width 0.12)
				(type solid)
			)
			(layer "B.SilkS")
		)
		(fp_line
			(start -1.5 0.75)
			(end -1.5 0.85)
			(stroke
				(width 0.12)
				(type solid)
			)
			(layer "B.SilkS")
		)
		(fp_line
			(start -1.5 0.85)
			(end 1.5 0.85)
			(stroke
				(width 0.12)
				(type solid)
			)
			(layer "B.SilkS")
		)
		(fp_line
			(start 1.5 -0.85)
			(end -1.5 -0.85)
			(stroke
				(width 0.12)
				(type solid)
			)
			(layer "B.SilkS")
		)
		(fp_line
			(start 1.5 -0.75)
			(end 1.5 -0.85)
			(stroke
				(width 0.12)
				(type solid)
			)
			(layer "B.SilkS")
		)
		(fp_line
			(start 1.5 0.75)
			(end 1.5 0.85)
			(stroke
				(width 0.12)
				(type solid)
			)
			(layer "B.SilkS")
		)
		(fp_line
			(start -2.05 0.85)
			(end -2.05 -0.85)
			(stroke
				(width 0.05)
				(type solid)
			)
			(layer "B.CrtYd")
		)
		(fp_line
			(start -1.7 -1.05)
			(end -1.7 -0.85)
			(stroke
				(width 0.05)
				(type solid)
			)
			(layer "B.CrtYd")
		)
		(fp_line
			(start -1.7 -0.85)
			(end -2.05 -0.85)
			(stroke
				(width 0.05)
				(type solid)
			)
			(layer "B.CrtYd")
		)
		(fp_line
			(start -1.7 0.85)
			(end -2.05 0.85)
			(stroke
				(width 0.05)
				(type solid)
			)
			(layer "B.CrtYd")
		)
		(fp_line
			(start -1.7 0.85)
			(end -1.7 1.05)
			(stroke
				(width 0.05)
				(type solid)
			)
			(layer "B.CrtYd")
		)
		(fp_line
			(start 1.7 -1.05)
			(end -1.7 -1.05)
			(stroke
				(width 0.05)
				(type solid)
			)
			(layer "B.CrtYd")
		)
		(fp_line
			(start 1.7 -1.05)
			(end 1.7 -0.85)
			(stroke
				(width 0.05)
				(type solid)
			)
			(layer "B.CrtYd")
		)
		(fp_line
			(start 1.7 0.85)
			(end 1.7 1.05)
			(stroke
				(width 0.05)
				(type solid)
			)
			(layer "B.CrtYd")
		)
		(fp_line
			(start 1.7 1.05)
			(end -1.7 1.05)
			(stroke
				(width 0.05)
				(type solid)
			)
			(layer "B.CrtYd")
		)
		(fp_line
			(start 2.05 -0.85)
			(end 1.7 -0.85)
			(stroke
				(width 0.05)
				(type solid)
			)
			(layer "B.CrtYd")
		)
		(fp_line
			(start 2.05 0.85)
			(end 1.7 0.85)
			(stroke
				(width 0.05)
				(type solid)
			)
			(layer "B.CrtYd")
		)
		(fp_line
			(start 2.05 0.85)
			(end 2.05 -0.85)
			(stroke
				(width 0.05)
				(type solid)
			)
			(layer "B.CrtYd")
		)
		(fp_rect
			(start -1.601 0.802)
			(end 1.6 -0.8)
			(stroke
				(width 0.1)
				(type solid)
			)
			(fill no)
			(layer "B.Fab")
		)
		(fp_text user "License: Apache-2.0"
			(at -2.1 -5.198 0)
			(layer "B.Fab")
			(effects
				(font
					(size 0.7 0.7)
					(thickness 0.15)
				)
				(justify right top mirror)
			)
		)
		(fp_text user "Author: Antmicro"
			(at -2.1 -6.198 0)
			(layer "B.Fab")
			(effects
				(font
					(size 0.7 0.7)
					(thickness 0.15)
				)
				(justify right top mirror)
			)
		)
		(fp_text user "${REFERENCE}"
			(at -2.1 -4.198 0)
			(layer "B.Fab")
			(effects
				(font
					(size 0.7 0.7)
					(thickness 0.15)
				)
				(justify right top mirror)
			)
		)
		(pad "1" smd roundrect
			(at -1.2 0)
			(size 1.2 1.2)
			(layers "B.Cu" "B.Mask" "B.Paste")
			(roundrect_rratio 0.1)
			(net 6 "DVDD")
			(pintype "passive")
		)
		(pad "2" smd roundrect
			(at 1.2 0)
			(size 1.2 1.2)
			(layers "B.Cu" "B.Mask" "B.Paste")
			(roundrect_rratio 0.1)
			(net 23 "GND")
			(pintype "passive")
		)
	)
	(footprint "antmicro-footprints:R_0402_1005Metric"
		(layer "B.Cu")
		(at 138.449999 117.15)
		(descr "Resistor SMD 0402")
		(tags "resistor SMD 0402")
		(property "Reference" "R44"
			(at 19.525001 -7.450001 180)
			(layer "B.SilkS")
			(effects
				(font
					(size 0.7 0.7)
					(thickness 0.15)
				)
				(justify mirror)
			)
		)
		(property "Value" "R_10k_0402"
			(at -1.011843 -1.772047 180)
			(layer "B.Fab")
			(effects
				(font
					(size 0.7 0.7)
					(thickness 0.15)
				)
				(justify left bottom mirror)
			)
		)
		(property "Datasheet" "https://www.bourns.com/docs/product-datasheets/cr.pdf"
			(at 0 0 180)
			(layer "B.Fab")
			(hide yes)
			(effects
				(font
					(size 1.27 1.27)
					(thickness 0.15)
				)
				(justify mirror)
			)
		)
		(property "Description" "SMD Chip Resistor, 10 kohm, ± 1%, 62.5 mW, 0402 [1005 Metric], Thick Film, General Purpose"
			(at 0 0 180)
			(layer "B.Fab")
			(hide yes)
			(effects
				(font
					(size 1.27 1.27)
					(thickness 0.15)
				)
				(justify mirror)
			)
		)
		(property "MPN" "CR0402-FX-1002GLF"
			(at 0 0 0)
			(unlocked yes)
			(layer "B.Fab")
			(hide yes)
			(effects
				(font
					(size 1 1)
					(thickness 0.15)
				)
				(justify mirror)
			)
		)
		(property "Manufacturer" "Bourns"
			(at 0 0 0)
			(unlocked yes)
			(layer "B.Fab")
			(hide yes)
			(effects
				(font
					(size 1 1)
					(thickness 0.15)
				)
				(justify mirror)
			)
		)
		(property "License" "Apache-2.0"
			(at 0 0 0)
			(unlocked yes)
			(layer "B.Fab")
			(hide yes)
			(effects
				(font
					(size 1 1)
					(thickness 0.15)
				)
				(justify mirror)
			)
		)
		(property "Val" "10k"
			(at 0 0 0)
			(unlocked yes)
			(layer "B.Fab")
			(hide yes)
			(effects
				(font
					(size 1 1)
					(thickness 0.15)
				)
				(justify mirror)
			)
		)
		(property "Tolerance" "1%"
			(at 0 0 0)
			(unlocked yes)
			(layer "B.Fab")
			(hide yes)
			(effects
				(font
					(size 1 1)
					(thickness 0.15)
				)
				(justify mirror)
			)
		)
		(property "Author" "Antmicro"
			(at 0 0 0)
			(unlocked yes)
			(layer "B.Fab")
			(hide yes)
			(effects
				(font
					(size 1 1)
					(thickness 0.15)
				)
				(justify mirror)
			)
		)
		(sheetname "/TB Controller/")
		(sheetfile "tb.kicad_sch")
		(attr smd)
		(fp_rect
			(start -0.925 0.47)
			(end 0.925 -0.47)
			(stroke
				(width 0.05)
				(type default)
			)
			(fill no)
			(layer "B.CrtYd")
		)
		(fp_rect
			(start -0.5 0.25)
			(end 0.5 -0.25)
			(stroke
				(width 0.15)
				(type solid)
			)
			(fill no)
			(layer "B.Fab")
		)
		(fp_text user "${REFERENCE}"
			(at -0.95 -3.168 180)
			(layer "B.Fab")
			(effects
				(font
					(size 0.7 0.7)
					(thickness 0.15)
				)
				(justify left bottom mirror)
			)
		)
		(fp_text user "License: Apache-2.0"
			(at -0.95 -5.169 180)
			(layer "B.Fab")
			(effects
				(font
					(size 0.7 0.7)
					(thickness 0.15)
				)
				(justify left bottom mirror)
			)
		)
		(fp_text user "Author: Antmicro"
			(at -0.95 -4.169 180)
			(layer "B.Fab")
			(effects
				(font
					(size 0.7 0.7)
					(thickness 0.15)
				)
				(justify left bottom mirror)
			)
		)
		(pad "1" smd roundrect
			(at -0.48 0)
			(size 0.59 0.64)
			(layers "B.Cu" "B.Mask" "B.Paste")
			(roundrect_rratio 0.25)
			(net 187 "Net-(U4C-GPIO_4)")
			(pintype "passive")
		)
		(pad "2" smd roundrect
			(at 0.48 0)
			(size 0.59 0.64)
			(layers "B.Cu" "B.Mask" "B.Paste")
			(roundrect_rratio 0.25)
			(net 23 "GND")
			(pintype "passive")
		)
	)
	(footprint "antmicro-footprints:TP_SMD_0.75mm"
		(layer "B.Cu")
		(at 117.25 88 90)
		(property "Reference" "TP3"
			(at 0.5 -0.85 270)
			(layer "B.SilkS")
			(effects
				(font
					(size 0.7 0.7)
					(thickness 0.15)
				)
				(justify left bottom mirror)
			)
		)
		(property "Value" "TP_0.75mm_SMD"
			(at 0 -1.2 270)
			(layer "B.Fab")
			(effects
				(font
					(size 0.7 0.7)
					(thickness 0.15)
				)
				(justify left bottom mirror)
			)
		)
		(property "Description" "SMT test point"
			(at 0 0 270)
			(layer "B.Fab")
			(hide yes)
			(effects
				(font
					(size 1.27 1.27)
					(thickness 0.15)
				)
				(justify mirror)
			)
		)
		(property "License" "Apache-2.0"
			(at 0 0 90)
			(unlocked yes)
			(layer "B.Fab")
			(hide yes)
			(effects
				(font
					(size 1 1)
					(thickness 0.15)
				)
				(justify mirror)
			)
		)
		(property "Manufacturer" ""
			(at 0 0 90)
			(unlocked yes)
			(layer "B.Fab")
			(hide yes)
			(effects
				(font
					(size 1 1)
					(thickness 0.15)
				)
				(justify mirror)
			)
		)
		(property "MPN" ""
			(at 0 0 90)
			(unlocked yes)
			(layer "B.Fab")
			(hide yes)
			(effects
				(font
					(size 1 1)
					(thickness 0.15)
				)
				(justify mirror)
			)
		)
		(property "Author" "Antmicro"
			(at 0 0 90)
			(unlocked yes)
			(layer "B.Fab")
			(hide yes)
			(effects
				(font
					(size 1 1)
					(thickness 0.15)
				)
				(justify mirror)
			)
		)
		(sheetname "/PD and TB DC-DC/")
		(sheetfile "PD_and_TB_DC_DC.kicad_sch")
		(attr exclude_from_pos_files exclude_from_bom)
		(fp_circle
			(center 0 0)
			(end 0.475 0)
			(stroke
				(width 0.05)
				(type default)
			)
			(fill no)
			(layer "B.CrtYd")
		)
		(fp_text user "${REFERENCE}"
			(at -0.4 -2.7 270)
			(layer "B.Fab")
			(effects
				(font
					(size 0.7 0.7)
					(thickness 0.15)
				)
				(justify left bottom mirror)
			)
		)
		(fp_text user "License: Apache-2.0"
			(at -0.4 -5.101 270)
			(layer "B.Fab")
			(effects
				(font
					(size 0.7 0.7)
					(thickness 0.15)
				)
				(justify left bottom mirror)
			)
		)
		(fp_text user "Author: Antmicro"
			(at -0.4 -3.901 270)
			(layer "B.Fab")
			(effects
				(font
					(size 0.7 0.7)
					(thickness 0.15)
				)
				(justify left bottom mirror)
			)
		)
		(pad "1" smd circle
			(at 0 0 90)
			(size 0.75 0.75)
			(layers "B.Cu" "B.Mask")
			(net 57 "+3V3_TB")
			(pinfunction "1")
			(pintype "passive")
		)
	)
	(footprint "antmicro-footprints:C_0402_1005Metric"
		(layer "B.Cu")
		(at 128.009997 117.629999 180)
		(descr "Capacitor SMD 0402")
		(tags "capacitor SMD 0402")
		(property "Reference" "C92"
			(at -21.900002 7.700002 0)
			(layer "B.SilkS")
			(effects
				(font
					(size 0.7 0.7)
					(thickness 0.15)
				)
				(justify mirror)
			)
		)
		(property "Value" "C_1u_0402"
			(at -1.022927 -2.155213 0)
			(layer "B.Fab")
			(effects
				(font
					(size 0.7 0.7)
					(thickness 0.15)
				)
				(justify left bottom mirror)
			)
		)
		(property "Datasheet" "https://product.tdk.com/en/search/capacitor/ceramic/mlcc/info?part_no=C1005X6S1A105K050BC"
			(at 0 0 0)
			(layer "B.Fab")
			(hide yes)
			(effects
				(font
					(size 1.27 1.27)
					(thickness 0.15)
				)
				(justify mirror)
			)
		)
		(property "Description" "SMD Multilayer Ceramic Capacitor, 1 µF, 10 V, 0402 [1005 Metric], ± 10%, X6S, C"
			(at 0 0 0)
			(layer "B.Fab")
			(hide yes)
			(effects
				(font
					(size 1.27 1.27)
					(thickness 0.15)
				)
				(justify mirror)
			)
		)
		(property "MPN" "C1005X6S1A105K050BC"
			(at 0 0 180)
			(unlocked yes)
			(layer "B.Fab")
			(hide yes)
			(effects
				(font
					(size 1 1)
					(thickness 0.15)
				)
				(justify mirror)
			)
		)
		(property "Manufacturer" "TDK"
			(at 0 0 180)
			(unlocked yes)
			(layer "B.Fab")
			(hide yes)
			(effects
				(font
					(size 1 1)
					(thickness 0.15)
				)
				(justify mirror)
			)
		)
		(property "License" "Apache-2.0"
			(at 0 0 180)
			(unlocked yes)
			(layer "B.Fab")
			(hide yes)
			(effects
				(font
					(size 1 1)
					(thickness 0.15)
				)
				(justify mirror)
			)
		)
		(property "Val" "1u"
			(at 0 0 180)
			(unlocked yes)
			(layer "B.Fab")
			(hide yes)
			(effects
				(font
					(size 1 1)
					(thickness 0.15)
				)
				(justify mirror)
			)
		)
		(property "Voltage" ""
			(at 0 0 180)
			(unlocked yes)
			(layer "B.Fab")
			(hide yes)
			(effects
				(font
					(size 1 1)
					(thickness 0.15)
				)
				(justify mirror)
			)
		)
		(property "Dielectric" ""
			(at 0 0 180)
			(unlocked yes)
			(layer "B.Fab")
			(hide yes)
			(effects
				(font
					(size 1 1)
					(thickness 0.15)
				)
				(justify mirror)
			)
		)
		(property "Author" "Antmicro"
			(at 0 0 180)
			(unlocked yes)
			(layer "B.Fab")
			(hide yes)
			(effects
				(font
					(size 1 1)
					(thickness 0.15)
				)
				(justify mirror)
			)
		)
		(sheetname "/TB Controller - Power/")
		(sheetfile "tb-power.kicad_sch")
		(attr smd)
		(fp_rect
			(start -0.925 0.47)
			(end 0.925 -0.47)
			(stroke
				(width 0.05)
				(type default)
			)
			(fill no)
			(layer "B.CrtYd")
		)
		(fp_line
			(start 0.504 0.25)
			(end 0.504 -0.248)
			(stroke
				(width 0.15)
				(type solid)
			)
			(layer "B.Fab")
		)
		(fp_line
			(start 0.504 -0.248)
			(end -0.494 -0.248)
			(stroke
				(width 0.15)
				(type solid)
			)
			(layer "B.Fab")
		)
		(fp_line
			(start -0.494 0.25)
			(end 0.504 0.25)
			(stroke
				(width 0.15)
				(type solid)
			)
			(layer "B.Fab")
		)
		(fp_line
			(start -0.494 -0.248)
			(end -0.494 0.25)
			(stroke
				(width 0.15)
				(type solid)
			)
			(layer "B.Fab")
		)
		(fp_text user "${REFERENCE}"
			(at -0.939 -4.599 0)
			(layer "B.Fab")
			(effects
				(font
					(size 0.7 0.7)
					(thickness 0.15)
				)
				(justify left bottom mirror)
			)
		)
		(fp_text user "License: Apache-2.0"
			(at -0.939 -5.799 0)
			(layer "B.Fab")
			(effects
				(font
					(size 0.7 0.7)
					(thickness 0.15)
				)
				(justify left bottom mirror)
			)
		)
		(fp_text user "Author: Antmicro"
			(at -0.939 -3.399 0)
			(layer "B.Fab")
			(effects
				(font
					(size 0.7 0.7)
					(thickness 0.15)
				)
				(justify left bottom mirror)
			)
		)
		(pad "1" smd roundrect
			(at -0.48 0 180)
			(size 0.59 0.64)
			(layers "B.Cu" "B.Mask" "B.Paste")
			(roundrect_rratio 0.25)
			(net 23 "GND")
			(pintype "passive")
		)
		(pad "2" smd roundrect
			(at 0.48 0 180)
			(size 0.59 0.64)
			(layers "B.Cu" "B.Mask" "B.Paste")
			(roundrect_rratio 0.25)
			(net 181 "Net-(U4A-VCC3P3_S0)")
			(pintype "passive")
		)
	)
	(footprint "antmicro-footprints:C_0402_1005Metric"
		(layer "B.Cu")
		(at 158.926866 83.085117)
		(descr "Capacitor SMD 0402")
		(tags "capacitor SMD 0402")
		(property "Reference" "C188"
			(at 19.873134 9.464883 180)
			(layer "B.SilkS")
			(effects
				(font
					(size 0.7 0.7)
					(thickness 0.15)
				)
				(justify mirror)
			)
		)
		(property "Value" "C_1u_25V_0402"
			(at -1.022927 -2.155213 180)
			(layer "B.Fab")
			(effects
				(font
					(size 0.7 0.7)
					(thickness 0.15)
				)
				(justify left bottom mirror)
			)
		)
		(property "Datasheet" "https://www.murata.com/products/productdetail?partno=GRM155R61E105KE11%23"
			(at 0 0 180)
			(layer "B.Fab")
			(hide yes)
			(effects
				(font
					(size 1.27 1.27)
					(thickness 0.15)
				)
				(justify mirror)
			)
		)
		(property "Description" "SMD Multilayer Ceramic Capacitor, 1 µF, 25 V, 0402 [1005 Metric], ± 10%, X5R, GRM Series"
			(at 0 0 180)
			(layer "B.Fab")
			(hide yes)
			(effects
				(font
					(size 1.27 1.27)
					(thickness 0.15)
				)
				(justify mirror)
			)
		)
		(property "MPN" "GRM155R61E105KE11J"
			(at 0 0 0)
			(unlocked yes)
			(layer "B.Fab")
			(hide yes)
			(effects
				(font
					(size 1 1)
					(thickness 0.15)
				)
				(justify mirror)
			)
		)
		(property "Manufacturer" "Murata"
			(at 0 0 0)
			(unlocked yes)
			(layer "B.Fab")
			(hide yes)
			(effects
				(font
					(size 1 1)
					(thickness 0.15)
				)
				(justify mirror)
			)
		)
		(property "License" "Apache-2.0"
			(at 0 0 0)
			(unlocked yes)
			(layer "B.Fab")
			(hide yes)
			(effects
				(font
					(size 1 1)
					(thickness 0.15)
				)
				(justify mirror)
			)
		)
		(property "Author" "Antmicro"
			(at 0 0 0)
			(unlocked yes)
			(layer "B.Fab")
			(hide yes)
			(effects
				(font
					(size 1 1)
					(thickness 0.15)
				)
				(justify mirror)
			)
		)
		(property "Val" "1u"
			(at 0 0 0)
			(unlocked yes)
			(layer "B.Fab")
			(hide yes)
			(effects
				(font
					(size 1 1)
					(thickness 0.15)
				)
				(justify mirror)
			)
		)
		(property "Voltage" "25V"
			(at 0 0 0)
			(unlocked yes)
			(layer "B.Fab")
			(hide yes)
			(effects
				(font
					(size 1 1)
					(thickness 0.15)
				)
				(justify mirror)
			)
		)
		(property "Dielectric" "X5R"
			(at 0 0 0)
			(unlocked yes)
			(layer "B.Fab")
			(hide yes)
			(effects
				(font
					(size 1 1)
					(thickness 0.15)
				)
				(justify mirror)
			)
		)
		(sheetname "/X710-AT2 power/")
		(sheetfile "x710-at2-power.kicad_sch")
		(attr smd)
		(fp_rect
			(start -0.925 0.47)
			(end 0.925 -0.47)
			(stroke
				(width 0.05)
				(type default)
			)
			(fill no)
			(layer "B.CrtYd")
		)
		(fp_line
			(start -0.494 -0.248)
			(end -0.494 0.25)
			(stroke
				(width 0.15)
				(type solid)
			)
			(layer "B.Fab")
		)
		(fp_line
			(start -0.494 0.25)
			(end 0.504 0.25)
			(stroke
				(width 0.15)
				(type solid)
			)
			(layer "B.Fab")
		)
		(fp_line
			(start 0.504 -0.248)
			(end -0.494 -0.248)
			(stroke
				(width 0.15)
				(type solid)
			)
			(layer "B.Fab")
		)
		(fp_line
			(start 0.504 0.25)
			(end 0.504 -0.248)
			(stroke
				(width 0.15)
				(type solid)
			)
			(layer "B.Fab")
		)
		(fp_text user "Author: Antmicro"
			(at -0.939 -3.399 180)
			(layer "B.Fab")
			(effects
				(font
					(size 0.7 0.7)
					(thickness 0.15)
				)
				(justify left bottom mirror)
			)
		)
		(fp_text user "${REFERENCE}"
			(at -0.939 -4.599 180)
			(layer "B.Fab")
			(effects
				(font
					(size 0.7 0.7)
					(thickness 0.15)
				)
				(justify left bottom mirror)
			)
		)
		(fp_text user "License: Apache-2.0"
			(at -0.939 -5.799 180)
			(layer "B.Fab")
			(effects
				(font
					(size 0.7 0.7)
					(thickness 0.15)
				)
				(justify left bottom mirror)
			)
		)
		(pad "1" smd roundrect
			(at -0.48 0)
			(size 0.59 0.64)
			(layers "B.Cu" "B.Mask" "B.Paste")
			(roundrect_rratio 0.25)
			(net 23 "GND")
			(pintype "passive")
		)
		(pad "2" smd roundrect
			(at 0.48 0)
			(size 0.59 0.64)
			(layers "B.Cu" "B.Mask" "B.Paste")
			(roundrect_rratio 0.25)
			(net 14 "P1_AVDDL")
			(pintype "passive")
		)
	)
	(footprint "antmicro-footprints:R_0402_1005Metric"
		(layer "B.Cu")
		(at 161.981866 69.5 90)
		(descr "Resistor SMD 0402")
		(tags "resistor SMD 0402")
		(property "Reference" "R176"
			(at -2.25 0 270)
			(layer "B.SilkS")
			(effects
				(font
					(size 0.7 0.7)
					(thickness 0.15)
				)
				(justify mirror)
			)
		)
		(property "Value" "R_1k_0402"
			(at -1.011843 -1.772047 270)
			(layer "B.Fab")
			(effects
				(font
					(size 0.7 0.7)
					(thickness 0.15)
				)
				(justify left bottom mirror)
			)
		)
		(property "Datasheet" "https://www.bourns.com/docs/product-datasheets/cr.pdf"
			(at 0 0 270)
			(layer "B.Fab")
			(hide yes)
			(effects
				(font
					(size 1.27 1.27)
					(thickness 0.15)
				)
				(justify mirror)
			)
		)
		(property "Description" "SMD Chip Resistor, 1 kohm, ± 1%, 63 mW, 0402 [1005 Metric], Thick Film, General Purpose"
			(at 0 0 270)
			(layer "B.Fab")
			(hide yes)
			(effects
				(font
					(size 1.27 1.27)
					(thickness 0.15)
				)
				(justify mirror)
			)
		)
		(property "MPN" "CR0402-FX-1001GLF"
			(at 0 0 90)
			(unlocked yes)
			(layer "B.Fab")
			(hide yes)
			(effects
				(font
					(size 1 1)
					(thickness 0.15)
				)
				(justify mirror)
			)
		)
		(property "Manufacturer" "Bourns"
			(at 0 0 90)
			(unlocked yes)
			(layer "B.Fab")
			(hide yes)
			(effects
				(font
					(size 1 1)
					(thickness 0.15)
				)
				(justify mirror)
			)
		)
		(property "License" "Apache-2.0"
			(at 0 0 90)
			(unlocked yes)
			(layer "B.Fab")
			(hide yes)
			(effects
				(font
					(size 1 1)
					(thickness 0.15)
				)
				(justify mirror)
			)
		)
		(property "Author" "Antmicro"
			(at 0 0 90)
			(unlocked yes)
			(layer "B.Fab")
			(hide yes)
			(effects
				(font
					(size 1 1)
					(thickness 0.15)
				)
				(justify mirror)
			)
		)
		(property "Val" "1k"
			(at 0 0 90)
			(unlocked yes)
			(layer "B.Fab")
			(hide yes)
			(effects
				(font
					(size 1 1)
					(thickness 0.15)
				)
				(justify mirror)
			)
		)
		(property "Tolerance" "1%"
			(at 0 0 90)
			(unlocked yes)
			(layer "B.Fab")
			(hide yes)
			(effects
				(font
					(size 1 1)
					(thickness 0.15)
				)
				(justify mirror)
			)
		)
		(sheetname "/X710-AT2 Misc/")
		(sheetfile "x710-at2-mics.kicad_sch")
		(attr smd)
		(fp_rect
			(start -0.925 0.47)
			(end 0.925 -0.47)
			(stroke
				(width 0.05)
				(type default)
			)
			(fill no)
			(layer "B.CrtYd")
		)
		(fp_rect
			(start -0.5 0.25)
			(end 0.5 -0.25)
			(stroke
				(width 0.15)
				(type solid)
			)
			(fill no)
			(layer "B.Fab")
		)
		(fp_text user "License: Apache-2.0"
			(at -0.95 -5.169 270)
			(layer "B.Fab")
			(effects
				(font
					(size 0.7 0.7)
					(thickness 0.15)
				)
				(justify left bottom mirror)
			)
		)
		(fp_text user "${REFERENCE}"
			(at -0.95 -3.168 270)
			(layer "B.Fab")
			(effects
				(font
					(size 0.7 0.7)
					(thickness 0.15)
				)
				(justify left bottom mirror)
			)
		)
		(fp_text user "Author: Antmicro"
			(at -0.95 -4.169 270)
			(layer "B.Fab")
			(effects
				(font
					(size 0.7 0.7)
					(thickness 0.15)
				)
				(justify left bottom mirror)
			)
		)
		(pad "1" smd roundrect
			(at -0.48 0 90)
			(size 0.59 0.64)
			(layers "B.Cu" "B.Mask" "B.Paste")
			(roundrect_rratio 0.25)
			(net 124 "/X710-AT2 10GbE/~{P1_INT}")
			(pintype "passive")
		)
		(pad "2" smd roundrect
			(at 0.48 0 90)
			(size 0.59 0.64)
			(layers "B.Cu" "B.Mask" "B.Paste")
			(roundrect_rratio 0.25)
			(net 7 "+3V3")
			(pintype "passive")
		)
	)
	(footprint "antmicro-footprints:TP_SMD_0.75mm"
		(layer "B.Cu")
		(at 157.521866 77.185117 180)
		(property "Reference" "TP33"
			(at -20.778136 -9.414883 0)
			(layer "B.SilkS")
			(effects
				(font
					(size 0.7 0.7)
					(thickness 0.15)
				)
				(justify mirror)
			)
		)
		(property "Value" "TP_0.75mm_SMD"
			(at 0 -1.2 0)
			(layer "B.Fab")
			(effects
				(font
					(size 0.7 0.7)
					(thickness 0.15)
				)
				(justify left bottom mirror)
			)
		)
		(property "Description" "SMT test point"
			(at 0 0 0)
			(layer "B.Fab")
			(hide yes)
			(effects
				(font
					(size 1.27 1.27)
					(thickness 0.15)
				)
				(justify mirror)
			)
		)
		(property "MPN" ""
			(at 0 0 180)
			(unlocked yes)
			(layer "B.Fab")
			(hide yes)
			(effects
				(font
					(size 1 1)
					(thickness 0.15)
				)
				(justify mirror)
			)
		)
		(property "Manufacturer" ""
			(at 0 0 180)
			(unlocked yes)
			(layer "B.Fab")
			(hide yes)
			(effects
				(font
					(size 1 1)
					(thickness 0.15)
				)
				(justify mirror)
			)
		)
		(property "Author" "Antmicro"
			(at 0 0 180)
			(unlocked yes)
			(layer "B.Fab")
			(hide yes)
			(effects
				(font
					(size 1 1)
					(thickness 0.15)
				)
				(justify mirror)
			)
		)
		(property "License" "Apache-2.0"
			(at 0 0 180)
			(unlocked yes)
			(layer "B.Fab")
			(hide yes)
			(effects
				(font
					(size 1 1)
					(thickness 0.15)
				)
				(justify mirror)
			)
		)
		(sheetname "/X710-AT2 Misc/")
		(sheetfile "x710-at2-mics.kicad_sch")
		(attr exclude_from_pos_files exclude_from_bom)
		(fp_circle
			(center 0 0)
			(end 0.475 0)
			(stroke
				(width 0.05)
				(type default)
			)
			(fill no)
			(layer "B.CrtYd")
		)
		(fp_text user "Author: Antmicro"
			(at -0.4 -3.901 0)
			(layer "B.Fab")
			(effects
				(font
					(size 0.7 0.7)
					(thickness 0.15)
				)
				(justify left bottom mirror)
			)
		)
		(fp_text user "License: Apache-2.0"
			(at -0.4 -5.101 0)
			(layer "B.Fab")
			(effects
				(font
					(size 0.7 0.7)
					(thickness 0.15)
				)
				(justify left bottom mirror)
			)
		)
		(fp_text user "${REFERENCE}"
			(at -0.4 -2.7 0)
			(layer "B.Fab")
			(effects
				(font
					(size 0.7 0.7)
					(thickness 0.15)
				)
				(justify left bottom mirror)
			)
		)
		(pad "1" smd circle
			(at 0 0 180)
			(size 0.75 0.75)
			(layers "B.Cu" "B.Mask")
			(net 106 "/X710-AT2 Misc/PHY_TDI")
			(pinfunction "1")
			(pintype "passive")
		)
	)
	(footprint "antmicro-footprints:C_0402_1005Metric"
		(layer "B.Cu")
		(at 127.524999 121.999999 -90)
		(descr "Capacitor SMD 0402")
		(tags "capacitor SMD 0402")
		(property "Reference" "C87"
			(at -7.700002 -21.900002 90)
			(layer "B.SilkS")
			(effects
				(font
					(size 0.7 0.7)
					(thickness 0.15)
				)
				(justify mirror)
			)
		)
		(property "Value" "C_100n_0402"
			(at -1.022927 -2.155213 90)
			(layer "B.Fab")
			(effects
				(font
					(size 0.7 0.7)
					(thickness 0.15)
				)
				(justify left bottom mirror)
			)
		)
		(property "Datasheet" "https://www.murata.com/products/productdetail?partno=GRM155R61H104KE14%23"
			(at 0 0 90)
			(layer "B.Fab")
			(hide yes)
			(effects
				(font
					(size 1.27 1.27)
					(thickness 0.15)
				)
				(justify mirror)
			)
		)
		(property "Description" "SMD Multilayer Ceramic Capacitor, 0.1 µF, 50 V, 0402 [1005 Metric], ± 10%, X5R, GRM Series"
			(at 0 0 90)
			(layer "B.Fab")
			(hide yes)
			(effects
				(font
					(size 1.27 1.27)
					(thickness 0.15)
				)
				(justify mirror)
			)
		)
		(property "MPN" "GRM155R61H104KE14D"
			(at 0 0 270)
			(unlocked yes)
			(layer "B.Fab")
			(hide yes)
			(effects
				(font
					(size 1 1)
					(thickness 0.15)
				)
				(justify mirror)
			)
		)
		(property "Manufacturer" "Murata"
			(at 0 0 270)
			(unlocked yes)
			(layer "B.Fab")
			(hide yes)
			(effects
				(font
					(size 1 1)
					(thickness 0.15)
				)
				(justify mirror)
			)
		)
		(property "License" "Apache-2.0"
			(at 0 0 270)
			(unlocked yes)
			(layer "B.Fab")
			(hide yes)
			(effects
				(font
					(size 1 1)
					(thickness 0.15)
				)
				(justify mirror)
			)
		)
		(property "Val" "100n"
			(at 0 0 270)
			(unlocked yes)
			(layer "B.Fab")
			(hide yes)
			(effects
				(font
					(size 1 1)
					(thickness 0.15)
				)
				(justify mirror)
			)
		)
		(property "Voltage" "50V"
			(at 0 0 270)
			(unlocked yes)
			(layer "B.Fab")
			(hide yes)
			(effects
				(font
					(size 1 1)
					(thickness 0.15)
				)
				(justify mirror)
			)
		)
		(property "Dielectric" "X5R"
			(at 0 0 270)
			(unlocked yes)
			(layer "B.Fab")
			(hide yes)
			(effects
				(font
					(size 1 1)
					(thickness 0.15)
				)
				(justify mirror)
			)
		)
		(property "Author" "Antmicro"
			(at 0 0 270)
			(unlocked yes)
			(layer "B.Fab")
			(hide yes)
			(effects
				(font
					(size 1 1)
					(thickness 0.15)
				)
				(justify mirror)
			)
		)
		(sheetname "/TB Controller - Power/")
		(sheetfile "tb-power.kicad_sch")
		(attr smd)
		(fp_rect
			(start -0.925 0.47)
			(end 0.925 -0.47)
			(stroke
				(width 0.05)
				(type default)
			)
			(fill no)
			(layer "B.CrtYd")
		)
		(fp_line
			(start -0.494 0.25)
			(end 0.504 0.25)
			(stroke
				(width 0.15)
				(type solid)
			)
			(layer "B.Fab")
		)
		(fp_line
			(start 0.504 0.25)
			(end 0.504 -0.248)
			(stroke
				(width 0.15)
				(type solid)
			)
			(layer "B.Fab")
		)
		(fp_line
			(start -0.494 -0.248)
			(end -0.494 0.25)
			(stroke
				(width 0.15)
				(type solid)
			)
			(layer "B.Fab")
		)
		(fp_line
			(start 0.504 -0.248)
			(end -0.494 -0.248)
			(stroke
				(width 0.15)
				(type solid)
			)
			(layer "B.Fab")
		)
		(fp_text user "Author: Antmicro"
			(at -0.939 -3.399 90)
			(layer "B.Fab")
			(effects
				(font
					(size 0.7 0.7)
					(thickness 0.15)
				)
				(justify left bottom mirror)
			)
		)
		(fp_text user "${REFERENCE}"
			(at -0.939 -4.599 90)
			(layer "B.Fab")
			(effects
				(font
					(size 0.7 0.7)
					(thickness 0.15)
				)
				(justify left bottom mirror)
			)
		)
		(fp_text user "License: Apache-2.0"
			(at -0.939 -5.799 90)
			(layer "B.Fab")
			(effects
				(font
					(size 0.7 0.7)
					(thickness 0.15)
				)
				(justify left bottom mirror)
			)
		)
		(pad "1" smd roundrect
			(at -0.48 0 270)
			(size 0.59 0.64)
			(layers "B.Cu" "B.Mask" "B.Paste")
			(roundrect_rratio 0.25)
			(net 23 "GND")
			(pintype "passive")
		)
		(pad "2" smd roundrect
			(at 0.48 0 270)
			(size 0.59 0.64)
			(layers "B.Cu" "B.Mask" "B.Paste")
			(roundrect_rratio 0.25)
			(net 181 "Net-(U4A-VCC3P3_S0)")
			(pintype "passive")
		)
	)
	(footprint "antmicro-footprints:C_0402_1005Metric"
		(layer "B.Cu")
		(at 130.449999 122.000001 -90)
		(descr "Capacitor SMD 0402")
		(tags "capacitor SMD 0402")
		(property "Reference" "C58"
			(at -7.700002 -21.900002 90)
			(layer "B.SilkS")
			(effects
				(font
					(size 0.7 0.7)
					(thickness 0.15)
				)
				(justify mirror)
			)
		)
		(property "Value" "C_1u_0402"
			(at -1.022927 -2.155213 90)
			(layer "B.Fab")
			(effects
				(font
					(size 0.7 0.7)
					(thickness 0.15)
				)
				(justify left bottom mirror)
			)
		)
		(property "Datasheet" "https://product.tdk.com/en/search/capacitor/ceramic/mlcc/info?part_no=C1005X6S1A105K050BC"
			(at 0 0 90)
			(layer "B.Fab")
			(hide yes)
			(effects
				(font
					(size 1.27 1.27)
					(thickness 0.15)
				)
				(justify mirror)
			)
		)
		(property "Description" "SMD Multilayer Ceramic Capacitor, 1 µF, 10 V, 0402 [1005 Metric], ± 10%, X6S, C"
			(at 0 0 90)
			(layer "B.Fab")
			(hide yes)
			(effects
				(font
					(size 1.27 1.27)
					(thickness 0.15)
				)
				(justify mirror)
			)
		)
		(property "MPN" "C1005X6S1A105K050BC"
			(at 0 0 270)
			(unlocked yes)
			(layer "B.Fab")
			(hide yes)
			(effects
				(font
					(size 1 1)
					(thickness 0.15)
				)
				(justify mirror)
			)
		)
		(property "Manufacturer" "TDK"
			(at 0 0 270)
			(unlocked yes)
			(layer "B.Fab")
			(hide yes)
			(effects
				(font
					(size 1 1)
					(thickness 0.15)
				)
				(justify mirror)
			)
		)
		(property "License" "Apache-2.0"
			(at 0 0 270)
			(unlocked yes)
			(layer "B.Fab")
			(hide yes)
			(effects
				(font
					(size 1 1)
					(thickness 0.15)
				)
				(justify mirror)
			)
		)
		(property "Val" "1u"
			(at 0 0 270)
			(unlocked yes)
			(layer "B.Fab")
			(hide yes)
			(effects
				(font
					(size 1 1)
					(thickness 0.15)
				)
				(justify mirror)
			)
		)
		(property "Voltage" ""
			(at 0 0 270)
			(unlocked yes)
			(layer "B.Fab")
			(hide yes)
			(effects
				(font
					(size 1 1)
					(thickness 0.15)
				)
				(justify mirror)
			)
		)
		(property "Dielectric" ""
			(at 0 0 270)
			(unlocked yes)
			(layer "B.Fab")
			(hide yes)
			(effects
				(font
					(size 1 1)
					(thickness 0.15)
				)
				(justify mirror)
			)
		)
		(property "Author" "Antmicro"
			(at 0 0 270)
			(unlocked yes)
			(layer "B.Fab")
			(hide yes)
			(effects
				(font
					(size 1 1)
					(thickness 0.15)
				)
				(justify mirror)
			)
		)
		(sheetname "/TB Controller - Power/")
		(sheetfile "tb-power.kicad_sch")
		(attr smd)
		(fp_rect
			(start -0.925 0.47)
			(end 0.925 -0.47)
			(stroke
				(width 0.05)
				(type default)
			)
			(fill no)
			(layer "B.CrtYd")
		)
		(fp_line
			(start -0.494 0.25)
			(end 0.504 0.25)
			(stroke
				(width 0.15)
				(type solid)
			)
			(layer "B.Fab")
		)
		(fp_line
			(start 0.504 0.25)
			(end 0.504 -0.248)
			(stroke
				(width 0.15)
				(type solid)
			)
			(layer "B.Fab")
		)
		(fp_line
			(start -0.494 -0.248)
			(end -0.494 0.25)
			(stroke
				(width 0.15)
				(type solid)
			)
			(layer "B.Fab")
		)
		(fp_line
			(start 0.504 -0.248)
			(end -0.494 -0.248)
			(stroke
				(width 0.15)
				(type solid)
			)
			(layer "B.Fab")
		)
		(fp_text user "Author: Antmicro"
			(at -0.939 -3.399 90)
			(layer "B.Fab")
			(effects
				(font
					(size 0.7 0.7)
					(thickness 0.15)
				)
				(justify left bottom mirror)
			)
		)
		(fp_text user "${REFERENCE}"
			(at -0.939 -4.599 90)
			(layer "B.Fab")
			(effects
				(font
					(size 0.7 0.7)
					(thickness 0.15)
				)
				(justify left bottom mirror)
			)
		)
		(fp_text user "License: Apache-2.0"
			(at -0.939 -5.799 90)
			(layer "B.Fab")
			(effects
				(font
					(size 0.7 0.7)
					(thickness 0.15)
				)
				(justify left bottom mirror)
			)
		)
		(pad "1" smd roundrect
			(at -0.48 0 270)
			(size 0.59 0.64)
			(layers "B.Cu" "B.Mask" "B.Paste")
			(roundrect_rratio 0.25)
			(net 23 "GND")
			(pintype "passive")
		)
		(pad "2" smd roundrect
			(at 0.48 0 270)
			(size 0.59 0.64)
			(layers "B.Cu" "B.Mask" "B.Paste")
			(roundrect_rratio 0.25)
			(net 404 "Net-(C58-Pad2)")
			(pintype "passive")
		)
	)
	(footprint "antmicro-footprints:C_0402_1005Metric"
		(layer "B.Cu")
		(at 175.579998 146.66 -90)
		(descr "Capacitor SMD 0402")
		(tags "capacitor SMD 0402")
		(property "Reference" "C303"
			(at 1.09 -0.42 90)
			(layer "B.SilkS")
			(effects
				(font
					(size 0.7 0.7)
					(thickness 0.15)
				)
				(justify left bottom mirror)
			)
		)
		(property "Value" "C_470p_0402"
			(at -1.022927 -2.155213 90)
			(layer "B.Fab")
			(effects
				(font
					(size 0.7 0.7)
					(thickness 0.15)
				)
				(justify left bottom mirror)
			)
		)
		(property "Datasheet" "https://www.passivecomponent.com/wp-content/uploads/datasheet/WTC_MLCC_General_Purpose.pdf"
			(at 0 0 90)
			(layer "B.Fab")
			(hide yes)
			(effects
				(font
					(size 1.27 1.27)
					(thickness 0.15)
				)
				(justify mirror)
			)
		)
		(property "Description" "SMD Multilayer Ceramic Capacitor, General Purpose, 470 pF, 25 V, 0402 [1005 Metric], ± 10%, X7R"
			(at 0 0 90)
			(layer "B.Fab")
			(hide yes)
			(effects
				(font
					(size 1.27 1.27)
					(thickness 0.15)
				)
				(justify mirror)
			)
		)
		(property "MPN" "0402B471K250CT"
			(at 0 0 270)
			(unlocked yes)
			(layer "B.Fab")
			(hide yes)
			(effects
				(font
					(size 1 1)
					(thickness 0.15)
				)
				(justify mirror)
			)
		)
		(property "Manufacturer" "Walsin"
			(at 0 0 270)
			(unlocked yes)
			(layer "B.Fab")
			(hide yes)
			(effects
				(font
					(size 1 1)
					(thickness 0.15)
				)
				(justify mirror)
			)
		)
		(property "License" "Apache-2.0"
			(at 0 0 270)
			(unlocked yes)
			(layer "B.Fab")
			(hide yes)
			(effects
				(font
					(size 1 1)
					(thickness 0.15)
				)
				(justify mirror)
			)
		)
		(property "Author" "Antmicro"
			(at 0 0 270)
			(unlocked yes)
			(layer "B.Fab")
			(hide yes)
			(effects
				(font
					(size 1 1)
					(thickness 0.15)
				)
				(justify mirror)
			)
		)
		(property "Val" "470p"
			(at 0 0 270)
			(unlocked yes)
			(layer "B.Fab")
			(hide yes)
			(effects
				(font
					(size 1 1)
					(thickness 0.15)
				)
				(justify mirror)
			)
		)
		(property "Voltage" "25V"
			(at 0 0 270)
			(unlocked yes)
			(layer "B.Fab")
			(hide yes)
			(effects
				(font
					(size 1 1)
					(thickness 0.15)
				)
				(justify mirror)
			)
		)
		(property "Dielectric" "X7R"
			(at 0 0 270)
			(unlocked yes)
			(layer "B.Fab")
			(hide yes)
			(effects
				(font
					(size 1 1)
					(thickness 0.15)
				)
				(justify mirror)
			)
		)
		(sheetname "/2xRJ45/")
		(sheetfile "2xrj45.kicad_sch")
		(attr smd)
		(fp_rect
			(start -0.925 0.47)
			(end 0.925 -0.47)
			(stroke
				(width 0.05)
				(type default)
			)
			(fill no)
			(layer "B.CrtYd")
		)
		(fp_line
			(start -0.494 0.25)
			(end 0.504 0.25)
			(stroke
				(width 0.15)
				(type solid)
			)
			(layer "B.Fab")
		)
		(fp_line
			(start 0.504 0.25)
			(end 0.504 -0.248)
			(stroke
				(width 0.15)
				(type solid)
			)
			(layer "B.Fab")
		)
		(fp_line
			(start -0.494 -0.248)
			(end -0.494 0.25)
			(stroke
				(width 0.15)
				(type solid)
			)
			(layer "B.Fab")
		)
		(fp_line
			(start 0.504 -0.248)
			(end -0.494 -0.248)
			(stroke
				(width 0.15)
				(type solid)
			)
			(layer "B.Fab")
		)
		(fp_text user "${REFERENCE}"
			(at -0.939 -4.599 90)
			(layer "B.Fab")
			(effects
				(font
					(size 0.7 0.7)
					(thickness 0.15)
				)
				(justify left bottom mirror)
			)
		)
		(fp_text user "Author: Antmicro"
			(at -0.939 -3.399 90)
			(layer "B.Fab")
			(effects
				(font
					(size 0.7 0.7)
					(thickness 0.15)
				)
				(justify left bottom mirror)
			)
		)
		(fp_text user "License: Apache-2.0"
			(at -0.939 -5.799 90)
			(layer "B.Fab")
			(effects
				(font
					(size 0.7 0.7)
					(thickness 0.15)
				)
				(justify left bottom mirror)
			)
		)
		(pad "1" smd roundrect
			(at -0.48 0 270)
			(size 0.59 0.64)
			(layers "B.Cu" "B.Mask" "B.Paste")
			(roundrect_rratio 0.25)
			(net 23 "GND")
			(pintype "passive")
		)
		(pad "2" smd roundrect
			(at 0.48 0 270)
			(size 0.59 0.64)
			(layers "B.Cu" "B.Mask" "B.Paste")
			(roundrect_rratio 0.25)
			(net 407 "Net-(J4-LED_YG_Y-)")
			(pintype "passive")
		)
	)
	(footprint "antmicro-footprints:R_0402_1005Metric"
		(layer "B.Cu")
		(at 146.681866 92.485118 -90)
		(descr "Resistor SMD 0402")
		(tags "resistor SMD 0402")
		(property "Reference" "R177"
			(at 10.814884 -18.718134 90)
			(layer "B.SilkS")
			(effects
				(font
					(size 0.7 0.7)
					(thickness 0.15)
				)
				(justify mirror)
			)
		)
		(property "Value" "R_10k_0402"
			(at -1.011843 -1.772047 90)
			(layer "B.Fab")
			(effects
				(font
					(size 0.7 0.7)
					(thickness 0.15)
				)
				(justify left bottom mirror)
			)
		)
		(property "Datasheet" "https://www.bourns.com/docs/product-datasheets/cr.pdf"
			(at 0 0 90)
			(layer "B.Fab")
			(hide yes)
			(effects
				(font
					(size 1.27 1.27)
					(thickness 0.15)
				)
				(justify mirror)
			)
		)
		(property "Description" "SMD Chip Resistor, 10 kohm, ± 1%, 62.5 mW, 0402 [1005 Metric], Thick Film, General Purpose"
			(at 0 0 90)
			(layer "B.Fab")
			(hide yes)
			(effects
				(font
					(size 1.27 1.27)
					(thickness 0.15)
				)
				(justify mirror)
			)
		)
		(property "MPN" "CR0402-FX-1002GLF"
			(at 0 0 270)
			(unlocked yes)
			(layer "B.Fab")
			(hide yes)
			(effects
				(font
					(size 1 1)
					(thickness 0.15)
				)
				(justify mirror)
			)
		)
		(property "Manufacturer" "Bourns"
			(at 0 0 270)
			(unlocked yes)
			(layer "B.Fab")
			(hide yes)
			(effects
				(font
					(size 1 1)
					(thickness 0.15)
				)
				(justify mirror)
			)
		)
		(property "License" "Apache-2.0"
			(at 0 0 270)
			(unlocked yes)
			(layer "B.Fab")
			(hide yes)
			(effects
				(font
					(size 1 1)
					(thickness 0.15)
				)
				(justify mirror)
			)
		)
		(property "Author" "Antmicro"
			(at 0 0 270)
			(unlocked yes)
			(layer "B.Fab")
			(hide yes)
			(effects
				(font
					(size 1 1)
					(thickness 0.15)
				)
				(justify mirror)
			)
		)
		(property "Val" "10k"
			(at 0 0 270)
			(unlocked yes)
			(layer "B.Fab")
			(hide yes)
			(effects
				(font
					(size 1 1)
					(thickness 0.15)
				)
				(justify mirror)
			)
		)
		(property "Tolerance" "1%"
			(at 0 0 270)
			(unlocked yes)
			(layer "B.Fab")
			(hide yes)
			(effects
				(font
					(size 1 1)
					(thickness 0.15)
				)
				(justify mirror)
			)
		)
		(sheetname "/X710-AT2 Misc/")
		(sheetfile "x710-at2-mics.kicad_sch")
		(attr smd)
		(fp_rect
			(start -0.925 0.47)
			(end 0.925 -0.47)
			(stroke
				(width 0.05)
				(type default)
			)
			(fill no)
			(layer "B.CrtYd")
		)
		(fp_rect
			(start -0.5 0.25)
			(end 0.5 -0.25)
			(stroke
				(width 0.15)
				(type solid)
			)
			(fill no)
			(layer "B.Fab")
		)
		(fp_text user "Author: Antmicro"
			(at -0.95 -4.169 90)
			(layer "B.Fab")
			(effects
				(font
					(size 0.7 0.7)
					(thickness 0.15)
				)
				(justify left bottom mirror)
			)
		)
		(fp_text user "License: Apache-2.0"
			(at -0.95 -5.169 90)
			(layer "B.Fab")
			(effects
				(font
					(size 0.7 0.7)
					(thickness 0.15)
				)
				(justify left bottom mirror)
			)
		)
		(fp_text user "${REFERENCE}"
			(at -0.95 -3.168 90)
			(layer "B.Fab")
			(effects
				(font
					(size 0.7 0.7)
					(thickness 0.15)
				)
				(justify left bottom mirror)
			)
		)
		(pad "1" smd roundrect
			(at -0.48 0 270)
			(size 0.59 0.64)
			(layers "B.Cu" "B.Mask" "B.Paste")
			(roundrect_rratio 0.25)
			(net 73 "/X710-AT2 Misc/~{SMBALRT}")
			(pintype "passive")
		)
		(pad "2" smd roundrect
			(at 0.48 0 270)
			(size 0.59 0.64)
			(layers "B.Cu" "B.Mask" "B.Paste")
			(roundrect_rratio 0.25)
			(net 7 "+3V3")
			(pintype "passive")
		)
	)
	(footprint "antmicro-footprints:C_0805_2012Metric"
		(layer "B.Cu")
		(at 166.6 139.25)
		(descr "Capacitor SMD 0805")
		(tags "capacitor SMD 0805")
		(property "Reference" "C293"
			(at 4.9 0.5 180)
			(layer "B.SilkS")
			(effects
				(font
					(size 0.7 0.7)
					(thickness 0.15)
				)
				(justify left bottom mirror)
			)
		)
		(property "Value" "C_100u_0805"
			(at -2.055717 -1.963152 180)
			(layer "B.Fab")
			(effects
				(font
					(size 0.7 0.7)
					(thickness 0.15)
				)
				(justify left bottom mirror)
			)
		)
		(property "Datasheet" "https://www.murata.com/products/productdetail?partno=GRM21BR60J107ME15%23"
			(at 0 0 180)
			(layer "B.Fab")
			(hide yes)
			(effects
				(font
					(size 1.27 1.27)
					(thickness 0.15)
				)
				(justify mirror)
			)
		)
		(property "Description" "SMD Multilayer Ceramic Capacitor, 100 µF, 6.3 V, 0805 [2012 Metric], ± 20%, X5R, GRM Series"
			(at 0 0 180)
			(layer "B.Fab")
			(hide yes)
			(effects
				(font
					(size 1.27 1.27)
					(thickness 0.15)
				)
				(justify mirror)
			)
		)
		(property "MPN" "GRM21BR60J107ME15L"
			(at 0 0 0)
			(unlocked yes)
			(layer "B.Fab")
			(hide yes)
			(effects
				(font
					(size 1 1)
					(thickness 0.15)
				)
				(justify mirror)
			)
		)
		(property "Manufacturer" "Murata"
			(at 0 0 0)
			(unlocked yes)
			(layer "B.Fab")
			(hide yes)
			(effects
				(font
					(size 1 1)
					(thickness 0.15)
				)
				(justify mirror)
			)
		)
		(property "License" "Apache-2.0"
			(at 0 0 0)
			(unlocked yes)
			(layer "B.Fab")
			(hide yes)
			(effects
				(font
					(size 1 1)
					(thickness 0.15)
				)
				(justify mirror)
			)
		)
		(property "Author" "Antmicro"
			(at 0 0 0)
			(unlocked yes)
			(layer "B.Fab")
			(hide yes)
			(effects
				(font
					(size 1 1)
					(thickness 0.15)
				)
				(justify mirror)
			)
		)
		(property "Val" "100u"
			(at 0 0 0)
			(unlocked yes)
			(layer "B.Fab")
			(hide yes)
			(effects
				(font
					(size 1 1)
					(thickness 0.15)
				)
				(justify mirror)
			)
		)
		(property "Voltage" ""
			(at 0 0 0)
			(unlocked yes)
			(layer "B.Fab")
			(hide yes)
			(effects
				(font
					(size 1 1)
					(thickness 0.15)
				)
				(justify mirror)
			)
		)
		(property "Dielectric" ""
			(at 0 0 0)
			(unlocked yes)
			(layer "B.Fab")
			(hide yes)
			(effects
				(font
					(size 1 1)
					(thickness 0.15)
				)
				(justify mirror)
			)
		)
		(property "Public" "False"
			(at 0 0 0)
			(unlocked yes)
			(layer "B.Fab")
			(hide yes)
			(effects
				(font
					(size 1 1)
					(thickness 0.15)
				)
				(justify mirror)
			)
		)
		(sheetname "/2xRJ45/")
		(sheetfile "2xrj45.kicad_sch")
		(attr smd)
		(fp_line
			(start -0.3 -0.7)
			(end 0.3 -0.7)
			(stroke
				(width 0.15)
				(type solid)
			)
			(layer "B.SilkS")
		)
		(fp_line
			(start -0.3 0.7)
			(end 0.3 0.7)
			(stroke
				(width 0.15)
				(type solid)
			)
			(layer "B.SilkS")
		)
		(fp_rect
			(start 1.95 0.9)
			(end -1.95 -0.9)
			(stroke
				(width 0.05)
				(type default)
			)
			(fill no)
			(layer "B.CrtYd")
		)
		(fp_rect
			(start -0.95 0.675)
			(end 0.95 -0.675)
			(stroke
				(width 0.15)
				(type solid)
			)
			(fill no)
			(layer "B.Fab")
		)
		(fp_text user "Author: Antmicro"
			(at -1.9 -5.947 180)
			(layer "B.Fab")
			(effects
				(font
					(size 0.7 0.7)
					(thickness 0.15)
				)
				(justify left bottom mirror)
			)
		)
		(fp_text user "${REFERENCE}"
			(at -1.9 -3.947 180)
			(layer "B.Fab")
			(effects
				(font
					(size 0.7 0.7)
					(thickness 0.15)
				)
				(justify left bottom mirror)
			)
		)
		(fp_text user "License: Apache-2.0"
			(at -1.9 -4.947 180)
			(layer "B.Fab")
			(effects
				(font
					(size 0.7 0.7)
					(thickness 0.15)
				)
				(justify left bottom mirror)
			)
		)
		(pad "1" smd roundrect
			(at -1.1 0)
			(size 1.2 1.3)
			(layers "B.Cu" "B.Mask" "B.Paste")
			(roundrect_rratio 0.25)
			(net 23 "GND")
			(pintype "passive")
		)
		(pad "2" smd roundrect
			(at 1.1 0)
			(size 1.2 1.3)
			(layers "B.Cu" "B.Mask" "B.Paste")
			(roundrect_rratio 0.25)
			(net 134 "/2xRJ45/P1_CT")
			(pintype "passive")
		)
	)
	(footprint "antmicro-footprints:C_0402_1005Metric"
		(layer "B.Cu")
		(at 145.631866 79.260116 180)
		(descr "Capacitor SMD 0402")
		(tags "capacitor SMD 0402")
		(property "Reference" "C250"
			(at -17.768134 -9.464883 0)
			(layer "B.SilkS")
			(effects
				(font
					(size 0.7 0.7)
					(thickness 0.15)
				)
				(justify mirror)
			)
		)
		(property "Value" "C_1u_25V_0402"
			(at -1.022927 -2.155213 0)
			(layer "B.Fab")
			(effects
				(font
					(size 0.7 0.7)
					(thickness 0.15)
				)
				(justify left bottom mirror)
			)
		)
		(property "Datasheet" "https://www.murata.com/products/productdetail?partno=GRM155R61E105KE11%23"
			(at 0 0 0)
			(layer "B.Fab")
			(hide yes)
			(effects
				(font
					(size 1.27 1.27)
					(thickness 0.15)
				)
				(justify mirror)
			)
		)
		(property "Description" "SMD Multilayer Ceramic Capacitor, 1 µF, 25 V, 0402 [1005 Metric], ± 10%, X5R, GRM Series"
			(at 0 0 0)
			(layer "B.Fab")
			(hide yes)
			(effects
				(font
					(size 1.27 1.27)
					(thickness 0.15)
				)
				(justify mirror)
			)
		)
		(property "MPN" "GRM155R61E105KE11J"
			(at 0 0 180)
			(unlocked yes)
			(layer "B.Fab")
			(hide yes)
			(effects
				(font
					(size 1 1)
					(thickness 0.15)
				)
				(justify mirror)
			)
		)
		(property "Manufacturer" "Murata"
			(at 0 0 180)
			(unlocked yes)
			(layer "B.Fab")
			(hide yes)
			(effects
				(font
					(size 1 1)
					(thickness 0.15)
				)
				(justify mirror)
			)
		)
		(property "License" "Apache-2.0"
			(at 0 0 180)
			(unlocked yes)
			(layer "B.Fab")
			(hide yes)
			(effects
				(font
					(size 1 1)
					(thickness 0.15)
				)
				(justify mirror)
			)
		)
		(property "Author" "Antmicro"
			(at 0 0 180)
			(unlocked yes)
			(layer "B.Fab")
			(hide yes)
			(effects
				(font
					(size 1 1)
					(thickness 0.15)
				)
				(justify mirror)
			)
		)
		(property "Val" "1u"
			(at 0 0 180)
			(unlocked yes)
			(layer "B.Fab")
			(hide yes)
			(effects
				(font
					(size 1 1)
					(thickness 0.15)
				)
				(justify mirror)
			)
		)
		(property "Voltage" "25V"
			(at 0 0 180)
			(unlocked yes)
			(layer "B.Fab")
			(hide yes)
			(effects
				(font
					(size 1 1)
					(thickness 0.15)
				)
				(justify mirror)
			)
		)
		(property "Dielectric" "X5R"
			(at 0 0 180)
			(unlocked yes)
			(layer "B.Fab")
			(hide yes)
			(effects
				(font
					(size 1 1)
					(thickness 0.15)
				)
				(justify mirror)
			)
		)
		(sheetname "/X710-AT2 power/")
		(sheetfile "x710-at2-power.kicad_sch")
		(attr smd)
		(fp_rect
			(start -0.925 0.47)
			(end 0.925 -0.47)
			(stroke
				(width 0.05)
				(type default)
			)
			(fill no)
			(layer "B.CrtYd")
		)
		(fp_line
			(start 0.504 0.25)
			(end 0.504 -0.248)
			(stroke
				(width 0.15)
				(type solid)
			)
			(layer "B.Fab")
		)
		(fp_line
			(start 0.504 -0.248)
			(end -0.494 -0.248)
			(stroke
				(width 0.15)
				(type solid)
			)
			(layer "B.Fab")
		)
		(fp_line
			(start -0.494 0.25)
			(end 0.504 0.25)
			(stroke
				(width 0.15)
				(type solid)
			)
			(layer "B.Fab")
		)
		(fp_line
			(start -0.494 -0.248)
			(end -0.494 0.25)
			(stroke
				(width 0.15)
				(type solid)
			)
			(layer "B.Fab")
		)
		(fp_text user "${REFERENCE}"
			(at -0.939 -4.599 0)
			(layer "B.Fab")
			(effects
				(font
					(size 0.7 0.7)
					(thickness 0.15)
				)
				(justify left bottom mirror)
			)
		)
		(fp_text user "License: Apache-2.0"
			(at -0.939 -5.799 0)
			(layer "B.Fab")
			(effects
				(font
					(size 0.7 0.7)
					(thickness 0.15)
				)
				(justify left bottom mirror)
			)
		)
		(fp_text user "Author: Antmicro"
			(at -0.939 -3.399 0)
			(layer "B.Fab")
			(effects
				(font
					(size 0.7 0.7)
					(thickness 0.15)
				)
				(justify left bottom mirror)
			)
		)
		(pad "1" smd roundrect
			(at -0.48 0 180)
			(size 0.59 0.64)
			(layers "B.Cu" "B.Mask" "B.Paste")
			(roundrect_rratio 0.25)
			(net 23 "GND")
			(pintype "passive")
		)
		(pad "2" smd roundrect
			(at 0.48 0 180)
			(size 0.59 0.64)
			(layers "B.Cu" "B.Mask" "B.Paste")
			(roundrect_rratio 0.25)
			(net 1 "VCCA")
			(pintype "passive")
		)
	)
	(footprint "antmicro-footprints:R_0402_1005Metric"
		(layer "B.Cu")
		(at 140.6 115.1)
		(descr "Resistor SMD 0402")
		(tags "resistor SMD 0402")
		(property "Reference" "R37"
			(at 19.525001 -7.450001 180)
			(layer "B.SilkS")
			(effects
				(font
					(size 0.7 0.7)
					(thickness 0.15)
				)
				(justify mirror)
			)
		)
		(property "Value" "R_100k_0402"
			(at -1.011843 -1.772047 180)
			(layer "B.Fab")
			(effects
				(font
					(size 0.7 0.7)
					(thickness 0.15)
				)
				(justify left bottom mirror)
			)
		)
		(property "Datasheet" "https://www.bourns.com/docs/product-datasheets/cr.pdf"
			(at 0 0 180)
			(layer "B.Fab")
			(hide yes)
			(effects
				(font
					(size 1.27 1.27)
					(thickness 0.15)
				)
				(justify mirror)
			)
		)
		(property "Description" "SMD Chip Resistor, 100 kohm, ± 1%, 62.5 mW, 0402 [1005 Metric], Thick Film, General Purpose"
			(at 0 0 180)
			(layer "B.Fab")
			(hide yes)
			(effects
				(font
					(size 1.27 1.27)
					(thickness 0.15)
				)
				(justify mirror)
			)
		)
		(property "MPN" "CR0402-FX-1003GLF"
			(at 0 0 0)
			(unlocked yes)
			(layer "B.Fab")
			(hide yes)
			(effects
				(font
					(size 1 1)
					(thickness 0.15)
				)
				(justify mirror)
			)
		)
		(property "Manufacturer" "Bourns"
			(at 0 0 0)
			(unlocked yes)
			(layer "B.Fab")
			(hide yes)
			(effects
				(font
					(size 1 1)
					(thickness 0.15)
				)
				(justify mirror)
			)
		)
		(property "License" "Apache-2.0"
			(at 0 0 0)
			(unlocked yes)
			(layer "B.Fab")
			(hide yes)
			(effects
				(font
					(size 1 1)
					(thickness 0.15)
				)
				(justify mirror)
			)
		)
		(property "Val" "100k"
			(at 0 0 0)
			(unlocked yes)
			(layer "B.Fab")
			(hide yes)
			(effects
				(font
					(size 1 1)
					(thickness 0.15)
				)
				(justify mirror)
			)
		)
		(property "Tolerance" "1%"
			(at 0 0 0)
			(unlocked yes)
			(layer "B.Fab")
			(hide yes)
			(effects
				(font
					(size 1 1)
					(thickness 0.15)
				)
				(justify mirror)
			)
		)
		(property "Author" "Antmicro"
			(at 0 0 0)
			(unlocked yes)
			(layer "B.Fab")
			(hide yes)
			(effects
				(font
					(size 1 1)
					(thickness 0.15)
				)
				(justify mirror)
			)
		)
		(sheetname "/TB Controller/")
		(sheetfile "tb.kicad_sch")
		(attr smd)
		(fp_rect
			(start -0.925 0.47)
			(end 0.925 -0.47)
			(stroke
				(width 0.05)
				(type default)
			)
			(fill no)
			(layer "B.CrtYd")
		)
		(fp_rect
			(start -0.5 0.25)
			(end 0.5 -0.25)
			(stroke
				(width 0.15)
				(type solid)
			)
			(fill no)
			(layer "B.Fab")
		)
		(fp_text user "Author: Antmicro"
			(at -0.95 -4.169 180)
			(layer "B.Fab")
			(effects
				(font
					(size 0.7 0.7)
					(thickness 0.15)
				)
				(justify left bottom mirror)
			)
		)
		(fp_text user "${REFERENCE}"
			(at -0.95 -3.168 180)
			(layer "B.Fab")
			(effects
				(font
					(size 0.7 0.7)
					(thickness 0.15)
				)
				(justify left bottom mirror)
			)
		)
		(fp_text user "License: Apache-2.0"
			(at -0.95 -5.169 180)
			(layer "B.Fab")
			(effects
				(font
					(size 0.7 0.7)
					(thickness 0.15)
				)
				(justify left bottom mirror)
			)
		)
		(pad "1" smd roundrect
			(at -0.48 0)
			(size 0.59 0.64)
			(layers "B.Cu" "B.Mask" "B.Paste")
			(roundrect_rratio 0.25)
			(net 23 "GND")
			(pintype "passive")
		)
		(pad "2" smd roundrect
			(at 0.48 0)
			(size 0.59 0.64)
			(layers "B.Cu" "B.Mask" "B.Paste")
			(roundrect_rratio 0.25)
			(net 220 "Net-(U4C-DPSNK1_HPD)")
			(pintype "passive")
		)
	)
	(footprint "antmicro-footprints:R_0402_1005Metric"
		(layer "B.Cu")
		(at 138.350001 136.599999)
		(descr "Resistor SMD 0402")
		(tags "resistor SMD 0402")
		(property "Reference" "R27"
			(at 19.525001 -8.1 180)
			(layer "B.SilkS")
			(effects
				(font
					(size 0.7 0.7)
					(thickness 0.15)
				)
				(justify mirror)
			)
		)
		(property "Value" "R_100k_0402"
			(at -1.011843 -1.772047 180)
			(layer "B.Fab")
			(effects
				(font
					(size 0.7 0.7)
					(thickness 0.15)
				)
				(justify left bottom mirror)
			)
		)
		(property "Datasheet" "https://www.bourns.com/docs/product-datasheets/cr.pdf"
			(at 0 0 180)
			(layer "B.Fab")
			(hide yes)
			(effects
				(font
					(size 1.27 1.27)
					(thickness 0.15)
				)
				(justify mirror)
			)
		)
		(property "Description" "SMD Chip Resistor, 100 kohm, ± 1%, 62.5 mW, 0402 [1005 Metric], Thick Film, General Purpose"
			(at 0 0 180)
			(layer "B.Fab")
			(hide yes)
			(effects
				(font
					(size 1.27 1.27)
					(thickness 0.15)
				)
				(justify mirror)
			)
		)
		(property "MPN" "CR0402-FX-1003GLF"
			(at 0 0 0)
			(unlocked yes)
			(layer "B.Fab")
			(hide yes)
			(effects
				(font
					(size 1 1)
					(thickness 0.15)
				)
				(justify mirror)
			)
		)
		(property "Manufacturer" "Bourns"
			(at 0 0 0)
			(unlocked yes)
			(layer "B.Fab")
			(hide yes)
			(effects
				(font
					(size 1 1)
					(thickness 0.15)
				)
				(justify mirror)
			)
		)
		(property "License" "Apache-2.0"
			(at 0 0 0)
			(unlocked yes)
			(layer "B.Fab")
			(hide yes)
			(effects
				(font
					(size 1 1)
					(thickness 0.15)
				)
				(justify mirror)
			)
		)
		(property "Val" "100k"
			(at 0 0 0)
			(unlocked yes)
			(layer "B.Fab")
			(hide yes)
			(effects
				(font
					(size 1 1)
					(thickness 0.15)
				)
				(justify mirror)
			)
		)
		(property "Tolerance" "1%"
			(at 0 0 0)
			(unlocked yes)
			(layer "B.Fab")
			(hide yes)
			(effects
				(font
					(size 1 1)
					(thickness 0.15)
				)
				(justify mirror)
			)
		)
		(property "Author" "Antmicro"
			(at 0 0 0)
			(unlocked yes)
			(layer "B.Fab")
			(hide yes)
			(effects
				(font
					(size 1 1)
					(thickness 0.15)
				)
				(justify mirror)
			)
		)
		(sheetname "/PD and TB DC-DC/")
		(sheetfile "PD_and_TB_DC_DC.kicad_sch")
		(attr smd)
		(fp_rect
			(start -0.925 0.47)
			(end 0.925 -0.47)
			(stroke
				(width 0.05)
				(type default)
			)
			(fill no)
			(layer "B.CrtYd")
		)
		(fp_rect
			(start -0.5 0.25)
			(end 0.5 -0.25)
			(stroke
				(width 0.15)
				(type solid)
			)
			(fill no)
			(layer "B.Fab")
		)
		(fp_text user "Author: Antmicro"
			(at -0.95 -4.169 180)
			(layer "B.Fab")
			(effects
				(font
					(size 0.7 0.7)
					(thickness 0.15)
				)
				(justify left bottom mirror)
			)
		)
		(fp_text user "${REFERENCE}"
			(at -0.95 -3.168 180)
			(layer "B.Fab")
			(effects
				(font
					(size 0.7 0.7)
					(thickness 0.15)
				)
				(justify left bottom mirror)
			)
		)
		(fp_text user "License: Apache-2.0"
			(at -0.95 -5.169 180)
			(layer "B.Fab")
			(effects
				(font
					(size 0.7 0.7)
					(thickness 0.15)
				)
				(justify left bottom mirror)
			)
		)
		(pad "1" smd roundrect
			(at -0.48 0)
			(size 0.59 0.64)
			(layers "B.Cu" "B.Mask" "B.Paste")
			(roundrect_rratio 0.25)
			(net 210 "Net-(U3-HRESET)")
			(pintype "passive")
		)
		(pad "2" smd roundrect
			(at 0.48 0)
			(size 0.59 0.64)
			(layers "B.Cu" "B.Mask" "B.Paste")
			(roundrect_rratio 0.25)
			(net 23 "GND")
			(pintype "passive")
		)
	)
	(footprint "antmicro-footprints:C_0402_1005Metric"
		(layer "B.Cu")
		(at 147.481866 79.260117 180)
		(descr "Capacitor SMD 0402")
		(tags "capacitor SMD 0402")
		(property "Reference" "C223"
			(at -18.618135 -9.464883 0)
			(layer "B.SilkS")
			(effects
				(font
					(size 0.7 0.7)
					(thickness 0.15)
				)
				(justify mirror)
			)
		)
		(property "Value" "C_1u_25V_0402"
			(at -1.022927 -2.155213 0)
			(layer "B.Fab")
			(effects
				(font
					(size 0.7 0.7)
					(thickness 0.15)
				)
				(justify left bottom mirror)
			)
		)
		(property "Datasheet" "https://www.murata.com/products/productdetail?partno=GRM155R61E105KE11%23"
			(at 0 0 0)
			(layer "B.Fab")
			(hide yes)
			(effects
				(font
					(size 1.27 1.27)
					(thickness 0.15)
				)
				(justify mirror)
			)
		)
		(property "Description" "SMD Multilayer Ceramic Capacitor, 1 µF, 25 V, 0402 [1005 Metric], ± 10%, X5R, GRM Series"
			(at 0 0 0)
			(layer "B.Fab")
			(hide yes)
			(effects
				(font
					(size 1.27 1.27)
					(thickness 0.15)
				)
				(justify mirror)
			)
		)
		(property "MPN" "GRM155R61E105KE11J"
			(at 0 0 180)
			(unlocked yes)
			(layer "B.Fab")
			(hide yes)
			(effects
				(font
					(size 1 1)
					(thickness 0.15)
				)
				(justify mirror)
			)
		)
		(property "Manufacturer" "Murata"
			(at 0 0 180)
			(unlocked yes)
			(layer "B.Fab")
			(hide yes)
			(effects
				(font
					(size 1 1)
					(thickness 0.15)
				)
				(justify mirror)
			)
		)
		(property "License" "Apache-2.0"
			(at 0 0 180)
			(unlocked yes)
			(layer "B.Fab")
			(hide yes)
			(effects
				(font
					(size 1 1)
					(thickness 0.15)
				)
				(justify mirror)
			)
		)
		(property "Author" "Antmicro"
			(at 0 0 180)
			(unlocked yes)
			(layer "B.Fab")
			(hide yes)
			(effects
				(font
					(size 1 1)
					(thickness 0.15)
				)
				(justify mirror)
			)
		)
		(property "Val" "1u"
			(at 0 0 180)
			(unlocked yes)
			(layer "B.Fab")
			(hide yes)
			(effects
				(font
					(size 1 1)
					(thickness 0.15)
				)
				(justify mirror)
			)
		)
		(property "Voltage" "25V"
			(at 0 0 180)
			(unlocked yes)
			(layer "B.Fab")
			(hide yes)
			(effects
				(font
					(size 1 1)
					(thickness 0.15)
				)
				(justify mirror)
			)
		)
		(property "Dielectric" "X5R"
			(at 0 0 180)
			(unlocked yes)
			(layer "B.Fab")
			(hide yes)
			(effects
				(font
					(size 1 1)
					(thickness 0.15)
				)
				(justify mirror)
			)
		)
		(sheetname "/X710-AT2 power/")
		(sheetfile "x710-at2-power.kicad_sch")
		(attr smd)
		(fp_rect
			(start -0.925 0.47)
			(end 0.925 -0.47)
			(stroke
				(width 0.05)
				(type default)
			)
			(fill no)
			(layer "B.CrtYd")
		)
		(fp_line
			(start 0.504 0.25)
			(end 0.504 -0.248)
			(stroke
				(width 0.15)
				(type solid)
			)
			(layer "B.Fab")
		)
		(fp_line
			(start 0.504 -0.248)
			(end -0.494 -0.248)
			(stroke
				(width 0.15)
				(type solid)
			)
			(layer "B.Fab")
		)
		(fp_line
			(start -0.494 0.25)
			(end 0.504 0.25)
			(stroke
				(width 0.15)
				(type solid)
			)
			(layer "B.Fab")
		)
		(fp_line
			(start -0.494 -0.248)
			(end -0.494 0.25)
			(stroke
				(width 0.15)
				(type solid)
			)
			(layer "B.Fab")
		)
		(fp_text user "Author: Antmicro"
			(at -0.939 -3.399 0)
			(layer "B.Fab")
			(effects
				(font
					(size 0.7 0.7)
					(thickness 0.15)
				)
				(justify left bottom mirror)
			)
		)
		(fp_text user "License: Apache-2.0"
			(at -0.939 -5.799 0)
			(layer "B.Fab")
			(effects
				(font
					(size 0.7 0.7)
					(thickness 0.15)
				)
				(justify left bottom mirror)
			)
		)
		(fp_text user "${REFERENCE}"
			(at -0.939 -4.599 0)
			(layer "B.Fab")
			(effects
				(font
					(size 0.7 0.7)
					(thickness 0.15)
				)
				(justify left bottom mirror)
			)
		)
		(pad "1" smd roundrect
			(at -0.48 0 180)
			(size 0.59 0.64)
			(layers "B.Cu" "B.Mask" "B.Paste")
			(roundrect_rratio 0.25)
			(net 23 "GND")
			(pintype "passive")
		)
		(pad "2" smd roundrect
			(at 0.48 0 180)
			(size 0.59 0.64)
			(layers "B.Cu" "B.Mask" "B.Paste")
			(roundrect_rratio 0.25)
			(net 9 "VCCD")
			(pintype "passive")
		)
	)
	(footprint "antmicro-footprints:R_0402_1005Metric"
		(layer "B.Cu")
		(at 172.58 146.66 90)
		(descr "Resistor SMD 0402")
		(tags "resistor SMD 0402")
		(property "Reference" "R215"
			(at -1.09 0.42 270)
			(layer "B.SilkS")
			(effects
				(font
					(size 0.7 0.7)
					(thickness 0.15)
				)
				(justify left bottom mirror)
			)
		)
		(property "Value" "R_220R_0402"
			(at -1.011843 -1.772047 270)
			(layer "B.Fab")
			(effects
				(font
					(size 0.7 0.7)
					(thickness 0.15)
				)
				(justify left bottom mirror)
			)
		)
		(property "Datasheet" "https://www.bourns.com/docs/product-datasheets/cr.pdf"
			(at 0 0 270)
			(layer "B.Fab")
			(hide yes)
			(effects
				(font
					(size 1.27 1.27)
					(thickness 0.15)
				)
				(justify mirror)
			)
		)
		(property "Description" "SMD Chip Resistor, 220 ohm, ± 1%, 62.5 mW, 0402 [1005 Metric], Thick Film, General Purpose"
			(at 0 0 270)
			(layer "B.Fab")
			(hide yes)
			(effects
				(font
					(size 1.27 1.27)
					(thickness 0.15)
				)
				(justify mirror)
			)
		)
		(property "MPN" "CR0402-FX-2200GLF"
			(at 0 0 90)
			(unlocked yes)
			(layer "B.Fab")
			(hide yes)
			(effects
				(font
					(size 1 1)
					(thickness 0.15)
				)
				(justify mirror)
			)
		)
		(property "Manufacturer" "Bourns"
			(at 0 0 90)
			(unlocked yes)
			(layer "B.Fab")
			(hide yes)
			(effects
				(font
					(size 1 1)
					(thickness 0.15)
				)
				(justify mirror)
			)
		)
		(property "License" "Apache-2.0"
			(at 0 0 90)
			(unlocked yes)
			(layer "B.Fab")
			(hide yes)
			(effects
				(font
					(size 1 1)
					(thickness 0.15)
				)
				(justify mirror)
			)
		)
		(property "Author" "Antmicro"
			(at 0 0 90)
			(unlocked yes)
			(layer "B.Fab")
			(hide yes)
			(effects
				(font
					(size 1 1)
					(thickness 0.15)
				)
				(justify mirror)
			)
		)
		(property "Val" "220R"
			(at 0 0 90)
			(unlocked yes)
			(layer "B.Fab")
			(hide yes)
			(effects
				(font
					(size 1 1)
					(thickness 0.15)
				)
				(justify mirror)
			)
		)
		(property "Tolerance" "1%"
			(at 0 0 90)
			(unlocked yes)
			(layer "B.Fab")
			(hide yes)
			(effects
				(font
					(size 1 1)
					(thickness 0.15)
				)
				(justify mirror)
			)
		)
		(sheetname "/2xRJ45/")
		(sheetfile "2xrj45.kicad_sch")
		(attr smd)
		(fp_rect
			(start -0.925 0.47)
			(end 0.925 -0.47)
			(stroke
				(width 0.05)
				(type default)
			)
			(fill no)
			(layer "B.CrtYd")
		)
		(fp_rect
			(start -0.5 0.25)
			(end 0.5 -0.25)
			(stroke
				(width 0.15)
				(type solid)
			)
			(fill no)
			(layer "B.Fab")
		)
		(fp_text user "${REFERENCE}"
			(at -0.95 -3.168 270)
			(layer "B.Fab")
			(effects
				(font
					(size 0.7 0.7)
					(thickness 0.15)
				)
				(justify left bottom mirror)
			)
		)
		(fp_text user "Author: Antmicro"
			(at -0.95 -4.169 270)
			(layer "B.Fab")
			(effects
				(font
					(size 0.7 0.7)
					(thickness 0.15)
				)
				(justify left bottom mirror)
			)
		)
		(fp_text user "License: Apache-2.0"
			(at -0.95 -5.169 270)
			(layer "B.Fab")
			(effects
				(font
					(size 0.7 0.7)
					(thickness 0.15)
				)
				(justify left bottom mirror)
			)
		)
		(pad "1" smd roundrect
			(at -0.48 0 90)
			(size 0.59 0.64)
			(layers "B.Cu" "B.Mask" "B.Paste")
			(roundrect_rratio 0.25)
			(net 411 "Net-(J4-LED_GRN-)")
			(pintype "passive")
		)
		(pad "2" smd roundrect
			(at 0.48 0 90)
			(size 0.59 0.64)
			(layers "B.Cu" "B.Mask" "B.Paste")
			(roundrect_rratio 0.25)
			(net 67 "/2xRJ45/~{P1_LED_ACT}")
			(pintype "passive")
		)
	)
	(footprint "antmicro-footprints:C_0402_1005Metric"
		(layer "B.Cu")
		(at 133.85 133.099999 -90)
		(descr "Capacitor SMD 0402")
		(tags "capacitor SMD 0402")
		(property "Reference" "C15"
			(at -8.339997 -19.525001 90)
			(layer "B.SilkS")
			(effects
				(font
					(size 0.7 0.7)
					(thickness 0.15)
				)
				(justify mirror)
			)
		)
		(property "Value" "C_10u_0402"
			(at -1.022927 -2.155213 90)
			(layer "B.Fab")
			(effects
				(font
					(size 0.7 0.7)
					(thickness 0.15)
				)
				(justify left bottom mirror)
			)
		)
		(property "Datasheet" "https://www.yageo.com/en/Chart/Download/pdf/CC0402MRX5R5BB106"
			(at 0 0 90)
			(layer "B.Fab")
			(hide yes)
			(effects
				(font
					(size 1.27 1.27)
					(thickness 0.15)
				)
				(justify mirror)
			)
		)
		(property "Description" "SMD Multilayer Ceramic Capacitor, 10 µF, 6.3 V, 0402 [1005 Metric], ± 20%, X5R, CC Series"
			(at 0 0 90)
			(layer "B.Fab")
			(hide yes)
			(effects
				(font
					(size 1.27 1.27)
					(thickness 0.15)
				)
				(justify mirror)
			)
		)
		(property "MPN" "CC0402MRX5R5BB106"
			(at 0 0 270)
			(unlocked yes)
			(layer "B.Fab")
			(hide yes)
			(effects
				(font
					(size 1 1)
					(thickness 0.15)
				)
				(justify mirror)
			)
		)
		(property "Manufacturer" "YAGEO"
			(at 0 0 270)
			(unlocked yes)
			(layer "B.Fab")
			(hide yes)
			(effects
				(font
					(size 1 1)
					(thickness 0.15)
				)
				(justify mirror)
			)
		)
		(property "License" "Apache-2.0"
			(at 0 0 270)
			(unlocked yes)
			(layer "B.Fab")
			(hide yes)
			(effects
				(font
					(size 1 1)
					(thickness 0.15)
				)
				(justify mirror)
			)
		)
		(property "Val" "10u"
			(at 0 0 270)
			(unlocked yes)
			(layer "B.Fab")
			(hide yes)
			(effects
				(font
					(size 1 1)
					(thickness 0.15)
				)
				(justify mirror)
			)
		)
		(property "Voltage" ""
			(at 0 0 270)
			(unlocked yes)
			(layer "B.Fab")
			(hide yes)
			(effects
				(font
					(size 1 1)
					(thickness 0.15)
				)
				(justify mirror)
			)
		)
		(property "Dielectric" ""
			(at 0 0 270)
			(unlocked yes)
			(layer "B.Fab")
			(hide yes)
			(effects
				(font
					(size 1 1)
					(thickness 0.15)
				)
				(justify mirror)
			)
		)
		(property "Author" "Antmicro"
			(at 0 0 270)
			(unlocked yes)
			(layer "B.Fab")
			(hide yes)
			(effects
				(font
					(size 1 1)
					(thickness 0.15)
				)
				(justify mirror)
			)
		)
		(sheetname "/PD and TB DC-DC/")
		(sheetfile "PD_and_TB_DC_DC.kicad_sch")
		(attr smd)
		(fp_rect
			(start -0.925 0.47)
			(end 0.925 -0.47)
			(stroke
				(width 0.05)
				(type default)
			)
			(fill no)
			(layer "B.CrtYd")
		)
		(fp_line
			(start -0.494 0.25)
			(end 0.504 0.25)
			(stroke
				(width 0.15)
				(type solid)
			)
			(layer "B.Fab")
		)
		(fp_line
			(start 0.504 0.25)
			(end 0.504 -0.248)
			(stroke
				(width 0.15)
				(type solid)
			)
			(layer "B.Fab")
		)
		(fp_line
			(start -0.494 -0.248)
			(end -0.494 0.25)
			(stroke
				(width 0.15)
				(type solid)
			)
			(layer "B.Fab")
		)
		(fp_line
			(start 0.504 -0.248)
			(end -0.494 -0.248)
			(stroke
				(width 0.15)
				(type solid)
			)
			(layer "B.Fab")
		)
		(fp_text user "License: Apache-2.0"
			(at -0.939 -5.799 90)
			(layer "B.Fab")
			(effects
				(font
					(size 0.7 0.7)
					(thickness 0.15)
				)
				(justify left bottom mirror)
			)
		)
		(fp_text user "${REFERENCE}"
			(at -0.939 -4.599 90)
			(layer "B.Fab")
			(effects
				(font
					(size 0.7 0.7)
					(thickness 0.15)
				)
				(justify left bottom mirror)
			)
		)
		(fp_text user "Author: Antmicro"
			(at -0.939 -3.399 90)
			(layer "B.Fab")
			(effects
				(font
					(size 0.7 0.7)
					(thickness 0.15)
				)
				(justify left bottom mirror)
			)
		)
		(pad "1" smd roundrect
			(at -0.48 0 270)
			(size 0.59 0.64)
			(layers "B.Cu" "B.Mask" "B.Paste")
			(roundrect_rratio 0.25)
			(net 23 "GND")
			(pintype "passive")
		)
		(pad "2" smd roundrect
			(at 0.48 0 270)
			(size 0.59 0.64)
			(layers "B.Cu" "B.Mask" "B.Paste")
			(roundrect_rratio 0.25)
			(net 57 "+3V3_TB")
			(pintype "passive")
		)
	)
	(footprint "antmicro-footprints:R_0402_1005Metric"
		(layer "B.Cu")
		(at 134.840001 135.089997 -90)
		(descr "Resistor SMD 0402")
		(tags "resistor SMD 0402")
		(property "Reference" "R29"
			(at -8.339997 -19.525001 90)
			(layer "B.SilkS")
			(effects
				(font
					(size 0.7 0.7)
					(thickness 0.15)
				)
				(justify mirror)
			)
		)
		(property "Value" "R_15k_0.1%_0402"
			(at -1.011843 -1.772047 90)
			(layer "B.Fab")
			(effects
				(font
					(size 0.7 0.7)
					(thickness 0.15)
				)
				(justify left bottom mirror)
			)
		)
		(property "Datasheet" "https://www.mouser.com/datasheet/2/315/AOA0000C307-1149632.pdf"
			(at 0 0 90)
			(layer "B.Fab")
			(hide yes)
			(effects
				(font
					(size 1.27 1.27)
					(thickness 0.15)
				)
				(justify mirror)
			)
		)
		(property "Description" "SMD Chip Resistor, 15 kohm, ± 0.1%, 62.5 mW, 0402 [1005 Metric], Metal Film (Thin Film)"
			(at 0 0 90)
			(layer "B.Fab")
			(hide yes)
			(effects
				(font
					(size 1.27 1.27)
					(thickness 0.15)
				)
				(justify mirror)
			)
		)
		(property "MPN" "ERA-2ARB153X"
			(at 0 0 270)
			(unlocked yes)
			(layer "B.Fab")
			(hide yes)
			(effects
				(font
					(size 1 1)
					(thickness 0.15)
				)
				(justify mirror)
			)
		)
		(property "Manufacturer" "Panasonic"
			(at 0 0 270)
			(unlocked yes)
			(layer "B.Fab")
			(hide yes)
			(effects
				(font
					(size 1 1)
					(thickness 0.15)
				)
				(justify mirror)
			)
		)
		(property "License" "Apache-2.0"
			(at 0 0 270)
			(unlocked yes)
			(layer "B.Fab")
			(hide yes)
			(effects
				(font
					(size 1 1)
					(thickness 0.15)
				)
				(justify mirror)
			)
		)
		(property "Val" "15k"
			(at 0 0 270)
			(unlocked yes)
			(layer "B.Fab")
			(hide yes)
			(effects
				(font
					(size 1 1)
					(thickness 0.15)
				)
				(justify mirror)
			)
		)
		(property "Tolerance" "0.1%"
			(at 0 0 270)
			(unlocked yes)
			(layer "B.Fab")
			(hide yes)
			(effects
				(font
					(size 1 1)
					(thickness 0.15)
				)
				(justify mirror)
			)
		)
		(property "Author" "Antmicro"
			(at 0 0 270)
			(unlocked yes)
			(layer "B.Fab")
			(hide yes)
			(effects
				(font
					(size 1 1)
					(thickness 0.15)
				)
				(justify mirror)
			)
		)
		(sheetname "/PD and TB DC-DC/")
		(sheetfile "PD_and_TB_DC_DC.kicad_sch")
		(attr smd)
		(fp_rect
			(start -0.925 0.47)
			(end 0.925 -0.47)
			(stroke
				(width 0.05)
				(type default)
			)
			(fill no)
			(layer "B.CrtYd")
		)
		(fp_rect
			(start -0.5 0.25)
			(end 0.5 -0.25)
			(stroke
				(width 0.15)
				(type solid)
			)
			(fill no)
			(layer "B.Fab")
		)
		(fp_text user "Author: Antmicro"
			(at -0.95 -4.169 90)
			(layer "B.Fab")
			(effects
				(font
					(size 0.7 0.7)
					(thickness 0.15)
				)
				(justify left bottom mirror)
			)
		)
		(fp_text user "License: Apache-2.0"
			(at -0.95 -5.169 90)
			(layer "B.Fab")
			(effects
				(font
					(size 0.7 0.7)
					(thickness 0.15)
				)
				(justify left bottom mirror)
			)
		)
		(fp_text user "${REFERENCE}"
			(at -0.95 -3.168 90)
			(layer "B.Fab")
			(effects
				(font
					(size 0.7 0.7)
					(thickness 0.15)
				)
				(justify left bottom mirror)
			)
		)
		(pad "1" smd roundrect
			(at -0.48 0 270)
			(size 0.59 0.64)
			(layers "B.Cu" "B.Mask" "B.Paste")
			(roundrect_rratio 0.25)
			(net 212 "Net-(U3-R_OSC)")
			(pintype "passive")
		)
		(pad "2" smd roundrect
			(at 0.48 0 270)
			(size 0.59 0.64)
			(layers "B.Cu" "B.Mask" "B.Paste")
			(roundrect_rratio 0.25)
			(net 23 "GND")
			(pintype "passive")
		)
	)
	(footprint "antmicro-footprints:R_0402_1005Metric"
		(layer "B.Cu")
		(at 139.199998 132.600001 180)
		(descr "Resistor SMD 0402")
		(tags "resistor SMD 0402")
		(property "Reference" "R9"
			(at -19.525001 8.1 0)
			(layer "B.SilkS")
			(effects
				(font
					(size 0.7 0.7)
					(thickness 0.15)
				)
				(justify mirror)
			)
		)
		(property "Value" "R_2k2_0402"
			(at -1.011843 -1.772047 0)
			(layer "B.Fab")
			(effects
				(font
					(size 0.7 0.7)
					(thickness 0.15)
				)
				(justify left bottom mirror)
			)
		)
		(property "Datasheet" "https://www.bourns.com/docs/product-datasheets/cr.pdf"
			(at 0 0 0)
			(layer "B.Fab")
			(hide yes)
			(effects
				(font
					(size 1.27 1.27)
					(thickness 0.15)
				)
				(justify mirror)
			)
		)
		(property "Description" "SMD Chip Resistor, 2.2 kohm, ± 1%, 62.5 mW, 0402 [1005 Metric], Thick Film, General Purpose"
			(at 0 0 0)
			(layer "B.Fab")
			(hide yes)
			(effects
				(font
					(size 1.27 1.27)
					(thickness 0.15)
				)
				(justify mirror)
			)
		)
		(property "MPN" "CR0402-FX-2201GLF"
			(at 0 0 180)
			(unlocked yes)
			(layer "B.Fab")
			(hide yes)
			(effects
				(font
					(size 1 1)
					(thickness 0.15)
				)
				(justify mirror)
			)
		)
		(property "Manufacturer" "Bourns"
			(at 0 0 180)
			(unlocked yes)
			(layer "B.Fab")
			(hide yes)
			(effects
				(font
					(size 1 1)
					(thickness 0.15)
				)
				(justify mirror)
			)
		)
		(property "License" "Apache-2.0"
			(at 0 0 180)
			(unlocked yes)
			(layer "B.Fab")
			(hide yes)
			(effects
				(font
					(size 1 1)
					(thickness 0.15)
				)
				(justify mirror)
			)
		)
		(property "Val" "2k2"
			(at 0 0 180)
			(unlocked yes)
			(layer "B.Fab")
			(hide yes)
			(effects
				(font
					(size 1 1)
					(thickness 0.15)
				)
				(justify mirror)
			)
		)
		(property "Tolerance" "1%"
			(at 0 0 180)
			(unlocked yes)
			(layer "B.Fab")
			(hide yes)
			(effects
				(font
					(size 1 1)
					(thickness 0.15)
				)
				(justify mirror)
			)
		)
		(property "Author" "Antmicro"
			(at 0 0 180)
			(unlocked yes)
			(layer "B.Fab")
			(hide yes)
			(effects
				(font
					(size 1 1)
					(thickness 0.15)
				)
				(justify mirror)
			)
		)
		(sheetname "/PD and TB DC-DC/")
		(sheetfile "PD_and_TB_DC_DC.kicad_sch")
		(attr smd)
		(fp_rect
			(start -0.925 0.47)
			(end 0.925 -0.47)
			(stroke
				(width 0.05)
				(type default)
			)
			(fill no)
			(layer "B.CrtYd")
		)
		(fp_rect
			(start -0.5 0.25)
			(end 0.5 -0.25)
			(stroke
				(width 0.15)
				(type solid)
			)
			(fill no)
			(layer "B.Fab")
		)
		(fp_text user "Author: Antmicro"
			(at -0.95 -4.169 0)
			(layer "B.Fab")
			(effects
				(font
					(size 0.7 0.7)
					(thickness 0.15)
				)
				(justify left bottom mirror)
			)
		)
		(fp_text user "License: Apache-2.0"
			(at -0.95 -5.169 0)
			(layer "B.Fab")
			(effects
				(font
					(size 0.7 0.7)
					(thickness 0.15)
				)
				(justify left bottom mirror)
			)
		)
		(fp_text user "${REFERENCE}"
			(at -0.95 -3.168 0)
			(layer "B.Fab")
			(effects
				(font
					(size 0.7 0.7)
					(thickness 0.15)
				)
				(justify left bottom mirror)
			)
		)
		(pad "1" smd roundrect
			(at -0.48 0 180)
			(size 0.59 0.64)
			(layers "B.Cu" "B.Mask" "B.Paste")
			(roundrect_rratio 0.25)
			(net 373 "/PD and TB DC-DC/I2C1.SCL")
			(pintype "passive")
		)
		(pad "2" smd roundrect
			(at 0.48 0 180)
			(size 0.59 0.64)
			(layers "B.Cu" "B.Mask" "B.Paste")
			(roundrect_rratio 0.25)
			(net 57 "+3V3_TB")
			(pintype "passive")
		)
	)
	(footprint "antmicro-footprints:C_0402_1005Metric"
		(layer "B.Cu")
		(at 157.961866 86.015117)
		(descr "Capacitor SMD 0402")
		(tags "capacitor SMD 0402")
		(property "Reference" "C192"
			(at 20.793134 9.464883 180)
			(layer "B.SilkS")
			(effects
				(font
					(size 0.7 0.7)
					(thickness 0.15)
				)
				(justify mirror)
			)
		)
		(property "Value" "C_1u_25V_0402"
			(at -1.022927 -2.155213 180)
			(layer "B.Fab")
			(effects
				(font
					(size 0.7 0.7)
					(thickness 0.15)
				)
				(justify left bottom mirror)
			)
		)
		(property "Datasheet" "https://www.murata.com/products/productdetail?partno=GRM155R61E105KE11%23"
			(at 0 0 180)
			(layer "B.Fab")
			(hide yes)
			(effects
				(font
					(size 1.27 1.27)
					(thickness 0.15)
				)
				(justify mirror)
			)
		)
		(property "Description" "SMD Multilayer Ceramic Capacitor, 1 µF, 25 V, 0402 [1005 Metric], ± 10%, X5R, GRM Series"
			(at 0 0 180)
			(layer "B.Fab")
			(hide yes)
			(effects
				(font
					(size 1.27 1.27)
					(thickness 0.15)
				)
				(justify mirror)
			)
		)
		(property "MPN" "GRM155R61E105KE11J"
			(at 0 0 0)
			(unlocked yes)
			(layer "B.Fab")
			(hide yes)
			(effects
				(font
					(size 1 1)
					(thickness 0.15)
				)
				(justify mirror)
			)
		)
		(property "Manufacturer" "Murata"
			(at 0 0 0)
			(unlocked yes)
			(layer "B.Fab")
			(hide yes)
			(effects
				(font
					(size 1 1)
					(thickness 0.15)
				)
				(justify mirror)
			)
		)
		(property "License" "Apache-2.0"
			(at 0 0 0)
			(unlocked yes)
			(layer "B.Fab")
			(hide yes)
			(effects
				(font
					(size 1 1)
					(thickness 0.15)
				)
				(justify mirror)
			)
		)
		(property "Author" "Antmicro"
			(at 0 0 0)
			(unlocked yes)
			(layer "B.Fab")
			(hide yes)
			(effects
				(font
					(size 1 1)
					(thickness 0.15)
				)
				(justify mirror)
			)
		)
		(property "Val" "1u"
			(at 0 0 0)
			(unlocked yes)
			(layer "B.Fab")
			(hide yes)
			(effects
				(font
					(size 1 1)
					(thickness 0.15)
				)
				(justify mirror)
			)
		)
		(property "Voltage" "25V"
			(at 0 0 0)
			(unlocked yes)
			(layer "B.Fab")
			(hide yes)
			(effects
				(font
					(size 1 1)
					(thickness 0.15)
				)
				(justify mirror)
			)
		)
		(property "Dielectric" "X5R"
			(at 0 0 0)
			(unlocked yes)
			(layer "B.Fab")
			(hide yes)
			(effects
				(font
					(size 1 1)
					(thickness 0.15)
				)
				(justify mirror)
			)
		)
		(sheetname "/X710-AT2 power/")
		(sheetfile "x710-at2-power.kicad_sch")
		(attr smd)
		(fp_rect
			(start -0.925 0.47)
			(end 0.925 -0.47)
			(stroke
				(width 0.05)
				(type default)
			)
			(fill no)
			(layer "B.CrtYd")
		)
		(fp_line
			(start -0.494 -0.248)
			(end -0.494 0.25)
			(stroke
				(width 0.15)
				(type solid)
			)
			(layer "B.Fab")
		)
		(fp_line
			(start -0.494 0.25)
			(end 0.504 0.25)
			(stroke
				(width 0.15)
				(type solid)
			)
			(layer "B.Fab")
		)
		(fp_line
			(start 0.504 -0.248)
			(end -0.494 -0.248)
			(stroke
				(width 0.15)
				(type solid)
			)
			(layer "B.Fab")
		)
		(fp_line
			(start 0.504 0.25)
			(end 0.504 -0.248)
			(stroke
				(width 0.15)
				(type solid)
			)
			(layer "B.Fab")
		)
		(fp_text user "Author: Antmicro"
			(at -0.939 -3.399 180)
			(layer "B.Fab")
			(effects
				(font
					(size 0.7 0.7)
					(thickness 0.15)
				)
				(justify left bottom mirror)
			)
		)
		(fp_text user "License: Apache-2.0"
			(at -0.939 -5.799 180)
			(layer "B.Fab")
			(effects
				(font
					(size 0.7 0.7)
					(thickness 0.15)
				)
				(justify left bottom mirror)
			)
		)
		(fp_text user "${REFERENCE}"
			(at -0.939 -4.599 180)
			(layer "B.Fab")
			(effects
				(font
					(size 0.7 0.7)
					(thickness 0.15)
				)
				(justify left bottom mirror)
			)
		)
		(pad "1" smd roundrect
			(at -0.48 0)
			(size 0.59 0.64)
			(layers "B.Cu" "B.Mask" "B.Paste")
			(roundrect_rratio 0.25)
			(net 23 "GND")
			(pintype "passive")
		)
		(pad "2" smd roundrect
			(at 0.48 0)
			(size 0.59 0.64)
			(layers "B.Cu" "B.Mask" "B.Paste")
			(roundrect_rratio 0.25)
			(net 10 "AVDDH")
			(pintype "passive")
		)
	)
	(footprint "antmicro-footprints:C_0402_1005Metric"
		(layer "B.Cu")
		(at 138.35 139.55 180)
		(descr "Capacitor SMD 0402")
		(tags "capacitor SMD 0402")
		(property "Reference" "C13"
			(at -19.525001 8.1 0)
			(layer "B.SilkS")
			(effects
				(font
					(size 0.7 0.7)
					(thickness 0.15)
				)
				(justify mirror)
			)
		)
		(property "Value" "C_4u7_25V_0402"
			(at -1.022927 -2.155213 0)
			(layer "B.Fab")
			(effects
				(font
					(size 0.7 0.7)
					(thickness 0.15)
				)
				(justify left bottom mirror)
			)
		)
		(property "Datasheet" "https://www.murata.com/products/productdetail?partno=GRM155C61E475ME15%23"
			(at 0 0 0)
			(layer "B.Fab")
			(hide yes)
			(effects
				(font
					(size 1.27 1.27)
					(thickness 0.15)
				)
				(justify mirror)
			)
		)
		(property "Description" "SMD Multilayer Ceramic Capacitor"
			(at 0 0 0)
			(layer "B.Fab")
			(hide yes)
			(effects
				(font
					(size 1.27 1.27)
					(thickness 0.15)
				)
				(justify mirror)
			)
		)
		(property "MPN" "GRM155C61E475ME15J"
			(at 0 0 180)
			(unlocked yes)
			(layer "B.Fab")
			(hide yes)
			(effects
				(font
					(size 1 1)
					(thickness 0.15)
				)
				(justify mirror)
			)
		)
		(property "Manufacturer" "Murata"
			(at 0 0 180)
			(unlocked yes)
			(layer "B.Fab")
			(hide yes)
			(effects
				(font
					(size 1 1)
					(thickness 0.15)
				)
				(justify mirror)
			)
		)
		(property "License" "Apache-2.0"
			(at 0 0 180)
			(unlocked yes)
			(layer "B.Fab")
			(hide yes)
			(effects
				(font
					(size 1 1)
					(thickness 0.15)
				)
				(justify mirror)
			)
		)
		(property "Val" "4u7"
			(at 0 0 180)
			(unlocked yes)
			(layer "B.Fab")
			(hide yes)
			(effects
				(font
					(size 1 1)
					(thickness 0.15)
				)
				(justify mirror)
			)
		)
		(property "Voltage" "25V"
			(at 0 0 180)
			(unlocked yes)
			(layer "B.Fab")
			(hide yes)
			(effects
				(font
					(size 1 1)
					(thickness 0.15)
				)
				(justify mirror)
			)
		)
		(property "Dielectric" "X5S"
			(at 0 0 180)
			(unlocked yes)
			(layer "B.Fab")
			(hide yes)
			(effects
				(font
					(size 1 1)
					(thickness 0.15)
				)
				(justify mirror)
			)
		)
		(property "Author" "Antmicro"
			(at 0 0 180)
			(unlocked yes)
			(layer "B.Fab")
			(hide yes)
			(effects
				(font
					(size 1 1)
					(thickness 0.15)
				)
				(justify mirror)
			)
		)
		(sheetname "/PD and TB DC-DC/")
		(sheetfile "PD_and_TB_DC_DC.kicad_sch")
		(attr smd)
		(fp_rect
			(start -0.925 0.47)
			(end 0.925 -0.47)
			(stroke
				(width 0.05)
				(type default)
			)
			(fill no)
			(layer "B.CrtYd")
		)
		(fp_line
			(start 0.504 0.25)
			(end 0.504 -0.248)
			(stroke
				(width 0.15)
				(type solid)
			)
			(layer "B.Fab")
		)
		(fp_line
			(start 0.504 -0.248)
			(end -0.494 -0.248)
			(stroke
				(width 0.15)
				(type solid)
			)
			(layer "B.Fab")
		)
		(fp_line
			(start -0.494 0.25)
			(end 0.504 0.25)
			(stroke
				(width 0.15)
				(type solid)
			)
			(layer "B.Fab")
		)
		(fp_line
			(start -0.494 -0.248)
			(end -0.494 0.25)
			(stroke
				(width 0.15)
				(type solid)
			)
			(layer "B.Fab")
		)
		(fp_text user "${REFERENCE}"
			(at -0.939 -4.599 0)
			(layer "B.Fab")
			(effects
				(font
					(size 0.7 0.7)
					(thickness 0.15)
				)
				(justify left bottom mirror)
			)
		)
		(fp_text user "Author: Antmicro"
			(at -0.939 -3.399 0)
			(layer "B.Fab")
			(effects
				(font
					(size 0.7 0.7)
					(thickness 0.15)
				)
				(justify left bottom mirror)
			)
		)
		(fp_text user "License: Apache-2.0"
			(at -0.939 -5.799 0)
			(layer "B.Fab")
			(effects
				(font
					(size 0.7 0.7)
					(thickness 0.15)
				)
				(justify left bottom mirror)
			)
		)
		(pad "1" smd roundrect
			(at -0.48 0 180)
			(size 0.59 0.64)
			(layers "B.Cu" "B.Mask" "B.Paste")
			(roundrect_rratio 0.25)
			(net 23 "GND")
			(pintype "passive")
		)
		(pad "2" smd roundrect
			(at 0.48 0 180)
			(size 0.59 0.64)
			(layers "B.Cu" "B.Mask" "B.Paste")
			(roundrect_rratio 0.25)
			(net 173 "PP_5V0")
			(pintype "passive")
		)
	)
	(footprint "antmicro-footprints:C_0402_1005Metric"
		(layer "B.Cu")
		(at 153.031866 77.260118 180)
		(descr "Capacitor SMD 0402")
		(tags "capacitor SMD 0402")
		(property "Reference" "C236"
			(at -21.168135 -9.464883 0)
			(layer "B.SilkS")
			(effects
				(font
					(size 0.7 0.7)
					(thickness 0.15)
				)
				(justify mirror)
			)
		)
		(property "Value" "C_1u_25V_0402"
			(at -1.022927 -2.155213 0)
			(layer "B.Fab")
			(effects
				(font
					(size 0.7 0.7)
					(thickness 0.15)
				)
				(justify left bottom mirror)
			)
		)
		(property "Datasheet" "https://www.murata.com/products/productdetail?partno=GRM155R61E105KE11%23"
			(at 0 0 0)
			(layer "B.Fab")
			(hide yes)
			(effects
				(font
					(size 1.27 1.27)
					(thickness 0.15)
				)
				(justify mirror)
			)
		)
		(property "Description" "SMD Multilayer Ceramic Capacitor, 1 µF, 25 V, 0402 [1005 Metric], ± 10%, X5R, GRM Series"
			(at 0 0 0)
			(layer "B.Fab")
			(hide yes)
			(effects
				(font
					(size 1.27 1.27)
					(thickness 0.15)
				)
				(justify mirror)
			)
		)
		(property "MPN" "GRM155R61E105KE11J"
			(at 0 0 180)
			(unlocked yes)
			(layer "B.Fab")
			(hide yes)
			(effects
				(font
					(size 1 1)
					(thickness 0.15)
				)
				(justify mirror)
			)
		)
		(property "Manufacturer" "Murata"
			(at 0 0 180)
			(unlocked yes)
			(layer "B.Fab")
			(hide yes)
			(effects
				(font
					(size 1 1)
					(thickness 0.15)
				)
				(justify mirror)
			)
		)
		(property "License" "Apache-2.0"
			(at 0 0 180)
			(unlocked yes)
			(layer "B.Fab")
			(hide yes)
			(effects
				(font
					(size 1 1)
					(thickness 0.15)
				)
				(justify mirror)
			)
		)
		(property "Author" "Antmicro"
			(at 0 0 180)
			(unlocked yes)
			(layer "B.Fab")
			(hide yes)
			(effects
				(font
					(size 1 1)
					(thickness 0.15)
				)
				(justify mirror)
			)
		)
		(property "Val" "1u"
			(at 0 0 180)
			(unlocked yes)
			(layer "B.Fab")
			(hide yes)
			(effects
				(font
					(size 1 1)
					(thickness 0.15)
				)
				(justify mirror)
			)
		)
		(property "Voltage" "25V"
			(at 0 0 180)
			(unlocked yes)
			(layer "B.Fab")
			(hide yes)
			(effects
				(font
					(size 1 1)
					(thickness 0.15)
				)
				(justify mirror)
			)
		)
		(property "Dielectric" "X5R"
			(at 0 0 180)
			(unlocked yes)
			(layer "B.Fab")
			(hide yes)
			(effects
				(font
					(size 1 1)
					(thickness 0.15)
				)
				(justify mirror)
			)
		)
		(sheetname "/X710-AT2 power/")
		(sheetfile "x710-at2-power.kicad_sch")
		(attr smd)
		(fp_rect
			(start -0.925 0.47)
			(end 0.925 -0.47)
			(stroke
				(width 0.05)
				(type default)
			)
			(fill no)
			(layer "B.CrtYd")
		)
		(fp_line
			(start 0.504 0.25)
			(end 0.504 -0.248)
			(stroke
				(width 0.15)
				(type solid)
			)
			(layer "B.Fab")
		)
		(fp_line
			(start 0.504 -0.248)
			(end -0.494 -0.248)
			(stroke
				(width 0.15)
				(type solid)
			)
			(layer "B.Fab")
		)
		(fp_line
			(start -0.494 0.25)
			(end 0.504 0.25)
			(stroke
				(width 0.15)
				(type solid)
			)
			(layer "B.Fab")
		)
		(fp_line
			(start -0.494 -0.248)
			(end -0.494 0.25)
			(stroke
				(width 0.15)
				(type solid)
			)
			(layer "B.Fab")
		)
		(fp_text user "${REFERENCE}"
			(at -0.939 -4.599 0)
			(layer "B.Fab")
			(effects
				(font
					(size 0.7 0.7)
					(thickness 0.15)
				)
				(justify left bottom mirror)
			)
		)
		(fp_text user "License: Apache-2.0"
			(at -0.939 -5.799 0)
			(layer "B.Fab")
			(effects
				(font
					(size 0.7 0.7)
					(thickness 0.15)
				)
				(justify left bottom mirror)
			)
		)
		(fp_text user "Author: Antmicro"
			(at -0.939 -3.399 0)
			(layer "B.Fab")
			(effects
				(font
					(size 0.7 0.7)
					(thickness 0.15)
				)
				(justify left bottom mirror)
			)
		)
		(pad "1" smd roundrect
			(at -0.48 0 180)
			(size 0.59 0.64)
			(layers "B.Cu" "B.Mask" "B.Paste")
			(roundrect_rratio 0.25)
			(net 23 "GND")
			(pintype "passive")
		)
		(pad "2" smd roundrect
			(at 0.48 0 180)
			(size 0.59 0.64)
			(layers "B.Cu" "B.Mask" "B.Paste")
			(roundrect_rratio 0.25)
			(net 1 "VCCA")
			(pintype "passive")
		)
	)
	(footprint "antmicro-footprints:C_0402_1005Metric"
		(layer "B.Cu")
		(at 145.631866 77.260117 180)
		(descr "Capacitor SMD 0402")
		(tags "capacitor SMD 0402")
		(property "Reference" "C245"
			(at -17.768134 -9.464883 0)
			(layer "B.SilkS")
			(effects
				(font
					(size 0.7 0.7)
					(thickness 0.15)
				)
				(justify mirror)
			)
		)
		(property "Value" "C_1u_25V_0402"
			(at -1.022927 -2.155213 0)
			(layer "B.Fab")
			(effects
				(font
					(size 0.7 0.7)
					(thickness 0.15)
				)
				(justify left bottom mirror)
			)
		)
		(property "Datasheet" "https://www.murata.com/products/productdetail?partno=GRM155R61E105KE11%23"
			(at 0 0 0)
			(layer "B.Fab")
			(hide yes)
			(effects
				(font
					(size 1.27 1.27)
					(thickness 0.15)
				)
				(justify mirror)
			)
		)
		(property "Description" "SMD Multilayer Ceramic Capacitor, 1 µF, 25 V, 0402 [1005 Metric], ± 10%, X5R, GRM Series"
			(at 0 0 0)
			(layer "B.Fab")
			(hide yes)
			(effects
				(font
					(size 1.27 1.27)
					(thickness 0.15)
				)
				(justify mirror)
			)
		)
		(property "MPN" "GRM155R61E105KE11J"
			(at 0 0 180)
			(unlocked yes)
			(layer "B.Fab")
			(hide yes)
			(effects
				(font
					(size 1 1)
					(thickness 0.15)
				)
				(justify mirror)
			)
		)
		(property "Manufacturer" "Murata"
			(at 0 0 180)
			(unlocked yes)
			(layer "B.Fab")
			(hide yes)
			(effects
				(font
					(size 1 1)
					(thickness 0.15)
				)
				(justify mirror)
			)
		)
		(property "License" "Apache-2.0"
			(at 0 0 180)
			(unlocked yes)
			(layer "B.Fab")
			(hide yes)
			(effects
				(font
					(size 1 1)
					(thickness 0.15)
				)
				(justify mirror)
			)
		)
		(property "Author" "Antmicro"
			(at 0 0 180)
			(unlocked yes)
			(layer "B.Fab")
			(hide yes)
			(effects
				(font
					(size 1 1)
					(thickness 0.15)
				)
				(justify mirror)
			)
		)
		(property "Val" "1u"
			(at 0 0 180)
			(unlocked yes)
			(layer "B.Fab")
			(hide yes)
			(effects
				(font
					(size 1 1)
					(thickness 0.15)
				)
				(justify mirror)
			)
		)
		(property "Voltage" "25V"
			(at 0 0 180)
			(unlocked yes)
			(layer "B.Fab")
			(hide yes)
			(effects
				(font
					(size 1 1)
					(thickness 0.15)
				)
				(justify mirror)
			)
		)
		(property "Dielectric" "X5R"
			(at 0 0 180)
			(unlocked yes)
			(layer "B.Fab")
			(hide yes)
			(effects
				(font
					(size 1 1)
					(thickness 0.15)
				)
				(justify mirror)
			)
		)
		(sheetname "/X710-AT2 power/")
		(sheetfile "x710-at2-power.kicad_sch")
		(attr smd)
		(fp_rect
			(start -0.925 0.47)
			(end 0.925 -0.47)
			(stroke
				(width 0.05)
				(type default)
			)
			(fill no)
			(layer "B.CrtYd")
		)
		(fp_line
			(start 0.504 0.25)
			(end 0.504 -0.248)
			(stroke
				(width 0.15)
				(type solid)
			)
			(layer "B.Fab")
		)
		(fp_line
			(start 0.504 -0.248)
			(end -0.494 -0.248)
			(stroke
				(width 0.15)
				(type solid)
			)
			(layer "B.Fab")
		)
		(fp_line
			(start -0.494 0.25)
			(end 0.504 0.25)
			(stroke
				(width 0.15)
				(type solid)
			)
			(layer "B.Fab")
		)
		(fp_line
			(start -0.494 -0.248)
			(end -0.494 0.25)
			(stroke
				(width 0.15)
				(type solid)
			)
			(layer "B.Fab")
		)
		(fp_text user "License: Apache-2.0"
			(at -0.939 -5.799 0)
			(layer "B.Fab")
			(effects
				(font
					(size 0.7 0.7)
					(thickness 0.15)
				)
				(justify left bottom mirror)
			)
		)
		(fp_text user "Author: Antmicro"
			(at -0.939 -3.399 0)
			(layer "B.Fab")
			(effects
				(font
					(size 0.7 0.7)
					(thickness 0.15)
				)
				(justify left bottom mirror)
			)
		)
		(fp_text user "${REFERENCE}"
			(at -0.939 -4.599 0)
			(layer "B.Fab")
			(effects
				(font
					(size 0.7 0.7)
					(thickness 0.15)
				)
				(justify left bottom mirror)
			)
		)
		(pad "1" smd roundrect
			(at -0.48 0 180)
			(size 0.59 0.64)
			(layers "B.Cu" "B.Mask" "B.Paste")
			(roundrect_rratio 0.25)
			(net 23 "GND")
			(pintype "passive")
		)
		(pad "2" smd roundrect
			(at 0.48 0 180)
			(size 0.59 0.64)
			(layers "B.Cu" "B.Mask" "B.Paste")
			(roundrect_rratio 0.25)
			(net 1 "VCCA")
			(pintype "passive")
		)
	)
	(footprint "antmicro-footprints:C_0402_1005Metric"
		(layer "B.Cu")
		(at 127.524999 120.050001 -90)
		(descr "Capacitor SMD 0402")
		(tags "capacitor SMD 0402")
		(property "Reference" "C56"
			(at -7.700002 -21.900002 90)
			(layer "B.SilkS")
			(effects
				(font
					(size 0.7 0.7)
					(thickness 0.15)
				)
				(justify mirror)
			)
		)
		(property "Value" "C_1u_0402"
			(at -1.022927 -2.155213 90)
			(layer "B.Fab")
			(effects
				(font
					(size 0.7 0.7)
					(thickness 0.15)
				)
				(justify left bottom mirror)
			)
		)
		(property "Datasheet" "https://product.tdk.com/en/search/capacitor/ceramic/mlcc/info?part_no=C1005X6S1A105K050BC"
			(at 0 0 90)
			(layer "B.Fab")
			(hide yes)
			(effects
				(font
					(size 1.27 1.27)
					(thickness 0.15)
				)
				(justify mirror)
			)
		)
		(property "Description" "SMD Multilayer Ceramic Capacitor, 1 µF, 10 V, 0402 [1005 Metric], ± 10%, X6S, C"
			(at 0 0 90)
			(layer "B.Fab")
			(hide yes)
			(effects
				(font
					(size 1.27 1.27)
					(thickness 0.15)
				)
				(justify mirror)
			)
		)
		(property "MPN" "C1005X6S1A105K050BC"
			(at 0 0 270)
			(unlocked yes)
			(layer "B.Fab")
			(hide yes)
			(effects
				(font
					(size 1 1)
					(thickness 0.15)
				)
				(justify mirror)
			)
		)
		(property "Manufacturer" "TDK"
			(at 0 0 270)
			(unlocked yes)
			(layer "B.Fab")
			(hide yes)
			(effects
				(font
					(size 1 1)
					(thickness 0.15)
				)
				(justify mirror)
			)
		)
		(property "License" "Apache-2.0"
			(at 0 0 270)
			(unlocked yes)
			(layer "B.Fab")
			(hide yes)
			(effects
				(font
					(size 1 1)
					(thickness 0.15)
				)
				(justify mirror)
			)
		)
		(property "Val" "1u"
			(at 0 0 270)
			(unlocked yes)
			(layer "B.Fab")
			(hide yes)
			(effects
				(font
					(size 1 1)
					(thickness 0.15)
				)
				(justify mirror)
			)
		)
		(property "Voltage" ""
			(at 0 0 270)
			(unlocked yes)
			(layer "B.Fab")
			(hide yes)
			(effects
				(font
					(size 1 1)
					(thickness 0.15)
				)
				(justify mirror)
			)
		)
		(property "Dielectric" ""
			(at 0 0 270)
			(unlocked yes)
			(layer "B.Fab")
			(hide yes)
			(effects
				(font
					(size 1 1)
					(thickness 0.15)
				)
				(justify mirror)
			)
		)
		(property "Author" "Antmicro"
			(at 0 0 270)
			(unlocked yes)
			(layer "B.Fab")
			(hide yes)
			(effects
				(font
					(size 1 1)
					(thickness 0.15)
				)
				(justify mirror)
			)
		)
		(sheetname "/TB Controller - Power/")
		(sheetfile "tb-power.kicad_sch")
		(attr smd)
		(fp_rect
			(start -0.925 0.47)
			(end 0.925 -0.47)
			(stroke
				(width 0.05)
				(type default)
			)
			(fill no)
			(layer "B.CrtYd")
		)
		(fp_line
			(start -0.494 0.25)
			(end 0.504 0.25)
			(stroke
				(width 0.15)
				(type solid)
			)
			(layer "B.Fab")
		)
		(fp_line
			(start 0.504 0.25)
			(end 0.504 -0.248)
			(stroke
				(width 0.15)
				(type solid)
			)
			(layer "B.Fab")
		)
		(fp_line
			(start -0.494 -0.248)
			(end -0.494 0.25)
			(stroke
				(width 0.15)
				(type solid)
			)
			(layer "B.Fab")
		)
		(fp_line
			(start 0.504 -0.248)
			(end -0.494 -0.248)
			(stroke
				(width 0.15)
				(type solid)
			)
			(layer "B.Fab")
		)
		(fp_text user "Author: Antmicro"
			(at -0.939 -3.399 90)
			(layer "B.Fab")
			(effects
				(font
					(size 0.7 0.7)
					(thickness 0.15)
				)
				(justify left bottom mirror)
			)
		)
		(fp_text user "License: Apache-2.0"
			(at -0.939 -5.799 90)
			(layer "B.Fab")
			(effects
				(font
					(size 0.7 0.7)
					(thickness 0.15)
				)
				(justify left bottom mirror)
			)
		)
		(fp_text user "${REFERENCE}"
			(at -0.939 -4.599 90)
			(layer "B.Fab")
			(effects
				(font
					(size 0.7 0.7)
					(thickness 0.15)
				)
				(justify left bottom mirror)
			)
		)
		(pad "1" smd roundrect
			(at -0.48 0 270)
			(size 0.59 0.64)
			(layers "B.Cu" "B.Mask" "B.Paste")
			(roundrect_rratio 0.25)
			(net 23 "GND")
			(pintype "passive")
		)
		(pad "2" smd roundrect
			(at 0.48 0 270)
			(size 0.59 0.64)
			(layers "B.Cu" "B.Mask" "B.Paste")
			(roundrect_rratio 0.25)
			(net 402 "Net-(C52-Pad2)")
			(pintype "passive")
		)
	)
	(footprint "antmicro-footprints:R_0402_1005Metric"
		(layer "B.Cu")
		(at 130.9 131.1 90)
		(descr "Resistor SMD 0402")
		(tags "resistor SMD 0402")
		(property "Reference" "R54"
			(at 8.1 20.250001 270)
			(layer "B.SilkS")
			(effects
				(font
					(size 0.7 0.7)
					(thickness 0.15)
				)
				(justify mirror)
			)
		)
		(property "Value" "R_1M_0402"
			(at -1.011843 -1.772047 270)
			(layer "B.Fab")
			(effects
				(font
					(size 0.7 0.7)
					(thickness 0.15)
				)
				(justify left bottom mirror)
			)
		)
		(property "Datasheet" "https://www.bourns.com/docs/product-datasheets/cr.pdf"
			(at 0 0 270)
			(layer "B.Fab")
			(hide yes)
			(effects
				(font
					(size 1.27 1.27)
					(thickness 0.15)
				)
				(justify mirror)
			)
		)
		(property "Description" "SMD Chip Resistor, 1 Mohm, ± 1%, 62.5 mW, 0402 [1005 Metric], Thick Film, General Purpose"
			(at 0 0 270)
			(layer "B.Fab")
			(hide yes)
			(effects
				(font
					(size 1.27 1.27)
					(thickness 0.15)
				)
				(justify mirror)
			)
		)
		(property "MPN" "CR0402-FX-1004GLF"
			(at 0 0 90)
			(unlocked yes)
			(layer "B.Fab")
			(hide yes)
			(effects
				(font
					(size 1 1)
					(thickness 0.15)
				)
				(justify mirror)
			)
		)
		(property "Manufacturer" "Bourns"
			(at 0 0 90)
			(unlocked yes)
			(layer "B.Fab")
			(hide yes)
			(effects
				(font
					(size 1 1)
					(thickness 0.15)
				)
				(justify mirror)
			)
		)
		(property "License" "Apache-2.0"
			(at 0 0 90)
			(unlocked yes)
			(layer "B.Fab")
			(hide yes)
			(effects
				(font
					(size 1 1)
					(thickness 0.15)
				)
				(justify mirror)
			)
		)
		(property "Val" "1M"
			(at 0 0 90)
			(unlocked yes)
			(layer "B.Fab")
			(hide yes)
			(effects
				(font
					(size 1 1)
					(thickness 0.15)
				)
				(justify mirror)
			)
		)
		(property "Tolerance" "1%"
			(at 0 0 90)
			(unlocked yes)
			(layer "B.Fab")
			(hide yes)
			(effects
				(font
					(size 1 1)
					(thickness 0.15)
				)
				(justify mirror)
			)
		)
		(property "Author" "Antmicro"
			(at 0 0 90)
			(unlocked yes)
			(layer "B.Fab")
			(hide yes)
			(effects
				(font
					(size 1 1)
					(thickness 0.15)
				)
				(justify mirror)
			)
		)
		(sheetname "/TB Controller/")
		(sheetfile "tb.kicad_sch")
		(attr smd)
		(fp_rect
			(start -0.925 0.47)
			(end 0.925 -0.47)
			(stroke
				(width 0.05)
				(type default)
			)
			(fill no)
			(layer "B.CrtYd")
		)
		(fp_rect
			(start -0.5 0.25)
			(end 0.5 -0.25)
			(stroke
				(width 0.15)
				(type solid)
			)
			(fill no)
			(layer "B.Fab")
		)
		(fp_text user "License: Apache-2.0"
			(at -0.95 -5.169 270)
			(layer "B.Fab")
			(effects
				(font
					(size 0.7 0.7)
					(thickness 0.15)
				)
				(justify left bottom mirror)
			)
		)
		(fp_text user "Author: Antmicro"
			(at -0.95 -4.169 270)
			(layer "B.Fab")
			(effects
				(font
					(size 0.7 0.7)
					(thickness 0.15)
				)
				(justify left bottom mirror)
			)
		)
		(fp_text user "${REFERENCE}"
			(at -0.95 -3.168 270)
			(layer "B.Fab")
			(effects
				(font
					(size 0.7 0.7)
					(thickness 0.15)
				)
				(justify left bottom mirror)
			)
		)
		(pad "1" smd roundrect
			(at -0.48 0 90)
			(size 0.59 0.64)
			(layers "B.Cu" "B.Mask" "B.Paste")
			(roundrect_rratio 0.25)
			(net 23 "GND")
			(pintype "passive")
		)
		(pad "2" smd roundrect
			(at 0.48 0 90)
			(size 0.59 0.64)
			(layers "B.Cu" "B.Mask" "B.Paste")
			(roundrect_rratio 0.25)
			(net 376 "/PD and TB DC-DC/LSX_1.LSX_P2R")
			(pintype "passive")
		)
	)
	(footprint "antmicro-footprints:R_0402_1005Metric"
		(layer "B.Cu")
		(at 152.681866 87.635117 -90)
		(descr "Resistor SMD 0402")
		(tags "resistor SMD 0402")
		(property "Reference" "R174"
			(at 8.564883 -17.718134 90)
			(layer "B.SilkS")
			(effects
				(font
					(size 0.7 0.7)
					(thickness 0.15)
				)
				(justify mirror)
			)
		)
		(property "Value" "R_1k_0402"
			(at -1.011843 -1.772047 90)
			(layer "B.Fab")
			(effects
				(font
					(size 0.7 0.7)
					(thickness 0.15)
				)
				(justify left bottom mirror)
			)
		)
		(property "Datasheet" "https://www.bourns.com/docs/product-datasheets/cr.pdf"
			(at 0 0 90)
			(layer "B.Fab")
			(hide yes)
			(effects
				(font
					(size 1.27 1.27)
					(thickness 0.15)
				)
				(justify mirror)
			)
		)
		(property "Description" "SMD Chip Resistor, 1 kohm, ± 1%, 63 mW, 0402 [1005 Metric], Thick Film, General Purpose"
			(at 0 0 90)
			(layer "B.Fab")
			(hide yes)
			(effects
				(font
					(size 1.27 1.27)
					(thickness 0.15)
				)
				(justify mirror)
			)
		)
		(property "MPN" "CR0402-FX-1001GLF"
			(at 0 0 270)
			(unlocked yes)
			(layer "B.Fab")
			(hide yes)
			(effects
				(font
					(size 1 1)
					(thickness 0.15)
				)
				(justify mirror)
			)
		)
		(property "Manufacturer" "Bourns"
			(at 0 0 270)
			(unlocked yes)
			(layer "B.Fab")
			(hide yes)
			(effects
				(font
					(size 1 1)
					(thickness 0.15)
				)
				(justify mirror)
			)
		)
		(property "License" "Apache-2.0"
			(at 0 0 270)
			(unlocked yes)
			(layer "B.Fab")
			(hide yes)
			(effects
				(font
					(size 1 1)
					(thickness 0.15)
				)
				(justify mirror)
			)
		)
		(property "Author" "Antmicro"
			(at 0 0 270)
			(unlocked yes)
			(layer "B.Fab")
			(hide yes)
			(effects
				(font
					(size 1 1)
					(thickness 0.15)
				)
				(justify mirror)
			)
		)
		(property "Val" "1k"
			(at 0 0 270)
			(unlocked yes)
			(layer "B.Fab")
			(hide yes)
			(effects
				(font
					(size 1 1)
					(thickness 0.15)
				)
				(justify mirror)
			)
		)
		(property "Tolerance" "1%"
			(at 0 0 270)
			(unlocked yes)
			(layer "B.Fab")
			(hide yes)
			(effects
				(font
					(size 1 1)
					(thickness 0.15)
				)
				(justify mirror)
			)
		)
		(sheetname "/X710-AT2 Misc/")
		(sheetfile "x710-at2-mics.kicad_sch")
		(attr smd)
		(fp_rect
			(start -0.925 0.47)
			(end 0.925 -0.47)
			(stroke
				(width 0.05)
				(type default)
			)
			(fill no)
			(layer "B.CrtYd")
		)
		(fp_rect
			(start -0.5 0.25)
			(end 0.5 -0.25)
			(stroke
				(width 0.15)
				(type solid)
			)
			(fill no)
			(layer "B.Fab")
		)
		(fp_text user "License: Apache-2.0"
			(at -0.95 -5.169 90)
			(layer "B.Fab")
			(effects
				(font
					(size 0.7 0.7)
					(thickness 0.15)
				)
				(justify left bottom mirror)
			)
		)
		(fp_text user "Author: Antmicro"
			(at -0.95 -4.169 90)
			(layer "B.Fab")
			(effects
				(font
					(size 0.7 0.7)
					(thickness 0.15)
				)
				(justify left bottom mirror)
			)
		)
		(fp_text user "${REFERENCE}"
			(at -0.95 -3.168 90)
			(layer "B.Fab")
			(effects
				(font
					(size 0.7 0.7)
					(thickness 0.15)
				)
				(justify left bottom mirror)
			)
		)
		(pad "1" smd roundrect
			(at -0.48 0 270)
			(size 0.59 0.64)
			(layers "B.Cu" "B.Mask" "B.Paste")
			(roundrect_rratio 0.25)
			(net 84 "/X710-AT2 Misc/RSVDL33")
			(pintype "passive")
		)
		(pad "2" smd roundrect
			(at 0.48 0 270)
			(size 0.59 0.64)
			(layers "B.Cu" "B.Mask" "B.Paste")
			(roundrect_rratio 0.25)
			(net 18 "+1V88")
			(pintype "passive")
		)
	)
	(footprint "antmicro-footprints:C_0402_1005Metric"
		(layer "B.Cu")
		(at 152.381866 89.535117 -90)
		(descr "Capacitor SMD 0402")
		(tags "capacitor SMD 0402")
		(property "Reference" "C191"
			(at 10.264883 -18.868134 90)
			(layer "B.SilkS")
			(effects
				(font
					(size 0.7 0.7)
					(thickness 0.15)
				)
				(justify mirror)
			)
		)
		(property "Value" "C_1u_25V_0402"
			(at -1.022927 -2.155213 90)
			(layer "B.Fab")
			(effects
				(font
					(size 0.7 0.7)
					(thickness 0.15)
				)
				(justify left bottom mirror)
			)
		)
		(property "Datasheet" "https://www.murata.com/products/productdetail?partno=GRM155R61E105KE11%23"
			(at 0 0 90)
			(layer "B.Fab")
			(hide yes)
			(effects
				(font
					(size 1.27 1.27)
					(thickness 0.15)
				)
				(justify mirror)
			)
		)
		(property "Description" "SMD Multilayer Ceramic Capacitor, 1 µF, 25 V, 0402 [1005 Metric], ± 10%, X5R, GRM Series"
			(at 0 0 90)
			(layer "B.Fab")
			(hide yes)
			(effects
				(font
					(size 1.27 1.27)
					(thickness 0.15)
				)
				(justify mirror)
			)
		)
		(property "MPN" "GRM155R61E105KE11J"
			(at 0 0 270)
			(unlocked yes)
			(layer "B.Fab")
			(hide yes)
			(effects
				(font
					(size 1 1)
					(thickness 0.15)
				)
				(justify mirror)
			)
		)
		(property "Manufacturer" "Murata"
			(at 0 0 270)
			(unlocked yes)
			(layer "B.Fab")
			(hide yes)
			(effects
				(font
					(size 1 1)
					(thickness 0.15)
				)
				(justify mirror)
			)
		)
		(property "License" "Apache-2.0"
			(at 0 0 270)
			(unlocked yes)
			(layer "B.Fab")
			(hide yes)
			(effects
				(font
					(size 1 1)
					(thickness 0.15)
				)
				(justify mirror)
			)
		)
		(property "Author" "Antmicro"
			(at 0 0 270)
			(unlocked yes)
			(layer "B.Fab")
			(hide yes)
			(effects
				(font
					(size 1 1)
					(thickness 0.15)
				)
				(justify mirror)
			)
		)
		(property "Val" "1u"
			(at 0 0 270)
			(unlocked yes)
			(layer "B.Fab")
			(hide yes)
			(effects
				(font
					(size 1 1)
					(thickness 0.15)
				)
				(justify mirror)
			)
		)
		(property "Voltage" "25V"
			(at 0 0 270)
			(unlocked yes)
			(layer "B.Fab")
			(hide yes)
			(effects
				(font
					(size 1 1)
					(thickness 0.15)
				)
				(justify mirror)
			)
		)
		(property "Dielectric" "X5R"
			(at 0 0 270)
			(unlocked yes)
			(layer "B.Fab")
			(hide yes)
			(effects
				(font
					(size 1 1)
					(thickness 0.15)
				)
				(justify mirror)
			)
		)
		(sheetname "/X710-AT2 power/")
		(sheetfile "x710-at2-power.kicad_sch")
		(attr smd)
		(fp_rect
			(start -0.925 0.47)
			(end 0.925 -0.47)
			(stroke
				(width 0.05)
				(type default)
			)
			(fill no)
			(layer "B.CrtYd")
		)
		(fp_line
			(start -0.494 0.25)
			(end 0.504 0.25)
			(stroke
				(width 0.15)
				(type solid)
			)
			(layer "B.Fab")
		)
		(fp_line
			(start 0.504 0.25)
			(end 0.504 -0.248)
			(stroke
				(width 0.15)
				(type solid)
			)
			(layer "B.Fab")
		)
		(fp_line
			(start -0.494 -0.248)
			(end -0.494 0.25)
			(stroke
				(width 0.15)
				(type solid)
			)
			(layer "B.Fab")
		)
		(fp_line
			(start 0.504 -0.248)
			(end -0.494 -0.248)
			(stroke
				(width 0.15)
				(type solid)
			)
			(layer "B.Fab")
		)
		(fp_text user "License: Apache-2.0"
			(at -0.939 -5.799 90)
			(layer "B.Fab")
			(effects
				(font
					(size 0.7 0.7)
					(thickness 0.15)
				)
				(justify left bottom mirror)
			)
		)
		(fp_text user "${REFERENCE}"
			(at -0.939 -4.599 90)
			(layer "B.Fab")
			(effects
				(font
					(size 0.7 0.7)
					(thickness 0.15)
				)
				(justify left bottom mirror)
			)
		)
		(fp_text user "Author: Antmicro"
			(at -0.939 -3.399 90)
			(layer "B.Fab")
			(effects
				(font
					(size 0.7 0.7)
					(thickness 0.15)
				)
				(justify left bottom mirror)
			)
		)
		(pad "1" smd roundrect
			(at -0.48 0 270)
			(size 0.59 0.64)
			(layers "B.Cu" "B.Mask" "B.Paste")
			(roundrect_rratio 0.25)
			(net 23 "GND")
			(pintype "passive")
		)
		(pad "2" smd roundrect
			(at 0.48 0 270)
			(size 0.59 0.64)
			(layers "B.Cu" "B.Mask" "B.Paste")
			(roundrect_rratio 0.25)
			(net 18 "+1V88")
			(pintype "passive")
		)
	)
	(footprint "antmicro-footprints:C_0603_1608Metric"
		(layer "B.Cu")
		(at 150.231867 89.985117 -90)
		(descr "Capacitor SMD 0603")
		(tags "capacitor 0603")
		(property "Reference" "C167"
			(at 10.414883 -18.868134 90)
			(layer "B.SilkS")
			(effects
				(font
					(size 0.7 0.7)
					(thickness 0.15)
				)
				(justify mirror)
			)
		)
		(property "Value" "C_10u_10V_X7R_0603"
			(at -1.42757 -1.770288 90)
			(layer "B.Fab")
			(effects
				(font
					(size 0.7 0.7)
					(thickness 0.15)
				)
				(justify left bottom mirror)
			)
		)
		(property "Datasheet" "https://www.murata.com/products/productdetail?partno=GRM188Z71A106KA73%23"
			(at 0 0 90)
			(layer "B.Fab")
			(hide yes)
			(effects
				(font
					(size 1.27 1.27)
					(thickness 0.15)
				)
				(justify mirror)
			)
		)
		(property "Description" "SMD Multilayer Ceramic Capacitor,  10µF, 10V, 0603, ±10%, X7R"
			(at 0 0 90)
			(layer "B.Fab")
			(hide yes)
			(effects
				(font
					(size 1.27 1.27)
					(thickness 0.15)
				)
				(justify mirror)
			)
		)
		(property "MPN" "GRM188Z71A106KA73D"
			(at 0 0 270)
			(unlocked yes)
			(layer "B.Fab")
			(hide yes)
			(effects
				(font
					(size 1 1)
					(thickness 0.15)
				)
				(justify mirror)
			)
		)
		(property "Val" "10u"
			(at 0 0 270)
			(unlocked yes)
			(layer "B.Fab")
			(hide yes)
			(effects
				(font
					(size 1 1)
					(thickness 0.15)
				)
				(justify mirror)
			)
		)
		(property "Voltage" "10V"
			(at 0 0 270)
			(unlocked yes)
			(layer "B.Fab")
			(hide yes)
			(effects
				(font
					(size 1 1)
					(thickness 0.15)
				)
				(justify mirror)
			)
		)
		(property "Dielectric" "X7R"
			(at 0 0 270)
			(unlocked yes)
			(layer "B.Fab")
			(hide yes)
			(effects
				(font
					(size 1 1)
					(thickness 0.15)
				)
				(justify mirror)
			)
		)
		(property "Manufacturer" "Murata"
			(at 0 0 270)
			(unlocked yes)
			(layer "B.Fab")
			(hide yes)
			(effects
				(font
					(size 1 1)
					(thickness 0.15)
				)
				(justify mirror)
			)
		)
		(property "License" "Apache-2.0"
			(at 0 0 270)
			(unlocked yes)
			(layer "B.Fab")
			(hide yes)
			(effects
				(font
					(size 1 1)
					(thickness 0.15)
				)
				(justify mirror)
			)
		)
		(property "Author" "Antmicro"
			(at 0 0 270)
			(unlocked yes)
			(layer "B.Fab")
			(hide yes)
			(effects
				(font
					(size 1 1)
					(thickness 0.15)
				)
				(justify mirror)
			)
		)
		(sheetname "/X710-AT2 power/")
		(sheetfile "x710-at2-power.kicad_sch")
		(attr smd)
		(fp_line
			(start -0.15 0.4)
			(end 0.15 0.4)
			(stroke
				(width 0.15)
				(type solid)
			)
			(layer "B.SilkS")
		)
		(fp_line
			(start -0.15 -0.4)
			(end 0.15 -0.4)
			(stroke
				(width 0.15)
				(type solid)
			)
			(layer "B.SilkS")
		)
		(fp_rect
			(start -1.25 0.65)
			(end 1.25 -0.65)
			(stroke
				(width 0.05)
				(type solid)
			)
			(fill no)
			(layer "B.CrtYd")
		)
		(fp_rect
			(start -0.8 0.4)
			(end 0.8 -0.4)
			(stroke
				(width 0.15)
				(type solid)
			)
			(fill no)
			(layer "B.Fab")
		)
		(fp_text user "License: Apache-2.0"
			(at -1.682 -5.895 90)
			(layer "B.Fab")
			(effects
				(font
					(size 0.7 0.7)
					(thickness 0.15)
				)
				(justify left bottom mirror)
			)
		)
		(fp_text user "${REFERENCE}"
			(at -1.682 -3.895 90)
			(layer "B.Fab")
			(effects
				(font
					(size 0.7 0.7)
					(thickness 0.15)
				)
				(justify left bottom mirror)
			)
		)
		(fp_text user "Author: Antmicro"
			(at -1.682 -4.894 90)
			(layer "B.Fab")
			(effects
				(font
					(size 0.7 0.7)
					(thickness 0.15)
				)
				(justify left bottom mirror)
			)
		)
		(pad "1" smd roundrect
			(at -0.7 0 270)
			(size 0.8 1)
			(layers "B.Cu" "B.Mask" "B.Paste")
			(roundrect_rratio 0.2)
			(net 23 "GND")
			(pintype "passive")
		)
		(pad "2" smd roundrect
			(at 0.7 0 270)
			(size 0.8 1)
			(layers "B.Cu" "B.Mask" "B.Paste")
			(roundrect_rratio 0.2)
			(net 18 "+1V88")
			(pintype "passive")
		)
	)
	(footprint "antmicro-footprints:TP_SMD_0.75mm"
		(layer "B.Cu")
		(at 159.731866 64.435117 90)
		(property "Reference" "TP29"
			(at -0.164883 3.268134 180)
			(layer "B.SilkS")
			(effects
				(font
					(size 0.7 0.7)
					(thickness 0.15)
				)
				(justify left bottom mirror)
			)
		)
		(property "Value" "TP_0.75mm_SMD"
			(at 0 -1.2 270)
			(layer "B.Fab")
			(effects
				(font
					(size 0.7 0.7)
					(thickness 0.15)
				)
				(justify left bottom mirror)
			)
		)
		(property "Description" "SMT test point"
			(at 0 0 270)
			(layer "B.Fab")
			(hide yes)
			(effects
				(font
					(size 1.27 1.27)
					(thickness 0.15)
				)
				(justify mirror)
			)
		)
		(property "MPN" ""
			(at 0 0 90)
			(unlocked yes)
			(layer "B.Fab")
			(hide yes)
			(effects
				(font
					(size 1 1)
					(thickness 0.15)
				)
				(justify mirror)
			)
		)
		(property "Manufacturer" ""
			(at 0 0 90)
			(unlocked yes)
			(layer "B.Fab")
			(hide yes)
			(effects
				(font
					(size 1 1)
					(thickness 0.15)
				)
				(justify mirror)
			)
		)
		(property "Author" "Antmicro"
			(at 0 0 90)
			(unlocked yes)
			(layer "B.Fab")
			(hide yes)
			(effects
				(font
					(size 1 1)
					(thickness 0.15)
				)
				(justify mirror)
			)
		)
		(property "License" "Apache-2.0"
			(at 0 0 90)
			(unlocked yes)
			(layer "B.Fab")
			(hide yes)
			(effects
				(font
					(size 1 1)
					(thickness 0.15)
				)
				(justify mirror)
			)
		)
		(sheetname "/X710-AT2 Misc/")
		(sheetfile "x710-at2-mics.kicad_sch")
		(attr exclude_from_pos_files exclude_from_bom)
		(fp_circle
			(center 0 0)
			(end 0.475 0)
			(stroke
				(width 0.05)
				(type default)
			)
			(fill no)
			(layer "B.CrtYd")
		)
		(fp_text user "Author: Antmicro"
			(at -0.4 -3.901 270)
			(layer "B.Fab")
			(effects
				(font
					(size 0.7 0.7)
					(thickness 0.15)
				)
				(justify left bottom mirror)
			)
		)
		(fp_text user "License: Apache-2.0"
			(at -0.4 -5.101 270)
			(layer "B.Fab")
			(effects
				(font
					(size 0.7 0.7)
					(thickness 0.15)
				)
				(justify left bottom mirror)
			)
		)
		(fp_text user "${REFERENCE}"
			(at -0.4 -2.7 270)
			(layer "B.Fab")
			(effects
				(font
					(size 0.7 0.7)
					(thickness 0.15)
				)
				(justify left bottom mirror)
			)
		)
		(pad "1" smd circle
			(at 0 0 90)
			(size 0.75 0.75)
			(layers "B.Cu" "B.Mask")
			(net 137 "/X710-AT2 Misc/NCSI.RXD_1")
			(pinfunction "1")
			(pintype "passive")
		)
	)
	(footprint "antmicro-footprints:R_0402_1005Metric"
		(layer "B.Cu")
		(at 142.5 118.174998 180)
		(descr "Resistor SMD 0402")
		(tags "resistor SMD 0402")
		(property "Reference" "R36"
			(at -19.75 7.450001 0)
			(layer "B.SilkS")
			(effects
				(font
					(size 0.7 0.7)
					(thickness 0.15)
				)
				(justify mirror)
			)
		)
		(property "Value" "R_2k2_0402"
			(at -1.011843 -1.772047 0)
			(layer "B.Fab")
			(effects
				(font
					(size 0.7 0.7)
					(thickness 0.15)
				)
				(justify left bottom mirror)
			)
		)
		(property "Datasheet" "https://www.bourns.com/docs/product-datasheets/cr.pdf"
			(at 0 0 0)
			(layer "B.Fab")
			(hide yes)
			(effects
				(font
					(size 1.27 1.27)
					(thickness 0.15)
				)
				(justify mirror)
			)
		)
		(property "Description" "SMD Chip Resistor, 2.2 kohm, ± 1%, 62.5 mW, 0402 [1005 Metric], Thick Film, General Purpose"
			(at 0 0 0)
			(layer "B.Fab")
			(hide yes)
			(effects
				(font
					(size 1.27 1.27)
					(thickness 0.15)
				)
				(justify mirror)
			)
		)
		(property "MPN" "CR0402-FX-2201GLF"
			(at 0 0 180)
			(unlocked yes)
			(layer "B.Fab")
			(hide yes)
			(effects
				(font
					(size 1 1)
					(thickness 0.15)
				)
				(justify mirror)
			)
		)
		(property "Manufacturer" "Bourns"
			(at 0 0 180)
			(unlocked yes)
			(layer "B.Fab")
			(hide yes)
			(effects
				(font
					(size 1 1)
					(thickness 0.15)
				)
				(justify mirror)
			)
		)
		(property "License" "Apache-2.0"
			(at 0 0 180)
			(unlocked yes)
			(layer "B.Fab")
			(hide yes)
			(effects
				(font
					(size 1 1)
					(thickness 0.15)
				)
				(justify mirror)
			)
		)
		(property "Val" "2k2"
			(at 0 0 180)
			(unlocked yes)
			(layer "B.Fab")
			(hide yes)
			(effects
				(font
					(size 1 1)
					(thickness 0.15)
				)
				(justify mirror)
			)
		)
		(property "Tolerance" "1%"
			(at 0 0 180)
			(unlocked yes)
			(layer "B.Fab")
			(hide yes)
			(effects
				(font
					(size 1 1)
					(thickness 0.15)
				)
				(justify mirror)
			)
		)
		(property "Author" "Antmicro"
			(at 0 0 180)
			(unlocked yes)
			(layer "B.Fab")
			(hide yes)
			(effects
				(font
					(size 1 1)
					(thickness 0.15)
				)
				(justify mirror)
			)
		)
		(sheetname "/TB Controller/")
		(sheetfile "tb.kicad_sch")
		(attr smd)
		(fp_rect
			(start -0.925 0.47)
			(end 0.925 -0.47)
			(stroke
				(width 0.05)
				(type default)
			)
			(fill no)
			(layer "B.CrtYd")
		)
		(fp_rect
			(start -0.5 0.25)
			(end 0.5 -0.25)
			(stroke
				(width 0.15)
				(type solid)
			)
			(fill no)
			(layer "B.Fab")
		)
		(fp_text user "${REFERENCE}"
			(at -0.95 -3.168 0)
			(layer "B.Fab")
			(effects
				(font
					(size 0.7 0.7)
					(thickness 0.15)
				)
				(justify left bottom mirror)
			)
		)
		(fp_text user "License: Apache-2.0"
			(at -0.95 -5.169 0)
			(layer "B.Fab")
			(effects
				(font
					(size 0.7 0.7)
					(thickness 0.15)
				)
				(justify left bottom mirror)
			)
		)
		(fp_text user "Author: Antmicro"
			(at -0.95 -4.169 0)
			(layer "B.Fab")
			(effects
				(font
					(size 0.7 0.7)
					(thickness 0.15)
				)
				(justify left bottom mirror)
			)
		)
		(pad "1" smd roundrect
			(at -0.48 0 180)
			(size 0.59 0.64)
			(layers "B.Cu" "B.Mask" "B.Paste")
			(roundrect_rratio 0.25)
			(net 23 "GND")
			(pintype "passive")
		)
		(pad "2" smd roundrect
			(at 0.48 0 180)
			(size 0.59 0.64)
			(layers "B.Cu" "B.Mask" "B.Paste")
			(roundrect_rratio 0.25)
			(net 219 "Net-(U4C-DPSNK0_DDC_DATA)")
			(pintype "passive")
		)
	)
	(footprint "antmicro-footprints:R_0402_1005Metric"
		(layer "B.Cu")
		(at 154.231866 91.535117 -90)
		(descr "Resistor SMD 0402")
		(tags "resistor SMD 0402")
		(property "Reference" "R181"
			(at 10.864883 -18.868134 90)
			(layer "B.SilkS")
			(effects
				(font
					(size 0.7 0.7)
					(thickness 0.15)
				)
				(justify mirror)
			)
		)
		(property "Value" "R_1k_0402"
			(at -1.011843 -1.772047 90)
			(layer "B.Fab")
			(effects
				(font
					(size 0.7 0.7)
					(thickness 0.15)
				)
				(justify left bottom mirror)
			)
		)
		(property "Datasheet" "https://www.bourns.com/docs/product-datasheets/cr.pdf"
			(at 0 0 90)
			(layer "B.Fab")
			(hide yes)
			(effects
				(font
					(size 1.27 1.27)
					(thickness 0.15)
				)
				(justify mirror)
			)
		)
		(property "Description" "SMD Chip Resistor, 1 kohm, ± 1%, 63 mW, 0402 [1005 Metric], Thick Film, General Purpose"
			(at 0 0 90)
			(layer "B.Fab")
			(hide yes)
			(effects
				(font
					(size 1.27 1.27)
					(thickness 0.15)
				)
				(justify mirror)
			)
		)
		(property "MPN" "CR0402-FX-1001GLF"
			(at 0 0 270)
			(unlocked yes)
			(layer "B.Fab")
			(hide yes)
			(effects
				(font
					(size 1 1)
					(thickness 0.15)
				)
				(justify mirror)
			)
		)
		(property "Manufacturer" "Bourns"
			(at 0 0 270)
			(unlocked yes)
			(layer "B.Fab")
			(hide yes)
			(effects
				(font
					(size 1 1)
					(thickness 0.15)
				)
				(justify mirror)
			)
		)
		(property "License" "Apache-2.0"
			(at 0 0 270)
			(unlocked yes)
			(layer "B.Fab")
			(hide yes)
			(effects
				(font
					(size 1 1)
					(thickness 0.15)
				)
				(justify mirror)
			)
		)
		(property "Author" "Antmicro"
			(at 0 0 270)
			(unlocked yes)
			(layer "B.Fab")
			(hide yes)
			(effects
				(font
					(size 1 1)
					(thickness 0.15)
				)
				(justify mirror)
			)
		)
		(property "Val" "1k"
			(at 0 0 270)
			(unlocked yes)
			(layer "B.Fab")
			(hide yes)
			(effects
				(font
					(size 1 1)
					(thickness 0.15)
				)
				(justify mirror)
			)
		)
		(property "Tolerance" "1%"
			(at 0 0 270)
			(unlocked yes)
			(layer "B.Fab")
			(hide yes)
			(effects
				(font
					(size 1 1)
					(thickness 0.15)
				)
				(justify mirror)
			)
		)
		(sheetname "/X710-AT2 Misc/")
		(sheetfile "x710-at2-mics.kicad_sch")
		(attr smd)
		(fp_rect
			(start -0.925 0.47)
			(end 0.925 -0.47)
			(stroke
				(width 0.05)
				(type default)
			)
			(fill no)
			(layer "B.CrtYd")
		)
		(fp_rect
			(start -0.5 0.25)
			(end 0.5 -0.25)
			(stroke
				(width 0.15)
				(type solid)
			)
			(fill no)
			(layer "B.Fab")
		)
		(fp_text user "Author: Antmicro"
			(at -0.95 -4.169 90)
			(layer "B.Fab")
			(effects
				(font
					(size 0.7 0.7)
					(thickness 0.15)
				)
				(justify left bottom mirror)
			)
		)
		(fp_text user "License: Apache-2.0"
			(at -0.95 -5.169 90)
			(layer "B.Fab")
			(effects
				(font
					(size 0.7 0.7)
					(thickness 0.15)
				)
				(justify left bottom mirror)
			)
		)
		(fp_text user "${REFERENCE}"
			(at -0.95 -3.168 90)
			(layer "B.Fab")
			(effects
				(font
					(size 0.7 0.7)
					(thickness 0.15)
				)
				(justify left bottom mirror)
			)
		)
		(pad "1" smd roundrect
			(at -0.48 0 270)
			(size 0.59 0.64)
			(layers "B.Cu" "B.Mask" "B.Paste")
			(roundrect_rratio 0.25)
			(net 85 "/X710-AT2 Misc/RSVDK40_1P88V")
			(pintype "passive")
		)
		(pad "2" smd roundrect
			(at 0.48 0 270)
			(size 0.59 0.64)
			(layers "B.Cu" "B.Mask" "B.Paste")
			(roundrect_rratio 0.25)
			(net 18 "+1V88")
			(pintype "passive")
		)
	)
	(footprint "antmicro-footprints:C_0402_1005Metric"
		(layer "B.Cu")
		(at 147.531866 71.535117)
		(descr "Capacitor SMD 0402")
		(tags "capacitor SMD 0402")
		(property "Reference" "C214"
			(at 19.068134 9.464883 180)
			(layer "B.SilkS")
			(effects
				(font
					(size 0.7 0.7)
					(thickness 0.15)
				)
				(justify mirror)
			)
		)
		(property "Value" "C_100n_0402"
			(at -1.022927 -2.155213 180)
			(layer "B.Fab")
			(effects
				(font
					(size 0.7 0.7)
					(thickness 0.15)
				)
				(justify left bottom mirror)
			)
		)
		(property "Datasheet" "https://www.murata.com/products/productdetail?partno=GRM155R61H104KE14%23"
			(at 0 0 180)
			(layer "B.Fab")
			(hide yes)
			(effects
				(font
					(size 1.27 1.27)
					(thickness 0.15)
				)
				(justify mirror)
			)
		)
		(property "Description" "SMD Multilayer Ceramic Capacitor, 0.1 µF, 50 V, 0402 [1005 Metric], ± 10%, X5R, GRM Series"
			(at 0 0 180)
			(layer "B.Fab")
			(hide yes)
			(effects
				(font
					(size 1.27 1.27)
					(thickness 0.15)
				)
				(justify mirror)
			)
		)
		(property "MPN" "GRM155R61H104KE14D"
			(at 0 0 0)
			(unlocked yes)
			(layer "B.Fab")
			(hide yes)
			(effects
				(font
					(size 1 1)
					(thickness 0.15)
				)
				(justify mirror)
			)
		)
		(property "Val" "100n"
			(at 0 0 0)
			(unlocked yes)
			(layer "B.Fab")
			(hide yes)
			(effects
				(font
					(size 1 1)
					(thickness 0.15)
				)
				(justify mirror)
			)
		)
		(property "Voltage" "50V"
			(at 0 0 0)
			(unlocked yes)
			(layer "B.Fab")
			(hide yes)
			(effects
				(font
					(size 1 1)
					(thickness 0.15)
				)
				(justify mirror)
			)
		)
		(property "Dielectric" "X5R"
			(at 0 0 0)
			(unlocked yes)
			(layer "B.Fab")
			(hide yes)
			(effects
				(font
					(size 1 1)
					(thickness 0.15)
				)
				(justify mirror)
			)
		)
		(property "Manufacturer" "Murata"
			(at 0 0 0)
			(unlocked yes)
			(layer "B.Fab")
			(hide yes)
			(effects
				(font
					(size 1 1)
					(thickness 0.15)
				)
				(justify mirror)
			)
		)
		(property "License" "Apache-2.0"
			(at 0 0 0)
			(unlocked yes)
			(layer "B.Fab")
			(hide yes)
			(effects
				(font
					(size 1 1)
					(thickness 0.15)
				)
				(justify mirror)
			)
		)
		(property "Author" "Antmicro"
			(at 0 0 0)
			(unlocked yes)
			(layer "B.Fab")
			(hide yes)
			(effects
				(font
					(size 1 1)
					(thickness 0.15)
				)
				(justify mirror)
			)
		)
		(sheetname "/X710-AT2 power/")
		(sheetfile "x710-at2-power.kicad_sch")
		(attr smd)
		(fp_rect
			(start -0.925 0.47)
			(end 0.925 -0.47)
			(stroke
				(width 0.05)
				(type default)
			)
			(fill no)
			(layer "B.CrtYd")
		)
		(fp_line
			(start -0.494 -0.248)
			(end -0.494 0.25)
			(stroke
				(width 0.15)
				(type solid)
			)
			(layer "B.Fab")
		)
		(fp_line
			(start -0.494 0.25)
			(end 0.504 0.25)
			(stroke
				(width 0.15)
				(type solid)
			)
			(layer "B.Fab")
		)
		(fp_line
			(start 0.504 -0.248)
			(end -0.494 -0.248)
			(stroke
				(width 0.15)
				(type solid)
			)
			(layer "B.Fab")
		)
		(fp_line
			(start 0.504 0.25)
			(end 0.504 -0.248)
			(stroke
				(width 0.15)
				(type solid)
			)
			(layer "B.Fab")
		)
		(fp_text user "License: Apache-2.0"
			(at -0.939 -5.799 180)
			(layer "B.Fab")
			(effects
				(font
					(size 0.7 0.7)
					(thickness 0.15)
				)
				(justify left bottom mirror)
			)
		)
		(fp_text user "Author: Antmicro"
			(at -0.939 -3.399 180)
			(layer "B.Fab")
			(effects
				(font
					(size 0.7 0.7)
					(thickness 0.15)
				)
				(justify left bottom mirror)
			)
		)
		(fp_text user "${REFERENCE}"
			(at -0.939 -4.599 180)
			(layer "B.Fab")
			(effects
				(font
					(size 0.7 0.7)
					(thickness 0.15)
				)
				(justify left bottom mirror)
			)
		)
		(pad "1" smd roundrect
			(at -0.48 0)
			(size 0.59 0.64)
			(layers "B.Cu" "B.Mask" "B.Paste")
			(roundrect_rratio 0.25)
			(net 23 "GND")
			(pintype "passive")
		)
		(pad "2" smd roundrect
			(at 0.48 0)
			(size 0.59 0.64)
			(layers "B.Cu" "B.Mask" "B.Paste")
			(roundrect_rratio 0.25)
			(net 7 "+3V3")
			(pintype "passive")
		)
	)
	(footprint "antmicro-footprints:C_0402_1005Metric"
		(layer "B.Cu")
		(at 145 136)
		(descr "Capacitor SMD 0402")
		(tags "capacitor SMD 0402")
		(property "Reference" "C296"
			(at 1 -0.5 180)
			(layer "B.SilkS")
			(effects
				(font
					(size 0.7 0.7)
					(thickness 0.15)
				)
				(justify left bottom mirror)
			)
		)
		(property "Value" "C_1u_25V_0402"
			(at -1.022927 -2.155213 180)
			(layer "B.Fab")
			(effects
				(font
					(size 0.7 0.7)
					(thickness 0.15)
				)
				(justify left bottom mirror)
			)
		)
		(property "Datasheet" "https://www.murata.com/products/productdetail?partno=GRM155R61E105KE11%23"
			(at 0 0 180)
			(layer "B.Fab")
			(hide yes)
			(effects
				(font
					(size 1.27 1.27)
					(thickness 0.15)
				)
				(justify mirror)
			)
		)
		(property "Description" "SMD Multilayer Ceramic Capacitor, 1 µF, 25 V, 0402 [1005 Metric], ± 10%, X5R, GRM Series"
			(at 0 0 180)
			(layer "B.Fab")
			(hide yes)
			(effects
				(font
					(size 1.27 1.27)
					(thickness 0.15)
				)
				(justify mirror)
			)
		)
		(property "MPN" "GRM155R61E105KE11J"
			(at 0 0 0)
			(unlocked yes)
			(layer "B.Fab")
			(hide yes)
			(effects
				(font
					(size 1 1)
					(thickness 0.15)
				)
				(justify mirror)
			)
		)
		(property "Manufacturer" "Murata"
			(at 0 0 0)
			(unlocked yes)
			(layer "B.Fab")
			(hide yes)
			(effects
				(font
					(size 1 1)
					(thickness 0.15)
				)
				(justify mirror)
			)
		)
		(property "License" "Apache-2.0"
			(at 0 0 0)
			(unlocked yes)
			(layer "B.Fab")
			(hide yes)
			(effects
				(font
					(size 1 1)
					(thickness 0.15)
				)
				(justify mirror)
			)
		)
		(property "Author" "Antmicro"
			(at 0 0 0)
			(unlocked yes)
			(layer "B.Fab")
			(hide yes)
			(effects
				(font
					(size 1 1)
					(thickness 0.15)
				)
				(justify mirror)
			)
		)
		(property "Val" "1u"
			(at 0 0 0)
			(unlocked yes)
			(layer "B.Fab")
			(hide yes)
			(effects
				(font
					(size 1 1)
					(thickness 0.15)
				)
				(justify mirror)
			)
		)
		(property "Voltage" "25V"
			(at 0 0 0)
			(unlocked yes)
			(layer "B.Fab")
			(hide yes)
			(effects
				(font
					(size 1 1)
					(thickness 0.15)
				)
				(justify mirror)
			)
		)
		(property "Dielectric" "X5R"
			(at 0 0 0)
			(unlocked yes)
			(layer "B.Fab")
			(hide yes)
			(effects
				(font
					(size 1 1)
					(thickness 0.15)
				)
				(justify mirror)
			)
		)
		(sheetname "/2xRJ45/")
		(sheetfile "2xrj45.kicad_sch")
		(attr smd)
		(fp_rect
			(start -0.925 0.47)
			(end 0.925 -0.47)
			(stroke
				(width 0.05)
				(type default)
			)
			(fill no)
			(layer "B.CrtYd")
		)
		(fp_line
			(start -0.494 -0.248)
			(end -0.494 0.25)
			(stroke
				(width 0.15)
				(type solid)
			)
			(layer "B.Fab")
		)
		(fp_line
			(start -0.494 0.25)
			(end 0.504 0.25)
			(stroke
				(width 0.15)
				(type solid)
			)
			(layer "B.Fab")
		)
		(fp_line
			(start 0.504 -0.248)
			(end -0.494 -0.248)
			(stroke
				(width 0.15)
				(type solid)
			)
			(layer "B.Fab")
		)
		(fp_line
			(start 0.504 0.25)
			(end 0.504 -0.248)
			(stroke
				(width 0.15)
				(type solid)
			)
			(layer "B.Fab")
		)
		(fp_text user "Author: Antmicro"
			(at -0.939 -3.399 180)
			(layer "B.Fab")
			(effects
				(font
					(size 0.7 0.7)
					(thickness 0.15)
				)
				(justify left bottom mirror)
			)
		)
		(fp_text user "License: Apache-2.0"
			(at -0.939 -5.799 180)
			(layer "B.Fab")
			(effects
				(font
					(size 0.7 0.7)
					(thickness 0.15)
				)
				(justify left bottom mirror)
			)
		)
		(fp_text user "${REFERENCE}"
			(at -0.939 -4.599 180)
			(layer "B.Fab")
			(effects
				(font
					(size 0.7 0.7)
					(thickness 0.15)
				)
				(justify left bottom mirror)
			)
		)
		(pad "1" smd roundrect
			(at -0.48 0)
			(size 0.59 0.64)
			(layers "B.Cu" "B.Mask" "B.Paste")
			(roundrect_rratio 0.25)
			(net 23 "GND")
			(pintype "passive")
		)
		(pad "2" smd roundrect
			(at 0.48 0)
			(size 0.59 0.64)
			(layers "B.Cu" "B.Mask" "B.Paste")
			(roundrect_rratio 0.25)
			(net 133 "/2xRJ45/P0_CT")
			(pintype "passive")
		)
	)
	(footprint "antmicro-footprints:C_0402_1005Metric"
		(layer "B.Cu")
		(at 125.625 126.9 90)
		(descr "Capacitor SMD 0402")
		(tags "capacitor SMD 0402")
		(property "Reference" "C85"
			(at 7.700002 21.900002 270)
			(layer "B.SilkS")
			(effects
				(font
					(size 0.7 0.7)
					(thickness 0.15)
				)
				(justify mirror)
			)
		)
		(property "Value" "C_1u_0402"
			(at -1.022927 -2.155213 270)
			(layer "B.Fab")
			(effects
				(font
					(size 0.7 0.7)
					(thickness 0.15)
				)
				(justify left bottom mirror)
			)
		)
		(property "Datasheet" "https://product.tdk.com/en/search/capacitor/ceramic/mlcc/info?part_no=C1005X6S1A105K050BC"
			(at 0 0 270)
			(layer "B.Fab")
			(hide yes)
			(effects
				(font
					(size 1.27 1.27)
					(thickness 0.15)
				)
				(justify mirror)
			)
		)
		(property "Description" "SMD Multilayer Ceramic Capacitor, 1 µF, 10 V, 0402 [1005 Metric], ± 10%, X6S, C"
			(at 0 0 270)
			(layer "B.Fab")
			(hide yes)
			(effects
				(font
					(size 1.27 1.27)
					(thickness 0.15)
				)
				(justify mirror)
			)
		)
		(property "MPN" "C1005X6S1A105K050BC"
			(at 0 0 90)
			(unlocked yes)
			(layer "B.Fab")
			(hide yes)
			(effects
				(font
					(size 1 1)
					(thickness 0.15)
				)
				(justify mirror)
			)
		)
		(property "Manufacturer" "TDK"
			(at 0 0 90)
			(unlocked yes)
			(layer "B.Fab")
			(hide yes)
			(effects
				(font
					(size 1 1)
					(thickness 0.15)
				)
				(justify mirror)
			)
		)
		(property "License" "Apache-2.0"
			(at 0 0 90)
			(unlocked yes)
			(layer "B.Fab")
			(hide yes)
			(effects
				(font
					(size 1 1)
					(thickness 0.15)
				)
				(justify mirror)
			)
		)
		(property "Val" "1u"
			(at 0 0 90)
			(unlocked yes)
			(layer "B.Fab")
			(hide yes)
			(effects
				(font
					(size 1 1)
					(thickness 0.15)
				)
				(justify mirror)
			)
		)
		(property "Voltage" ""
			(at 0 0 90)
			(unlocked yes)
			(layer "B.Fab")
			(hide yes)
			(effects
				(font
					(size 1 1)
					(thickness 0.15)
				)
				(justify mirror)
			)
		)
		(property "Dielectric" ""
			(at 0 0 90)
			(unlocked yes)
			(layer "B.Fab")
			(hide yes)
			(effects
				(font
					(size 1 1)
					(thickness 0.15)
				)
				(justify mirror)
			)
		)
		(property "Author" "Antmicro"
			(at 0 0 90)
			(unlocked yes)
			(layer "B.Fab")
			(hide yes)
			(effects
				(font
					(size 1 1)
					(thickness 0.15)
				)
				(justify mirror)
			)
		)
		(sheetname "/TB Controller - Power/")
		(sheetfile "tb-power.kicad_sch")
		(attr smd)
		(fp_rect
			(start -0.925 0.47)
			(end 0.925 -0.47)
			(stroke
				(width 0.05)
				(type default)
			)
			(fill no)
			(layer "B.CrtYd")
		)
		(fp_line
			(start 0.504 -0.248)
			(end -0.494 -0.248)
			(stroke
				(width 0.15)
				(type solid)
			)
			(layer "B.Fab")
		)
		(fp_line
			(start -0.494 -0.248)
			(end -0.494 0.25)
			(stroke
				(width 0.15)
				(type solid)
			)
			(layer "B.Fab")
		)
		(fp_line
			(start 0.504 0.25)
			(end 0.504 -0.248)
			(stroke
				(width 0.15)
				(type solid)
			)
			(layer "B.Fab")
		)
		(fp_line
			(start -0.494 0.25)
			(end 0.504 0.25)
			(stroke
				(width 0.15)
				(type solid)
			)
			(layer "B.Fab")
		)
		(fp_text user "License: Apache-2.0"
			(at -0.939 -5.799 270)
			(layer "B.Fab")
			(effects
				(font
					(size 0.7 0.7)
					(thickness 0.15)
				)
				(justify left bottom mirror)
			)
		)
		(fp_text user "${REFERENCE}"
			(at -0.939 -4.599 270)
			(layer "B.Fab")
			(effects
				(font
					(size 0.7 0.7)
					(thickness 0.15)
				)
				(justify left bottom mirror)
			)
		)
		(fp_text user "Author: Antmicro"
			(at -0.939 -3.399 270)
			(layer "B.Fab")
			(effects
				(font
					(size 0.7 0.7)
					(thickness 0.15)
				)
				(justify left bottom mirror)
			)
		)
		(pad "1" smd roundrect
			(at -0.48 0 90)
			(size 0.59 0.64)
			(layers "B.Cu" "B.Mask" "B.Paste")
			(roundrect_rratio 0.25)
			(net 23 "GND")
			(pintype "passive")
		)
		(pad "2" smd roundrect
			(at 0.48 0 90)
			(size 0.59 0.64)
			(layers "B.Cu" "B.Mask" "B.Paste")
			(roundrect_rratio 0.25)
			(net 180 "Net-(U4A-VCC0P9_LVR_SENSE)")
			(pintype "passive")
		)
	)
	(footprint "antmicro-footprints:R_0402_1005Metric"
		(layer "B.Cu")
		(at 154.481865 74.785117 -90)
		(descr "Resistor SMD 0402")
		(tags "resistor SMD 0402")
		(property "Reference" "R203"
			(at 8.014883 -21.618136 90)
			(layer "B.SilkS")
			(effects
				(font
					(size 0.7 0.7)
					(thickness 0.15)
				)
				(justify mirror)
			)
		)
		(property "Value" "R_100R_0402"
			(at -1.011843 -1.772047 90)
			(layer "B.Fab")
			(effects
				(font
					(size 0.7 0.7)
					(thickness 0.15)
				)
				(justify left bottom mirror)
			)
		)
		(property "Datasheet" "https://www.bourns.com/docs/product-datasheets/cr.pdf"
			(at 0 0 90)
			(layer "B.Fab")
			(hide yes)
			(effects
				(font
					(size 1.27 1.27)
					(thickness 0.15)
				)
				(justify mirror)
			)
		)
		(property "Description" "SMD Chip Resistor, 100 ohm, ± 1%, 62.5 mW, 0402 [1005 Metric], Thick Film, General Purpose"
			(at 0 0 90)
			(layer "B.Fab")
			(hide yes)
			(effects
				(font
					(size 1.27 1.27)
					(thickness 0.15)
				)
				(justify mirror)
			)
		)
		(property "MPN" "CR0402-FX-1000GLF"
			(at 0 0 270)
			(unlocked yes)
			(layer "B.Fab")
			(hide yes)
			(effects
				(font
					(size 1 1)
					(thickness 0.15)
				)
				(justify mirror)
			)
		)
		(property "Manufacturer" "Bourns"
			(at 0 0 270)
			(unlocked yes)
			(layer "B.Fab")
			(hide yes)
			(effects
				(font
					(size 1 1)
					(thickness 0.15)
				)
				(justify mirror)
			)
		)
		(property "License" "Apache-2.0"
			(at 0 0 270)
			(unlocked yes)
			(layer "B.Fab")
			(hide yes)
			(effects
				(font
					(size 1 1)
					(thickness 0.15)
				)
				(justify mirror)
			)
		)
		(property "Author" "Antmicro"
			(at 0 0 270)
			(unlocked yes)
			(layer "B.Fab")
			(hide yes)
			(effects
				(font
					(size 1 1)
					(thickness 0.15)
				)
				(justify mirror)
			)
		)
		(property "Val" "100R"
			(at 0 0 270)
			(unlocked yes)
			(layer "B.Fab")
			(hide yes)
			(effects
				(font
					(size 1 1)
					(thickness 0.15)
				)
				(justify mirror)
			)
		)
		(property "Tolerance" "1%"
			(at 0 0 270)
			(unlocked yes)
			(layer "B.Fab")
			(hide yes)
			(effects
				(font
					(size 1 1)
					(thickness 0.15)
				)
				(justify mirror)
			)
		)
		(sheetname "/X710-AT2 10GbE/")
		(sheetfile "x710-at2-10gbe.kicad_sch")
		(attr smd dnp)
		(fp_rect
			(start -0.925 0.47)
			(end 0.925 -0.47)
			(stroke
				(width 0.05)
				(type default)
			)
			(fill no)
			(layer "B.CrtYd")
		)
		(fp_rect
			(start -0.5 0.25)
			(end 0.5 -0.25)
			(stroke
				(width 0.15)
				(type solid)
			)
			(fill no)
			(layer "B.Fab")
		)
		(fp_text user "License: Apache-2.0"
			(at -0.95 -5.169 90)
			(layer "B.Fab")
			(effects
				(font
					(size 0.7 0.7)
					(thickness 0.15)
				)
				(justify left bottom mirror)
			)
		)
		(fp_text user "${REFERENCE}"
			(at -0.95 -3.168 90)
			(layer "B.Fab")
			(effects
				(font
					(size 0.7 0.7)
					(thickness 0.15)
				)
				(justify left bottom mirror)
			)
		)
		(fp_text user "Author: Antmicro"
			(at -0.95 -4.169 90)
			(layer "B.Fab")
			(effects
				(font
					(size 0.7 0.7)
					(thickness 0.15)
				)
				(justify left bottom mirror)
			)
		)
		(pad "1" smd roundrect
			(at -0.48 0 270)
			(size 0.59 0.64)
			(layers "B.Cu" "B.Mask" "B.Paste")
			(roundrect_rratio 0.25)
			(net 23 "GND")
			(pintype "passive")
		)
		(pad "2" smd roundrect
			(at 0.48 0 270)
			(size 0.59 0.64)
			(layers "B.Cu" "B.Mask" "B.Paste")
			(roundrect_rratio 0.25)
			(net 64 "/X710-AT2 10GbE/OSC_SEL")
			(pintype "passive")
		)
	)
	(footprint "antmicro-footprints:C_0402_1005Metric"
		(layer "B.Cu")
		(at 153.031866 75.260117 180)
		(descr "Capacitor SMD 0402")
		(tags "capacitor SMD 0402")
		(property "Reference" "C225"
			(at -21.168135 -9.464883 0)
			(layer "B.SilkS")
			(effects
				(font
					(size 0.7 0.7)
					(thickness 0.15)
				)
				(justify mirror)
			)
		)
		(property "Value" "C_1u_25V_0402"
			(at -1.022927 -2.155213 0)
			(layer "B.Fab")
			(effects
				(font
					(size 0.7 0.7)
					(thickness 0.15)
				)
				(justify left bottom mirror)
			)
		)
		(property "Datasheet" "https://www.murata.com/products/productdetail?partno=GRM155R61E105KE11%23"
			(at 0 0 0)
			(layer "B.Fab")
			(hide yes)
			(effects
				(font
					(size 1.27 1.27)
					(thickness 0.15)
				)
				(justify mirror)
			)
		)
		(property "Description" "SMD Multilayer Ceramic Capacitor, 1 µF, 25 V, 0402 [1005 Metric], ± 10%, X5R, GRM Series"
			(at 0 0 0)
			(layer "B.Fab")
			(hide yes)
			(effects
				(font
					(size 1.27 1.27)
					(thickness 0.15)
				)
				(justify mirror)
			)
		)
		(property "MPN" "GRM155R61E105KE11J"
			(at 0 0 180)
			(unlocked yes)
			(layer "B.Fab")
			(hide yes)
			(effects
				(font
					(size 1 1)
					(thickness 0.15)
				)
				(justify mirror)
			)
		)
		(property "Manufacturer" "Murata"
			(at 0 0 180)
			(unlocked yes)
			(layer "B.Fab")
			(hide yes)
			(effects
				(font
					(size 1 1)
					(thickness 0.15)
				)
				(justify mirror)
			)
		)
		(property "License" "Apache-2.0"
			(at 0 0 180)
			(unlocked yes)
			(layer "B.Fab")
			(hide yes)
			(effects
				(font
					(size 1 1)
					(thickness 0.15)
				)
				(justify mirror)
			)
		)
		(property "Author" "Antmicro"
			(at 0 0 180)
			(unlocked yes)
			(layer "B.Fab")
			(hide yes)
			(effects
				(font
					(size 1 1)
					(thickness 0.15)
				)
				(justify mirror)
			)
		)
		(property "Val" "1u"
			(at 0 0 180)
			(unlocked yes)
			(layer "B.Fab")
			(hide yes)
			(effects
				(font
					(size 1 1)
					(thickness 0.15)
				)
				(justify mirror)
			)
		)
		(property "Voltage" "25V"
			(at 0 0 180)
			(unlocked yes)
			(layer "B.Fab")
			(hide yes)
			(effects
				(font
					(size 1 1)
					(thickness 0.15)
				)
				(justify mirror)
			)
		)
		(property "Dielectric" "X5R"
			(at 0 0 180)
			(unlocked yes)
			(layer "B.Fab")
			(hide yes)
			(effects
				(font
					(size 1 1)
					(thickness 0.15)
				)
				(justify mirror)
			)
		)
		(sheetname "/X710-AT2 power/")
		(sheetfile "x710-at2-power.kicad_sch")
		(attr smd)
		(fp_rect
			(start -0.925 0.47)
			(end 0.925 -0.47)
			(stroke
				(width 0.05)
				(type default)
			)
			(fill no)
			(layer "B.CrtYd")
		)
		(fp_line
			(start 0.504 0.25)
			(end 0.504 -0.248)
			(stroke
				(width 0.15)
				(type solid)
			)
			(layer "B.Fab")
		)
		(fp_line
			(start 0.504 -0.248)
			(end -0.494 -0.248)
			(stroke
				(width 0.15)
				(type solid)
			)
			(layer "B.Fab")
		)
		(fp_line
			(start -0.494 0.25)
			(end 0.504 0.25)
			(stroke
				(width 0.15)
				(type solid)
			)
			(layer "B.Fab")
		)
		(fp_line
			(start -0.494 -0.248)
			(end -0.494 0.25)
			(stroke
				(width 0.15)
				(type solid)
			)
			(layer "B.Fab")
		)
		(fp_text user "${REFERENCE}"
			(at -0.939 -4.599 0)
			(layer "B.Fab")
			(effects
				(font
					(size 0.7 0.7)
					(thickness 0.15)
				)
				(justify left bottom mirror)
			)
		)
		(fp_text user "License: Apache-2.0"
			(at -0.939 -5.799 0)
			(layer "B.Fab")
			(effects
				(font
					(size 0.7 0.7)
					(thickness 0.15)
				)
				(justify left bottom mirror)
			)
		)
		(fp_text user "Author: Antmicro"
			(at -0.939 -3.399 0)
			(layer "B.Fab")
			(effects
				(font
					(size 0.7 0.7)
					(thickness 0.15)
				)
				(justify left bottom mirror)
			)
		)
		(pad "1" smd roundrect
			(at -0.48 0 180)
			(size 0.59 0.64)
			(layers "B.Cu" "B.Mask" "B.Paste")
			(roundrect_rratio 0.25)
			(net 23 "GND")
			(pintype "passive")
		)
		(pad "2" smd roundrect
			(at 0.48 0 180)
			(size 0.59 0.64)
			(layers "B.Cu" "B.Mask" "B.Paste")
			(roundrect_rratio 0.25)
			(net 7 "+3V3")
			(pintype "passive")
		)
	)
	(footprint "antmicro-footprints:C_1206_3216Metric"
		(layer "B.Cu")
		(at 163.25 136.25 90)
		(descr "Capacitor SMD 1206")
		(tags "capacitor SMD 1206")
		(property "Reference" "C291"
			(at 1.25 -1.25 270)
			(layer "B.SilkS")
			(effects
				(font
					(size 0.7 0.7)
					(thickness 0.15)
				)
				(justify left bottom mirror)
			)
		)
		(property "Value" "C_220u_1206_6V3"
			(at 0 -2.101 270)
			(layer "B.Fab")
			(effects
				(font
					(size 0.7 0.7)
					(thickness 0.15)
				)
				(justify left bottom mirror)
			)
		)
		(property "Datasheet" "https://www.murata.com/products/productdetail?partno=GRM31CR60J227ME11%23"
			(at 0 0 270)
			(layer "B.Fab")
			(hide yes)
			(effects
				(font
					(size 1.27 1.27)
					(thickness 0.15)
				)
				(justify mirror)
			)
		)
		(property "Description" "SMD Multilayer Ceramic Capacitor, 220 µF, 6.3 V, 1206 [3216 Metric], ± 20%, X5R, GRM Series"
			(at 0 0 270)
			(layer "B.Fab")
			(hide yes)
			(effects
				(font
					(size 1.27 1.27)
					(thickness 0.15)
				)
				(justify mirror)
			)
		)
		(property "MPN" "GRM31CR60J227ME11L"
			(at 0 0 90)
			(unlocked yes)
			(layer "B.Fab")
			(hide yes)
			(effects
				(font
					(size 1 1)
					(thickness 0.15)
				)
				(justify mirror)
			)
		)
		(property "Manufacturer" "Murata"
			(at 0 0 90)
			(unlocked yes)
			(layer "B.Fab")
			(hide yes)
			(effects
				(font
					(size 1 1)
					(thickness 0.15)
				)
				(justify mirror)
			)
		)
		(property "License" "Apache-2.0"
			(at 0 0 90)
			(unlocked yes)
			(layer "B.Fab")
			(hide yes)
			(effects
				(font
					(size 1 1)
					(thickness 0.15)
				)
				(justify mirror)
			)
		)
		(property "Author" "Antmicro"
			(at 0 0 90)
			(unlocked yes)
			(layer "B.Fab")
			(hide yes)
			(effects
				(font
					(size 1 1)
					(thickness 0.15)
				)
				(justify mirror)
			)
		)
		(property "Val" "220u"
			(at 0 0 90)
			(unlocked yes)
			(layer "B.Fab")
			(hide yes)
			(effects
				(font
					(size 1 1)
					(thickness 0.15)
				)
				(justify mirror)
			)
		)
		(property "Voltage" ""
			(at 0 0 90)
			(unlocked yes)
			(layer "B.Fab")
			(hide yes)
			(effects
				(font
					(size 1 1)
					(thickness 0.15)
				)
				(justify mirror)
			)
		)
		(property "Dielectric" ""
			(at 0 0 90)
			(unlocked yes)
			(layer "B.Fab")
			(hide yes)
			(effects
				(font
					(size 1 1)
					(thickness 0.15)
				)
				(justify mirror)
			)
		)
		(property "Public" "False"
			(at 0 0 90)
			(unlocked yes)
			(layer "B.Fab")
			(hide yes)
			(effects
				(font
					(size 1 1)
					(thickness 0.15)
				)
				(justify mirror)
			)
		)
		(sheetname "/2xRJ45/")
		(sheetfile "2xrj45.kicad_sch")
		(attr smd)
		(fp_line
			(start 0.8 -0.901)
			(end -0.8 -0.901)
			(stroke
				(width 0.15)
				(type solid)
			)
			(layer "B.SilkS")
		)
		(fp_line
			(start 0.8 0.899)
			(end -0.8 0.899)
			(stroke
				(width 0.15)
				(type solid)
			)
			(layer "B.SilkS")
		)
		(fp_rect
			(start -2.325 1.15)
			(end 2.325 -1.15)
			(stroke
				(width 0.05)
				(type default)
			)
			(fill no)
			(layer "B.CrtYd")
		)
		(fp_rect
			(start -1.6 0.799)
			(end 1.6 -0.801)
			(stroke
				(width 0.15)
				(type solid)
			)
			(fill no)
			(layer "B.Fab")
		)
		(fp_text user "License: Apache-2.0"
			(at -2.625 -6.501 270)
			(layer "B.Fab")
			(effects
				(font
					(size 0.7 0.7)
					(thickness 0.15)
				)
				(justify left bottom mirror)
			)
		)
		(fp_text user "Author: Antmicro"
			(at -2.625 -5.301 270)
			(layer "B.Fab")
			(effects
				(font
					(size 0.7 0.7)
					(thickness 0.15)
				)
				(justify left bottom mirror)
			)
		)
		(fp_text user "${REFERENCE}"
			(at -2.625 -4.101 270)
			(layer "B.Fab")
			(effects
				(font
					(size 0.7 0.7)
					(thickness 0.15)
				)
				(justify left bottom mirror)
			)
		)
		(pad "1" smd roundrect
			(at -1.5 -0.001 90)
			(size 1.15 1.8)
			(layers "B.Cu" "B.Mask" "B.Paste")
			(roundrect_rratio 0.25)
			(net 23 "GND")
			(pintype "passive")
		)
		(pad "2" smd roundrect
			(at 1.5 -0.001 90)
			(size 1.15 1.8)
			(layers "B.Cu" "B.Mask" "B.Paste")
			(roundrect_rratio 0.25)
			(net 135 "+1V88_CT")
			(pintype "passive")
		)
	)
	(footprint "antmicro-footprints:C_0603_1608Metric"
		(layer "B.Cu")
		(at 149.481866 97.5 180)
		(descr "Capacitor SMD 0603")
		(tags "capacitor 0603")
		(property "Reference" "C176"
			(at -1.318134 0.7 0)
			(layer "B.SilkS")
			(effects
				(font
					(size 0.7 0.7)
					(thickness 0.15)
				)
				(justify left bottom mirror)
			)
		)
		(property "Value" "C_10u_10V_X7R_0603"
			(at -1.42757 -1.770288 0)
			(layer "B.Fab")
			(effects
				(font
					(size 0.7 0.7)
					(thickness 0.15)
				)
				(justify left bottom mirror)
			)
		)
		(property "Datasheet" "https://www.murata.com/products/productdetail?partno=GRM188Z71A106KA73%23"
			(at 0 0 0)
			(layer "B.Fab")
			(hide yes)
			(effects
				(font
					(size 1.27 1.27)
					(thickness 0.15)
				)
				(justify mirror)
			)
		)
		(property "Description" "SMD Multilayer Ceramic Capacitor,  10µF, 10V, 0603, ±10%, X7R"
			(at 0 0 0)
			(layer "B.Fab")
			(hide yes)
			(effects
				(font
					(size 1.27 1.27)
					(thickness 0.15)
				)
				(justify mirror)
			)
		)
		(property "MPN" "GRM188Z71A106KA73D"
			(at 0 0 180)
			(unlocked yes)
			(layer "B.Fab")
			(hide yes)
			(effects
				(font
					(size 1 1)
					(thickness 0.15)
				)
				(justify mirror)
			)
		)
		(property "Val" "10u"
			(at 0 0 180)
			(unlocked yes)
			(layer "B.Fab")
			(hide yes)
			(effects
				(font
					(size 1 1)
					(thickness 0.15)
				)
				(justify mirror)
			)
		)
		(property "Voltage" "10V"
			(at 0 0 180)
			(unlocked yes)
			(layer "B.Fab")
			(hide yes)
			(effects
				(font
					(size 1 1)
					(thickness 0.15)
				)
				(justify mirror)
			)
		)
		(property "Dielectric" "X7R"
			(at 0 0 180)
			(unlocked yes)
			(layer "B.Fab")
			(hide yes)
			(effects
				(font
					(size 1 1)
					(thickness 0.15)
				)
				(justify mirror)
			)
		)
		(property "Manufacturer" "Murata"
			(at 0 0 180)
			(unlocked yes)
			(layer "B.Fab")
			(hide yes)
			(effects
				(font
					(size 1 1)
					(thickness 0.15)
				)
				(justify mirror)
			)
		)
		(property "License" "Apache-2.0"
			(at 0 0 180)
			(unlocked yes)
			(layer "B.Fab")
			(hide yes)
			(effects
				(font
					(size 1 1)
					(thickness 0.15)
				)
				(justify mirror)
			)
		)
		(property "Author" "Antmicro"
			(at 0 0 180)
			(unlocked yes)
			(layer "B.Fab")
			(hide yes)
			(effects
				(font
					(size 1 1)
					(thickness 0.15)
				)
				(justify mirror)
			)
		)
		(sheetname "/X710-AT2 power/")
		(sheetfile "x710-at2-power.kicad_sch")
		(attr smd)
		(fp_line
			(start -0.15 0.4)
			(end 0.15 0.4)
			(stroke
				(width 0.15)
				(type solid)
			)
			(layer "B.SilkS")
		)
		(fp_line
			(start -0.15 -0.4)
			(end 0.15 -0.4)
			(stroke
				(width 0.15)
				(type solid)
			)
			(layer "B.SilkS")
		)
		(fp_rect
			(start -1.25 0.65)
			(end 1.25 -0.65)
			(stroke
				(width 0.05)
				(type solid)
			)
			(fill no)
			(layer "B.CrtYd")
		)
		(fp_rect
			(start -0.8 0.4)
			(end 0.8 -0.4)
			(stroke
				(width 0.15)
				(type solid)
			)
			(fill no)
			(layer "B.Fab")
		)
		(fp_text user "Author: Antmicro"
			(at -1.682 -4.894 0)
			(layer "B.Fab")
			(effects
				(font
					(size 0.7 0.7)
					(thickness 0.15)
				)
				(justify left bottom mirror)
			)
		)
		(fp_text user "${REFERENCE}"
			(at -1.682 -3.895 0)
			(layer "B.Fab")
			(effects
				(font
					(size 0.7 0.7)
					(thickness 0.15)
				)
				(justify left bottom mirror)
			)
		)
		(fp_text user "License: Apache-2.0"
			(at -1.682 -5.895 0)
			(layer "B.Fab")
			(effects
				(font
					(size 0.7 0.7)
					(thickness 0.15)
				)
				(justify left bottom mirror)
			)
		)
		(pad "1" smd roundrect
			(at -0.7 0 180)
			(size 0.8 1)
			(layers "B.Cu" "B.Mask" "B.Paste")
			(roundrect_rratio 0.2)
			(net 23 "GND")
			(pintype "passive")
		)
		(pad "2" smd roundrect
			(at 0.7 0 180)
			(size 0.8 1)
			(layers "B.Cu" "B.Mask" "B.Paste")
			(roundrect_rratio 0.2)
			(net 18 "+1V88")
			(pintype "passive")
		)
	)
	(footprint "antmicro-footprints:C_0402_1005Metric"
		(layer "B.Cu")
		(at 167 136)
		(descr "Capacitor SMD 0402")
		(tags "capacitor SMD 0402")
		(property "Reference" "C299"
			(at 1 -0.5 180)
			(layer "B.SilkS")
			(effects
				(font
					(size 0.7 0.7)
					(thickness 0.15)
				)
				(justify left bottom mirror)
			)
		)
		(property "Value" "C_1u_25V_0402"
			(at -1.022927 -2.155213 180)
			(layer "B.Fab")
			(effects
				(font
					(size 0.7 0.7)
					(thickness 0.15)
				)
				(justify left bottom mirror)
			)
		)
		(property "Datasheet" "https://www.murata.com/products/productdetail?partno=GRM155R61E105KE11%23"
			(at 0 0 180)
			(layer "B.Fab")
			(hide yes)
			(effects
				(font
					(size 1.27 1.27)
					(thickness 0.15)
				)
				(justify mirror)
			)
		)
		(property "Description" "SMD Multilayer Ceramic Capacitor, 1 µF, 25 V, 0402 [1005 Metric], ± 10%, X5R, GRM Series"
			(at 0 0 180)
			(layer "B.Fab")
			(hide yes)
			(effects
				(font
					(size 1.27 1.27)
					(thickness 0.15)
				)
				(justify mirror)
			)
		)
		(property "MPN" "GRM155R61E105KE11J"
			(at 0 0 0)
			(unlocked yes)
			(layer "B.Fab")
			(hide yes)
			(effects
				(font
					(size 1 1)
					(thickness 0.15)
				)
				(justify mirror)
			)
		)
		(property "Manufacturer" "Murata"
			(at 0 0 0)
			(unlocked yes)
			(layer "B.Fab")
			(hide yes)
			(effects
				(font
					(size 1 1)
					(thickness 0.15)
				)
				(justify mirror)
			)
		)
		(property "License" "Apache-2.0"
			(at 0 0 0)
			(unlocked yes)
			(layer "B.Fab")
			(hide yes)
			(effects
				(font
					(size 1 1)
					(thickness 0.15)
				)
				(justify mirror)
			)
		)
		(property "Author" "Antmicro"
			(at 0 0 0)
			(unlocked yes)
			(layer "B.Fab")
			(hide yes)
			(effects
				(font
					(size 1 1)
					(thickness 0.15)
				)
				(justify mirror)
			)
		)
		(property "Val" "1u"
			(at 0 0 0)
			(unlocked yes)
			(layer "B.Fab")
			(hide yes)
			(effects
				(font
					(size 1 1)
					(thickness 0.15)
				)
				(justify mirror)
			)
		)
		(property "Voltage" "25V"
			(at 0 0 0)
			(unlocked yes)
			(layer "B.Fab")
			(hide yes)
			(effects
				(font
					(size 1 1)
					(thickness 0.15)
				)
				(justify mirror)
			)
		)
		(property "Dielectric" "X5R"
			(at 0 0 0)
			(unlocked yes)
			(layer "B.Fab")
			(hide yes)
			(effects
				(font
					(size 1 1)
					(thickness 0.15)
				)
				(justify mirror)
			)
		)
		(sheetname "/2xRJ45/")
		(sheetfile "2xrj45.kicad_sch")
		(attr smd)
		(fp_rect
			(start -0.925 0.47)
			(end 0.925 -0.47)
			(stroke
				(width 0.05)
				(type default)
			)
			(fill no)
			(layer "B.CrtYd")
		)
		(fp_line
			(start -0.494 -0.248)
			(end -0.494 0.25)
			(stroke
				(width 0.15)
				(type solid)
			)
			(layer "B.Fab")
		)
		(fp_line
			(start -0.494 0.25)
			(end 0.504 0.25)
			(stroke
				(width 0.15)
				(type solid)
			)
			(layer "B.Fab")
		)
		(fp_line
			(start 0.504 -0.248)
			(end -0.494 -0.248)
			(stroke
				(width 0.15)
				(type solid)
			)
			(layer "B.Fab")
		)
		(fp_line
			(start 0.504 0.25)
			(end 0.504 -0.248)
			(stroke
				(width 0.15)
				(type solid)
			)
			(layer "B.Fab")
		)
		(fp_text user "${REFERENCE}"
			(at -0.939 -4.599 180)
			(layer "B.Fab")
			(effects
				(font
					(size 0.7 0.7)
					(thickness 0.15)
				)
				(justify left bottom mirror)
			)
		)
		(fp_text user "Author: Antmicro"
			(at -0.939 -3.399 180)
			(layer "B.Fab")
			(effects
				(font
					(size 0.7 0.7)
					(thickness 0.15)
				)
				(justify left bottom mirror)
			)
		)
		(fp_text user "License: Apache-2.0"
			(at -0.939 -5.799 180)
			(layer "B.Fab")
			(effects
				(font
					(size 0.7 0.7)
					(thickness 0.15)
				)
				(justify left bottom mirror)
			)
		)
		(pad "1" smd roundrect
			(at -0.48 0)
			(size 0.59 0.64)
			(layers "B.Cu" "B.Mask" "B.Paste")
			(roundrect_rratio 0.25)
			(net 23 "GND")
			(pintype "passive")
		)
		(pad "2" smd roundrect
			(at 0.48 0)
			(size 0.59 0.64)
			(layers "B.Cu" "B.Mask" "B.Paste")
			(roundrect_rratio 0.25)
			(net 134 "/2xRJ45/P1_CT")
			(pintype "passive")
		)
	)
	(footprint "antmicro-footprints:R_0402_1005Metric"
		(layer "B.Cu")
		(at 162.381866 75.485118)
		(descr "Resistor SMD 0402")
		(tags "resistor SMD 0402")
		(property "Reference" "R175"
			(at 2.368134 0.014883 180)
			(layer "B.SilkS")
			(effects
				(font
					(size 0.7 0.7)
					(thickness 0.15)
				)
				(justify mirror)
			)
		)
		(property "Value" "R_1k_0402"
			(at -1.011843 -1.772047 180)
			(layer "B.Fab")
			(effects
				(font
					(size 0.7 0.7)
					(thickness 0.15)
				)
				(justify left bottom mirror)
			)
		)
		(property "Datasheet" "https://www.bourns.com/docs/product-datasheets/cr.pdf"
			(at 0 0 180)
			(layer "B.Fab")
			(hide yes)
			(effects
				(font
					(size 1.27 1.27)
					(thickness 0.15)
				)
				(justify mirror)
			)
		)
		(property "Description" "SMD Chip Resistor, 1 kohm, ± 1%, 63 mW, 0402 [1005 Metric], Thick Film, General Purpose"
			(at 0 0 180)
			(layer "B.Fab")
			(hide yes)
			(effects
				(font
					(size 1.27 1.27)
					(thickness 0.15)
				)
				(justify mirror)
			)
		)
		(property "MPN" "CR0402-FX-1001GLF"
			(at 0 0 0)
			(unlocked yes)
			(layer "B.Fab")
			(hide yes)
			(effects
				(font
					(size 1 1)
					(thickness 0.15)
				)
				(justify mirror)
			)
		)
		(property "Manufacturer" "Bourns"
			(at 0 0 0)
			(unlocked yes)
			(layer "B.Fab")
			(hide yes)
			(effects
				(font
					(size 1 1)
					(thickness 0.15)
				)
				(justify mirror)
			)
		)
		(property "License" "Apache-2.0"
			(at 0 0 0)
			(unlocked yes)
			(layer "B.Fab")
			(hide yes)
			(effects
				(font
					(size 1 1)
					(thickness 0.15)
				)
				(justify mirror)
			)
		)
		(property "Author" "Antmicro"
			(at 0 0 0)
			(unlocked yes)
			(layer "B.Fab")
			(hide yes)
			(effects
				(font
					(size 1 1)
					(thickness 0.15)
				)
				(justify mirror)
			)
		)
		(property "Val" "1k"
			(at 0 0 0)
			(unlocked yes)
			(layer "B.Fab")
			(hide yes)
			(effects
				(font
					(size 1 1)
					(thickness 0.15)
				)
				(justify mirror)
			)
		)
		(property "Tolerance" "1%"
			(at 0 0 0)
			(unlocked yes)
			(layer "B.Fab")
			(hide yes)
			(effects
				(font
					(size 1 1)
					(thickness 0.15)
				)
				(justify mirror)
			)
		)
		(sheetname "/X710-AT2 Misc/")
		(sheetfile "x710-at2-mics.kicad_sch")
		(attr smd)
		(fp_rect
			(start -0.925 0.47)
			(end 0.925 -0.47)
			(stroke
				(width 0.05)
				(type default)
			)
			(fill no)
			(layer "B.CrtYd")
		)
		(fp_rect
			(start -0.5 0.25)
			(end 0.5 -0.25)
			(stroke
				(width 0.15)
				(type solid)
			)
			(fill no)
			(layer "B.Fab")
		)
		(fp_text user "${REFERENCE}"
			(at -0.95 -3.168 180)
			(layer "B.Fab")
			(effects
				(font
					(size 0.7 0.7)
					(thickness 0.15)
				)
				(justify left bottom mirror)
			)
		)
		(fp_text user "License: Apache-2.0"
			(at -0.95 -5.169 180)
			(layer "B.Fab")
			(effects
				(font
					(size 0.7 0.7)
					(thickness 0.15)
				)
				(justify left bottom mirror)
			)
		)
		(fp_text user "Author: Antmicro"
			(at -0.95 -4.169 180)
			(layer "B.Fab")
			(effects
				(font
					(size 0.7 0.7)
					(thickness 0.15)
				)
				(justify left bottom mirror)
			)
		)
		(pad "1" smd roundrect
			(at -0.48 0)
			(size 0.59 0.64)
			(layers "B.Cu" "B.Mask" "B.Paste")
			(roundrect_rratio 0.25)
			(net 111 "/X710-AT2 10GbE/~{P0_INT}")
			(pintype "passive")
		)
		(pad "2" smd roundrect
			(at 0.48 0)
			(size 0.59 0.64)
			(layers "B.Cu" "B.Mask" "B.Paste")
			(roundrect_rratio 0.25)
			(net 7 "+3V3")
			(pintype "passive")
		)
	)
	(footprint "antmicro-footprints:D_SOD-323F"
		(layer "B.Cu")
		(at 116.2 109.6 -90)
		(property "Reference" "D3"
			(at -0.8 -2 90)
			(layer "B.SilkS")
			(effects
				(font
					(size 0.7 0.7)
					(thickness 0.15)
				)
				(justify left bottom mirror)
			)
		)
		(property "Value" "MM3Z3V3C"
			(at 0 -1.9 90)
			(layer "B.Fab")
			(effects
				(font
					(size 0.7 0.7)
					(thickness 0.15)
				)
				(justify left bottom mirror)
			)
		)
		(property "Datasheet" "https://www.onsemi.com/download/data-sheet/pdf/mm3z9v1c-d.pdf"
			(at 0 0 90)
			(layer "B.Fab")
			(hide yes)
			(effects
				(font
					(size 1.27 1.27)
					(thickness 0.15)
				)
				(justify mirror)
			)
		)
		(property "Description" "Zener Single Diode, 3.3 V, 200 mW, SOD-323F, 2 Pins, 150 °C, Surface Mount"
			(at 0 0 90)
			(layer "B.Fab")
			(hide yes)
			(effects
				(font
					(size 1.27 1.27)
					(thickness 0.15)
				)
				(justify mirror)
			)
		)
		(property "MPN" "MM3Z3V3C"
			(at 0 0 270)
			(unlocked yes)
			(layer "B.Fab")
			(hide yes)
			(effects
				(font
					(size 1 1)
					(thickness 0.15)
				)
				(justify mirror)
			)
		)
		(property "Manufacturer" "ON Semiconductor"
			(at 0 0 270)
			(unlocked yes)
			(layer "B.Fab")
			(hide yes)
			(effects
				(font
					(size 1 1)
					(thickness 0.15)
				)
				(justify mirror)
			)
		)
		(property "License" "Apache-2.0"
			(at 0 0 270)
			(unlocked yes)
			(layer "B.Fab")
			(hide yes)
			(effects
				(font
					(size 1 1)
					(thickness 0.15)
				)
				(justify mirror)
			)
		)
		(property "Author" "Antmicro"
			(at 0 0 270)
			(unlocked yes)
			(layer "B.Fab")
			(hide yes)
			(effects
				(font
					(size 1 1)
					(thickness 0.15)
				)
				(justify mirror)
			)
		)
		(sheetname "/PD and TB DC-DC/")
		(sheetfile "PD_and_TB_DC_DC.kicad_sch")
		(attr smd)
		(fp_line
			(start -0.975 0.749)
			(end -0.975 0.449)
			(stroke
				(width 0.15)
				(type solid)
			)
			(layer "B.SilkS")
		)
		(fp_line
			(start -0.625 0.749)
			(end -0.975 0.749)
			(stroke
				(width 0.15)
				(type solid)
			)
			(layer "B.SilkS")
		)
		(fp_line
			(start 0.623 0.749)
			(end 0.973 0.749)
			(stroke
				(width 0.15)
				(type solid)
			)
			(layer "B.SilkS")
		)
		(fp_line
			(start 0.973 0.749)
			(end 0.973 0.449)
			(stroke
				(width 0.15)
				(type solid)
			)
			(layer "B.SilkS")
		)
		(fp_line
			(start -0.5 0.425)
			(end -0.5 -0.425)
			(stroke
				(width 0.15)
				(type solid)
			)
			(layer "B.SilkS")
		)
		(fp_line
			(start 0.973 -0.451)
			(end 0.973 -0.749)
			(stroke
				(width 0.15)
				(type solid)
			)
			(layer "B.SilkS")
		)
		(fp_line
			(start -0.975 -0.749)
			(end -0.975 -0.451)
			(stroke
				(width 0.15)
				(type solid)
			)
			(layer "B.SilkS")
		)
		(fp_line
			(start -0.625 -0.749)
			(end -0.975 -0.749)
			(stroke
				(width 0.15)
				(type solid)
			)
			(layer "B.SilkS")
		)
		(fp_line
			(start 0.973 -0.749)
			(end 0.623 -0.749)
			(stroke
				(width 0.15)
				(type solid)
			)
			(layer "B.SilkS")
		)
		(fp_rect
			(start -1.55 0.95)
			(end 1.55 -0.95)
			(stroke
				(width 0.05)
				(type solid)
			)
			(fill no)
			(layer "B.CrtYd")
		)
		(fp_rect
			(start -1.25 0.676)
			(end 1.245365 -0.676)
			(stroke
				(width 0.1)
				(type solid)
			)
			(fill no)
			(layer "B.Fab")
		)
		(fp_text user "License: Apache-2.0"
			(at -1.7 -6.299 90)
			(layer "B.Fab")
			(effects
				(font
					(size 0.7 0.7)
					(thickness 0.15)
				)
				(justify left bottom mirror)
			)
		)
		(fp_text user "${REFERENCE}"
			(at -1.7 -5.099 90)
			(layer "B.Fab")
			(effects
				(font
					(size 0.7 0.7)
					(thickness 0.15)
				)
				(justify left bottom mirror)
			)
		)
		(fp_text user "Author: Antmicro"
			(at -1.7 -3.899 90)
			(layer "B.Fab")
			(effects
				(font
					(size 0.7 0.7)
					(thickness 0.15)
				)
				(justify left bottom mirror)
			)
		)
		(pad "1" smd roundrect
			(at -1.051 -0.001 270)
			(size 0.8 0.6)
			(layers "B.Cu" "B.Mask" "B.Paste")
			(roundrect_rratio 0.15)
			(net 413 "Net-(D3-C)")
			(pinfunction "C")
			(pintype "passive")
		)
		(pad "2" smd roundrect
			(at 1.05 -0.001 270)
			(size 0.8 0.6)
			(layers "B.Cu" "B.Mask" "B.Paste")
			(roundrect_rratio 0.15)
			(net 23 "GND")
			(pinfunction "A")
			(pintype "passive")
		)
	)
	(footprint "antmicro-footprints:C_0402_1005Metric"
		(layer "B.Cu")
		(at 157.681866 93.385117 -90)
		(descr "Capacitor SMD 0402")
		(tags "capacitor SMD 0402")
		(property "Reference" "C160"
			(at 9.914883 -18.068134 90)
			(layer "B.SilkS")
			(effects
				(font
					(size 0.7 0.7)
					(thickness 0.15)
				)
				(justify mirror)
			)
		)
		(property "Value" "C_100n_0402"
			(at -1.022927 -2.155213 90)
			(layer "B.Fab")
			(effects
				(font
					(size 0.7 0.7)
					(thickness 0.15)
				)
				(justify left bottom mirror)
			)
		)
		(property "Datasheet" "https://www.murata.com/products/productdetail?partno=GRM155R61H104KE14%23"
			(at 0 0 90)
			(layer "B.Fab")
			(hide yes)
			(effects
				(font
					(size 1.27 1.27)
					(thickness 0.15)
				)
				(justify mirror)
			)
		)
		(property "Description" "SMD Multilayer Ceramic Capacitor, 0.1 µF, 50 V, 0402 [1005 Metric], ± 10%, X5R, GRM Series"
			(at 0 0 90)
			(layer "B.Fab")
			(hide yes)
			(effects
				(font
					(size 1.27 1.27)
					(thickness 0.15)
				)
				(justify mirror)
			)
		)
		(property "MPN" "GRM155R61H104KE14D"
			(at 0 0 270)
			(unlocked yes)
			(layer "B.Fab")
			(hide yes)
			(effects
				(font
					(size 1 1)
					(thickness 0.15)
				)
				(justify mirror)
			)
		)
		(property "Val" "100n"
			(at 0 0 270)
			(unlocked yes)
			(layer "B.Fab")
			(hide yes)
			(effects
				(font
					(size 1 1)
					(thickness 0.15)
				)
				(justify mirror)
			)
		)
		(property "Voltage" "50V"
			(at 0 0 270)
			(unlocked yes)
			(layer "B.Fab")
			(hide yes)
			(effects
				(font
					(size 1 1)
					(thickness 0.15)
				)
				(justify mirror)
			)
		)
		(property "Dielectric" "X5R"
			(at 0 0 270)
			(unlocked yes)
			(layer "B.Fab")
			(hide yes)
			(effects
				(font
					(size 1 1)
					(thickness 0.15)
				)
				(justify mirror)
			)
		)
		(property "Manufacturer" "Murata"
			(at 0 0 270)
			(unlocked yes)
			(layer "B.Fab")
			(hide yes)
			(effects
				(font
					(size 1 1)
					(thickness 0.15)
				)
				(justify mirror)
			)
		)
		(property "License" "Apache-2.0"
			(at 0 0 270)
			(unlocked yes)
			(layer "B.Fab")
			(hide yes)
			(effects
				(font
					(size 1 1)
					(thickness 0.15)
				)
				(justify mirror)
			)
		)
		(property "Author" "Antmicro"
			(at 0 0 270)
			(unlocked yes)
			(layer "B.Fab")
			(hide yes)
			(effects
				(font
					(size 1 1)
					(thickness 0.15)
				)
				(justify mirror)
			)
		)
		(sheetname "/X710-AT2 power/")
		(sheetfile "x710-at2-power.kicad_sch")
		(attr smd)
		(fp_rect
			(start -0.925 0.47)
			(end 0.925 -0.47)
			(stroke
				(width 0.05)
				(type default)
			)
			(fill no)
			(layer "B.CrtYd")
		)
		(fp_line
			(start -0.494 0.25)
			(end 0.504 0.25)
			(stroke
				(width 0.15)
				(type solid)
			)
			(layer "B.Fab")
		)
		(fp_line
			(start 0.504 0.25)
			(end 0.504 -0.248)
			(stroke
				(width 0.15)
				(type solid)
			)
			(layer "B.Fab")
		)
		(fp_line
			(start -0.494 -0.248)
			(end -0.494 0.25)
			(stroke
				(width 0.15)
				(type solid)
			)
			(layer "B.Fab")
		)
		(fp_line
			(start 0.504 -0.248)
			(end -0.494 -0.248)
			(stroke
				(width 0.15)
				(type solid)
			)
			(layer "B.Fab")
		)
		(fp_text user "License: Apache-2.0"
			(at -0.939 -5.799 90)
			(layer "B.Fab")
			(effects
				(font
					(size 0.7 0.7)
					(thickness 0.15)
				)
				(justify left bottom mirror)
			)
		)
		(fp_text user "Author: Antmicro"
			(at -0.939 -3.399 90)
			(layer "B.Fab")
			(effects
				(font
					(size 0.7 0.7)
					(thickness 0.15)
				)
				(justify left bottom mirror)
			)
		)
		(fp_text user "${REFERENCE}"
			(at -0.939 -4.599 90)
			(layer "B.Fab")
			(effects
				(font
					(size 0.7 0.7)
					(thickness 0.15)
				)
				(justify left bottom mirror)
			)
		)
		(pad "1" smd roundrect
			(at -0.48 0 270)
			(size 0.59 0.64)
			(layers "B.Cu" "B.Mask" "B.Paste")
			(roundrect_rratio 0.25)
			(net 23 "GND")
			(pintype "passive")
		)
		(pad "2" smd roundrect
			(at 0.48 0 270)
			(size 0.59 0.64)
			(layers "B.Cu" "B.Mask" "B.Paste")
			(roundrect_rratio 0.25)
			(net 136 "+1V0")
			(pintype "passive")
		)
	)
	(footprint "antmicro-footprints:C_0402_1005Metric"
		(layer "B.Cu")
		(at 126.25 134.75 90)
		(descr "Capacitor SMD 0402")
		(tags "capacitor SMD 0402")
		(property "Reference" "C37"
			(at -1.25 0.5 270)
			(layer "B.SilkS")
			(effects
				(font
					(size 0.7 0.7)
					(thickness 0.15)
				)
				(justify left bottom mirror)
			)
		)
		(property "Value" "C_220n_0402"
			(at -1.022927 -2.155213 270)
			(layer "B.Fab")
			(effects
				(font
					(size 0.7 0.7)
					(thickness 0.15)
				)
				(justify left bottom mirror)
			)
		)
		(property "Datasheet" "https://www.yageo.com/en/Chart/Download/pdf/CC0402KRX5R6BB224"
			(at 0 0 270)
			(layer "B.Fab")
			(hide yes)
			(effects
				(font
					(size 1.27 1.27)
					(thickness 0.15)
				)
				(justify mirror)
			)
		)
		(property "Description" "SMD Multilayer Ceramic Capacitor, 0.22 µF, 10 V, 0402 [1005 Metric], ± 10%, X5R, CC Series"
			(at 0 0 270)
			(layer "B.Fab")
			(hide yes)
			(effects
				(font
					(size 1.27 1.27)
					(thickness 0.15)
				)
				(justify mirror)
			)
		)
		(property "MPN" "CC0402KRX5R6BB224"
			(at 0 0 90)
			(unlocked yes)
			(layer "B.Fab")
			(hide yes)
			(effects
				(font
					(size 1 1)
					(thickness 0.15)
				)
				(justify mirror)
			)
		)
		(property "Manufacturer" "YAGEO"
			(at 0 0 90)
			(unlocked yes)
			(layer "B.Fab")
			(hide yes)
			(effects
				(font
					(size 1 1)
					(thickness 0.15)
				)
				(justify mirror)
			)
		)
		(property "License" "Apache-2.0"
			(at 0 0 90)
			(unlocked yes)
			(layer "B.Fab")
			(hide yes)
			(effects
				(font
					(size 1 1)
					(thickness 0.15)
				)
				(justify mirror)
			)
		)
		(property "Val" "220n"
			(at 0 0 90)
			(unlocked yes)
			(layer "B.Fab")
			(hide yes)
			(effects
				(font
					(size 1 1)
					(thickness 0.15)
				)
				(justify mirror)
			)
		)
		(property "Voltage" ""
			(at 0 0 90)
			(unlocked yes)
			(layer "B.Fab")
			(hide yes)
			(effects
				(font
					(size 1 1)
					(thickness 0.15)
				)
				(justify mirror)
			)
		)
		(property "Dielectric" ""
			(at 0 0 90)
			(unlocked yes)
			(layer "B.Fab")
			(hide yes)
			(effects
				(font
					(size 1 1)
					(thickness 0.15)
				)
				(justify mirror)
			)
		)
		(property "Author" "Antmicro"
			(at 0 0 90)
			(unlocked yes)
			(layer "B.Fab")
			(hide yes)
			(effects
				(font
					(size 1 1)
					(thickness 0.15)
				)
				(justify mirror)
			)
		)
		(sheetname "/TB Controller/")
		(sheetfile "tb.kicad_sch")
		(attr smd)
		(fp_rect
			(start -0.925 0.47)
			(end 0.925 -0.47)
			(stroke
				(width 0.05)
				(type default)
			)
			(fill no)
			(layer "B.CrtYd")
		)
		(fp_line
			(start 0.504 -0.248)
			(end -0.494 -0.248)
			(stroke
				(width 0.15)
				(type solid)
			)
			(layer "B.Fab")
		)
		(fp_line
			(start -0.494 -0.248)
			(end -0.494 0.25)
			(stroke
				(width 0.15)
				(type solid)
			)
			(layer "B.Fab")
		)
		(fp_line
			(start 0.504 0.25)
			(end 0.504 -0.248)
			(stroke
				(width 0.15)
				(type solid)
			)
			(layer "B.Fab")
		)
		(fp_line
			(start -0.494 0.25)
			(end 0.504 0.25)
			(stroke
				(width 0.15)
				(type solid)
			)
			(layer "B.Fab")
		)
		(fp_text user "Author: Antmicro"
			(at -0.939 -3.399 270)
			(layer "B.Fab")
			(effects
				(font
					(size 0.7 0.7)
					(thickness 0.15)
				)
				(justify left bottom mirror)
			)
		)
		(fp_text user "License: Apache-2.0"
			(at -0.939 -5.799 270)
			(layer "B.Fab")
			(effects
				(font
					(size 0.7 0.7)
					(thickness 0.15)
				)
				(justify left bottom mirror)
			)
		)
		(fp_text user "${REFERENCE}"
			(at -0.939 -4.599 270)
			(layer "B.Fab")
			(effects
				(font
					(size 0.7 0.7)
					(thickness 0.15)
				)
				(justify left bottom mirror)
			)
		)
		(pad "1" smd roundrect
			(at -0.48 0 90)
			(size 0.59 0.64)
			(layers "B.Cu" "B.Mask" "B.Paste")
			(roundrect_rratio 0.25)
			(net 312 "/PD and TB DC-DC/USB3.TX1_N")
			(pintype "passive")
		)
		(pad "2" smd roundrect
			(at 0.48 0 90)
			(size 0.59 0.64)
			(layers "B.Cu" "B.Mask" "B.Paste")
			(roundrect_rratio 0.25)
			(net 174 "/TB Controller/PA_TX1_N")
			(pintype "passive")
		)
	)
	(footprint "antmicro-footprints:TP_SMD_0.75mm"
		(layer "B.Cu")
		(at 155.231866 62.935117 180)
		(property "Reference" "TP21"
			(at -0.368134 3.135117 270)
			(layer "B.SilkS")
			(effects
				(font
					(size 0.7 0.7)
					(thickness 0.15)
				)
				(justify left bottom mirror)
			)
		)
		(property "Value" "TP_0.75mm_SMD"
			(at 0 -1.2 0)
			(layer "B.Fab")
			(effects
				(font
					(size 0.7 0.7)
					(thickness 0.15)
				)
				(justify left bottom mirror)
			)
		)
		(property "Description" "SMT test point"
			(at 0 0 0)
			(layer "B.Fab")
			(hide yes)
			(effects
				(font
					(size 1.27 1.27)
					(thickness 0.15)
				)
				(justify mirror)
			)
		)
		(property "MPN" ""
			(at 0 0 180)
			(unlocked yes)
			(layer "B.Fab")
			(hide yes)
			(effects
				(font
					(size 1 1)
					(thickness 0.15)
				)
				(justify mirror)
			)
		)
		(property "Manufacturer" ""
			(at 0 0 180)
			(unlocked yes)
			(layer "B.Fab")
			(hide yes)
			(effects
				(font
					(size 1 1)
					(thickness 0.15)
				)
				(justify mirror)
			)
		)
		(property "Author" "Antmicro"
			(at 0 0 180)
			(unlocked yes)
			(layer "B.Fab")
			(hide yes)
			(effects
				(font
					(size 1 1)
					(thickness 0.15)
				)
				(justify mirror)
			)
		)
		(property "License" "Apache-2.0"
			(at 0 0 180)
			(unlocked yes)
			(layer "B.Fab")
			(hide yes)
			(effects
				(font
					(size 1 1)
					(thickness 0.15)
				)
				(justify mirror)
			)
		)
		(sheetname "/X710-AT2 Misc/")
		(sheetfile "x710-at2-mics.kicad_sch")
		(attr exclude_from_pos_files exclude_from_bom)
		(fp_circle
			(center 0 0)
			(end 0.475 0)
			(stroke
				(width 0.05)
				(type default)
			)
			(fill no)
			(layer "B.CrtYd")
		)
		(fp_text user "License: Apache-2.0"
			(at -0.4 -5.101 0)
			(layer "B.Fab")
			(effects
				(font
					(size 0.7 0.7)
					(thickness 0.15)
				)
				(justify left bottom mirror)
			)
		)
		(fp_text user "${REFERENCE}"
			(at -0.4 -2.7 0)
			(layer "B.Fab")
			(effects
				(font
					(size 0.7 0.7)
					(thickness 0.15)
				)
				(justify left bottom mirror)
			)
		)
		(fp_text user "Author: Antmicro"
			(at -0.4 -3.901 0)
			(layer "B.Fab")
			(effects
				(font
					(size 0.7 0.7)
					(thickness 0.15)
				)
				(justify left bottom mirror)
			)
		)
		(pad "1" smd circle
			(at 0 0 180)
			(size 0.75 0.75)
			(layers "B.Cu" "B.Mask")
			(net 145 "/X710-AT2 Misc/NCSI.ARB_IN")
			(pinfunction "1")
			(pintype "passive")
		)
	)
	(footprint "antmicro-footprints:R_0402_1005Metric"
		(layer "B.Cu")
		(at 129.9 131.1 90)
		(descr "Resistor SMD 0402")
		(tags "resistor SMD 0402")
		(property "Reference" "R55"
			(at 8.1 20.250001 270)
			(layer "B.SilkS")
			(effects
				(font
					(size 0.7 0.7)
					(thickness 0.15)
				)
				(justify mirror)
			)
		)
		(property "Value" "R_1M_0402"
			(at -1.011843 -1.772047 270)
			(layer "B.Fab")
			(effects
				(font
					(size 0.7 0.7)
					(thickness 0.15)
				)
				(justify left bottom mirror)
			)
		)
		(property "Datasheet" "https://www.bourns.com/docs/product-datasheets/cr.pdf"
			(at 0 0 270)
			(layer "B.Fab")
			(hide yes)
			(effects
				(font
					(size 1.27 1.27)
					(thickness 0.15)
				)
				(justify mirror)
			)
		)
		(property "Description" "SMD Chip Resistor, 1 Mohm, ± 1%, 62.5 mW, 0402 [1005 Metric], Thick Film, General Purpose"
			(at 0 0 270)
			(layer "B.Fab")
			(hide yes)
			(effects
				(font
					(size 1.27 1.27)
					(thickness 0.15)
				)
				(justify mirror)
			)
		)
		(property "MPN" "CR0402-FX-1004GLF"
			(at 0 0 90)
			(unlocked yes)
			(layer "B.Fab")
			(hide yes)
			(effects
				(font
					(size 1 1)
					(thickness 0.15)
				)
				(justify mirror)
			)
		)
		(property "Manufacturer" "Bourns"
			(at 0 0 90)
			(unlocked yes)
			(layer "B.Fab")
			(hide yes)
			(effects
				(font
					(size 1 1)
					(thickness 0.15)
				)
				(justify mirror)
			)
		)
		(property "License" "Apache-2.0"
			(at 0 0 90)
			(unlocked yes)
			(layer "B.Fab")
			(hide yes)
			(effects
				(font
					(size 1 1)
					(thickness 0.15)
				)
				(justify mirror)
			)
		)
		(property "Val" "1M"
			(at 0 0 90)
			(unlocked yes)
			(layer "B.Fab")
			(hide yes)
			(effects
				(font
					(size 1 1)
					(thickness 0.15)
				)
				(justify mirror)
			)
		)
		(property "Tolerance" "1%"
			(at 0 0 90)
			(unlocked yes)
			(layer "B.Fab")
			(hide yes)
			(effects
				(font
					(size 1 1)
					(thickness 0.15)
				)
				(justify mirror)
			)
		)
		(property "Author" "Antmicro"
			(at 0 0 90)
			(unlocked yes)
			(layer "B.Fab")
			(hide yes)
			(effects
				(font
					(size 1 1)
					(thickness 0.15)
				)
				(justify mirror)
			)
		)
		(sheetname "/TB Controller/")
		(sheetfile "tb.kicad_sch")
		(attr smd)
		(fp_rect
			(start -0.925 0.47)
			(end 0.925 -0.47)
			(stroke
				(width 0.05)
				(type default)
			)
			(fill no)
			(layer "B.CrtYd")
		)
		(fp_rect
			(start -0.5 0.25)
			(end 0.5 -0.25)
			(stroke
				(width 0.15)
				(type solid)
			)
			(fill no)
			(layer "B.Fab")
		)
		(fp_text user "License: Apache-2.0"
			(at -0.95 -5.169 270)
			(layer "B.Fab")
			(effects
				(font
					(size 0.7 0.7)
					(thickness 0.15)
				)
				(justify left bottom mirror)
			)
		)
		(fp_text user "Author: Antmicro"
			(at -0.95 -4.169 270)
			(layer "B.Fab")
			(effects
				(font
					(size 0.7 0.7)
					(thickness 0.15)
				)
				(justify left bottom mirror)
			)
		)
		(fp_text user "${REFERENCE}"
			(at -0.95 -3.168 270)
			(layer "B.Fab")
			(effects
				(font
					(size 0.7 0.7)
					(thickness 0.15)
				)
				(justify left bottom mirror)
			)
		)
		(pad "1" smd roundrect
			(at -0.48 0 90)
			(size 0.59 0.64)
			(layers "B.Cu" "B.Mask" "B.Paste")
			(roundrect_rratio 0.25)
			(net 23 "GND")
			(pintype "passive")
		)
		(pad "2" smd roundrect
			(at 0.48 0 90)
			(size 0.59 0.64)
			(layers "B.Cu" "B.Mask" "B.Paste")
			(roundrect_rratio 0.25)
			(net 383 "/PD and TB DC-DC/LSX_1.LSX_R2P")
			(pintype "passive")
		)
	)
	(footprint "antmicro-footprints:Fiducial_1mm_Mask2mm"
		(layer "B.Cu")
		(at 130.5 151.5 180)
		(descr "Circular Fiducial, 1mm bare copper, 3mm soldermask opening")
		(tags "fiducial")
		(property "Reference" "FD8"
			(at 1.25 -0.25 0)
			(layer "B.SilkS")
			(effects
				(font
					(size 0.7 0.7)
					(thickness 0.15)
				)
				(justify left bottom mirror)
			)
		)
		(property "Value" "Fiducial_1mm_Mask2mm"
			(at 0 -2.2 0)
			(layer "B.Fab")
			(effects
				(font
					(size 0.7 0.7)
					(thickness 0.15)
				)
				(justify left bottom mirror)
			)
		)
		(property "Description" "Fiducial mask"
			(at 0 0 0)
			(layer "B.Fab")
			(hide yes)
			(effects
				(font
					(size 1.27 1.27)
					(thickness 0.15)
				)
				(justify mirror)
			)
		)
		(property "Author" "Antmicro"
			(at 0 0 180)
			(unlocked yes)
			(layer "B.Fab")
			(hide yes)
			(effects
				(font
					(size 1 1)
					(thickness 0.15)
				)
				(justify mirror)
			)
		)
		(property "License" "Apache-2.0"
			(at 0 0 180)
			(unlocked yes)
			(layer "B.Fab")
			(hide yes)
			(effects
				(font
					(size 1 1)
					(thickness 0.15)
				)
				(justify mirror)
			)
		)
		(sheetname "/")
		(sheetfile "thunderbolt-to-10gbe-adapter.kicad_sch")
		(attr exclude_from_pos_files exclude_from_bom)
		(fp_circle
			(center 0 0)
			(end 1.24 0)
			(stroke
				(width 0.05)
				(type solid)
			)
			(fill no)
			(layer "B.CrtYd")
		)
		(fp_circle
			(center 0 0)
			(end 0.999 0)
			(stroke
				(width 0.15)
				(type solid)
			)
			(fill no)
			(layer "B.Fab")
		)
		(fp_text user "Author: Antmicro"
			(at -1.25 -5.803 0)
			(layer "B.Fab")
			(effects
				(font
					(size 0.7 0.7)
					(thickness 0.15)
				)
				(justify left bottom mirror)
			)
		)
		(fp_text user "License: Apache-2.0"
			(at -1.25 -7.003 0)
			(layer "B.Fab")
			(effects
				(font
					(size 0.7 0.7)
					(thickness 0.15)
				)
				(justify left bottom mirror)
			)
		)
		(fp_text user "${REFERENCE}"
			(at -1.25 -4.603 0)
			(layer "B.Fab")
			(effects
				(font
					(size 0.7 0.7)
					(thickness 0.15)
				)
				(justify left bottom mirror)
			)
		)
		(pad "" smd circle
			(at 0 0 180)
			(size 1 1)
			(layers "B.Cu" "B.Mask")
			(solder_mask_margin 0.5)
			(clearance 0.5)
		)
	)
	(footprint "antmicro-footprints:R_0402_1005Metric"
		(layer "B.Cu")
		(at 180.8 70)
		(descr "Resistor SMD 0402")
		(tags "resistor SMD 0402")
		(property "Reference" "R83"
			(at 3 0.4 180)
			(layer "B.SilkS")
			(effects
				(font
					(size 0.7 0.7)
					(thickness 0.15)
				)
				(justify left bottom mirror)
			)
		)
		(property "Value" "R_330R_0402"
			(at -1.011843 -1.772047 180)
			(layer "B.Fab")
			(effects
				(font
					(size 0.7 0.7)
					(thickness 0.15)
				)
				(justify left bottom mirror)
			)
		)
		(property "Datasheet" "https://www.bourns.com/docs/product-datasheets/cr.pdf"
			(at 0 0 180)
			(layer "B.Fab")
			(hide yes)
			(effects
				(font
					(size 1.27 1.27)
					(thickness 0.15)
				)
				(justify mirror)
			)
		)
		(property "Description" "SMD Chip Resistor, 330 ohm, ± 1%, 62.5 mW, 0402 [1005 Metric], Thick Film, General Purpose"
			(at 0 0 180)
			(layer "B.Fab")
			(hide yes)
			(effects
				(font
					(size 1.27 1.27)
					(thickness 0.15)
				)
				(justify mirror)
			)
		)
		(property "MPN" "CR0402-FX-3300GLF"
			(at 0 0 0)
			(unlocked yes)
			(layer "B.Fab")
			(hide yes)
			(effects
				(font
					(size 1 1)
					(thickness 0.15)
				)
				(justify mirror)
			)
		)
		(property "Manufacturer" "Bourns"
			(at 0 0 0)
			(unlocked yes)
			(layer "B.Fab")
			(hide yes)
			(effects
				(font
					(size 1 1)
					(thickness 0.15)
				)
				(justify mirror)
			)
		)
		(property "License" "Apache-2.0"
			(at 0 0 0)
			(unlocked yes)
			(layer "B.Fab")
			(hide yes)
			(effects
				(font
					(size 1 1)
					(thickness 0.15)
				)
				(justify mirror)
			)
		)
		(property "Author" "Antmicro"
			(at 0 0 0)
			(unlocked yes)
			(layer "B.Fab")
			(hide yes)
			(effects
				(font
					(size 1 1)
					(thickness 0.15)
				)
				(justify mirror)
			)
		)
		(property "Val" "330R"
			(at 0 0 0)
			(unlocked yes)
			(layer "B.Fab")
			(hide yes)
			(effects
				(font
					(size 1 1)
					(thickness 0.15)
				)
				(justify mirror)
			)
		)
		(property "Tolerance" "1%"
			(at 0 0 0)
			(unlocked yes)
			(layer "B.Fab")
			(hide yes)
			(effects
				(font
					(size 1 1)
					(thickness 0.15)
				)
				(justify mirror)
			)
		)
		(sheetname "/X710 DCDC converters/")
		(sheetfile "DCDC_converters_X710.kicad_sch")
		(attr smd)
		(fp_rect
			(start -0.925 0.47)
			(end 0.925 -0.47)
			(stroke
				(width 0.05)
				(type default)
			)
			(fill no)
			(layer "B.CrtYd")
		)
		(fp_rect
			(start -0.5 0.25)
			(end 0.5 -0.25)
			(stroke
				(width 0.15)
				(type solid)
			)
			(fill no)
			(layer "B.Fab")
		)
		(fp_text user "Author: Antmicro"
			(at -0.95 -4.169 180)
			(layer "B.Fab")
			(effects
				(font
					(size 0.7 0.7)
					(thickness 0.15)
				)
				(justify left bottom mirror)
			)
		)
		(fp_text user "${REFERENCE}"
			(at -0.95 -3.168 180)
			(layer "B.Fab")
			(effects
				(font
					(size 0.7 0.7)
					(thickness 0.15)
				)
				(justify left bottom mirror)
			)
		)
		(fp_text user "License: Apache-2.0"
			(at -0.95 -5.169 180)
			(layer "B.Fab")
			(effects
				(font
					(size 0.7 0.7)
					(thickness 0.15)
				)
				(justify left bottom mirror)
			)
		)
		(pad "1" smd roundrect
			(at -0.48 0)
			(size 0.59 0.64)
			(layers "B.Cu" "B.Mask" "B.Paste")
			(roundrect_rratio 0.25)
			(net 23 "GND")
			(pintype "passive")
		)
		(pad "2" smd roundrect
			(at 0.48 0)
			(size 0.59 0.64)
			(layers "B.Cu" "B.Mask" "B.Paste")
			(roundrect_rratio 0.25)
			(net 414 "Net-(D6-C)")
			(pintype "passive")
		)
	)
	(footprint "antmicro-footprints:C_0402_1005Metric"
		(layer "B.Cu")
		(at 126.549999 124.075 90)
		(descr "Capacitor SMD 0402")
		(tags "capacitor SMD 0402")
		(property "Reference" "C57"
			(at 7.700002 21.900002 270)
			(layer "B.SilkS")
			(effects
				(font
					(size 0.7 0.7)
					(thickness 0.15)
				)
				(justify mirror)
			)
		)
		(property "Value" "C_1u_0402"
			(at -1.022927 -2.155213 270)
			(layer "B.Fab")
			(effects
				(font
					(size 0.7 0.7)
					(thickness 0.15)
				)
				(justify left bottom mirror)
			)
		)
		(property "Datasheet" "https://product.tdk.com/en/search/capacitor/ceramic/mlcc/info?part_no=C1005X6S1A105K050BC"
			(at 0 0 270)
			(layer "B.Fab")
			(hide yes)
			(effects
				(font
					(size 1.27 1.27)
					(thickness 0.15)
				)
				(justify mirror)
			)
		)
		(property "Description" "SMD Multilayer Ceramic Capacitor, 1 µF, 10 V, 0402 [1005 Metric], ± 10%, X6S, C"
			(at 0 0 270)
			(layer "B.Fab")
			(hide yes)
			(effects
				(font
					(size 1.27 1.27)
					(thickness 0.15)
				)
				(justify mirror)
			)
		)
		(property "MPN" "C1005X6S1A105K050BC"
			(at 0 0 90)
			(unlocked yes)
			(layer "B.Fab")
			(hide yes)
			(effects
				(font
					(size 1 1)
					(thickness 0.15)
				)
				(justify mirror)
			)
		)
		(property "Manufacturer" "TDK"
			(at 0 0 90)
			(unlocked yes)
			(layer "B.Fab")
			(hide yes)
			(effects
				(font
					(size 1 1)
					(thickness 0.15)
				)
				(justify mirror)
			)
		)
		(property "License" "Apache-2.0"
			(at 0 0 90)
			(unlocked yes)
			(layer "B.Fab")
			(hide yes)
			(effects
				(font
					(size 1 1)
					(thickness 0.15)
				)
				(justify mirror)
			)
		)
		(property "Val" "1u"
			(at 0 0 90)
			(unlocked yes)
			(layer "B.Fab")
			(hide yes)
			(effects
				(font
					(size 1 1)
					(thickness 0.15)
				)
				(justify mirror)
			)
		)
		(property "Voltage" ""
			(at 0 0 90)
			(unlocked yes)
			(layer "B.Fab")
			(hide yes)
			(effects
				(font
					(size 1 1)
					(thickness 0.15)
				)
				(justify mirror)
			)
		)
		(property "Dielectric" ""
			(at 0 0 90)
			(unlocked yes)
			(layer "B.Fab")
			(hide yes)
			(effects
				(font
					(size 1 1)
					(thickness 0.15)
				)
				(justify mirror)
			)
		)
		(property "Author" "Antmicro"
			(at 0 0 90)
			(unlocked yes)
			(layer "B.Fab")
			(hide yes)
			(effects
				(font
					(size 1 1)
					(thickness 0.15)
				)
				(justify mirror)
			)
		)
		(sheetname "/TB Controller - Power/")
		(sheetfile "tb-power.kicad_sch")
		(attr smd)
		(fp_rect
			(start -0.925 0.47)
			(end 0.925 -0.47)
			(stroke
				(width 0.05)
				(type default)
			)
			(fill no)
			(layer "B.CrtYd")
		)
		(fp_line
			(start 0.504 -0.248)
			(end -0.494 -0.248)
			(stroke
				(width 0.15)
				(type solid)
			)
			(layer "B.Fab")
		)
		(fp_line
			(start -0.494 -0.248)
			(end -0.494 0.25)
			(stroke
				(width 0.15)
				(type solid)
			)
			(layer "B.Fab")
		)
		(fp_line
			(start 0.504 0.25)
			(end 0.504 -0.248)
			(stroke
				(width 0.15)
				(type solid)
			)
			(layer "B.Fab")
		)
		(fp_line
			(start -0.494 0.25)
			(end 0.504 0.25)
			(stroke
				(width 0.15)
				(type solid)
			)
			(layer "B.Fab")
		)
		(fp_text user "Author: Antmicro"
			(at -0.939 -3.399 270)
			(layer "B.Fab")
			(effects
				(font
					(size 0.7 0.7)
					(thickness 0.15)
				)
				(justify left bottom mirror)
			)
		)
		(fp_text user "License: Apache-2.0"
			(at -0.939 -5.799 270)
			(layer "B.Fab")
			(effects
				(font
					(size 0.7 0.7)
					(thickness 0.15)
				)
				(justify left bottom mirror)
			)
		)
		(fp_text user "${REFERENCE}"
			(at -0.939 -4.599 270)
			(layer "B.Fab")
			(effects
				(font
					(size 0.7 0.7)
					(thickness 0.15)
				)
				(justify left bottom mirror)
			)
		)
		(pad "1" smd roundrect
			(at -0.48 0 90)
			(size 0.59 0.64)
			(layers "B.Cu" "B.Mask" "B.Paste")
			(roundrect_rratio 0.25)
			(net 23 "GND")
			(pintype "passive")
		)
		(pad "2" smd roundrect
			(at 0.48 0 90)
			(size 0.59 0.64)
			(layers "B.Cu" "B.Mask" "B.Paste")
			(roundrect_rratio 0.25)
			(net 403 "Net-(C55-Pad2)")
			(pintype "passive")
		)
	)
	(footprint "antmicro-footprints:C_0402_1005Metric"
		(layer "B.Cu")
		(at 132.860001 133 90)
		(descr "Capacitor SMD 0402")
		(tags "capacitor SMD 0402")
		(property "Reference" "C20"
			(at 8.339997 19.525001 270)
			(layer "B.SilkS")
			(effects
				(font
					(size 0.7 0.7)
					(thickness 0.15)
				)
				(justify mirror)
			)
		)
		(property "Value" "C_2u2_0402"
			(at -1.022927 -2.155213 270)
			(layer "B.Fab")
			(effects
				(font
					(size 0.7 0.7)
					(thickness 0.15)
				)
				(justify left bottom mirror)
			)
		)
		(property "Datasheet" "https://product.tdk.com/en/search/capacitor/ceramic/mlcc/info?part_no=C1005X5R1A225K050BC"
			(at 0 0 270)
			(layer "B.Fab")
			(hide yes)
			(effects
				(font
					(size 1.27 1.27)
					(thickness 0.15)
				)
				(justify mirror)
			)
		)
		(property "Description" "SMD Multilayer Ceramic Capacitor, 2.2 µF, 10 V, 0402 [1005 Metric], ± 10%, X5R, C"
			(at 0 0 270)
			(layer "B.Fab")
			(hide yes)
			(effects
				(font
					(size 1.27 1.27)
					(thickness 0.15)
				)
				(justify mirror)
			)
		)
		(property "MPN" "C1005X5R1A225K050BC"
			(at 0 0 90)
			(unlocked yes)
			(layer "B.Fab")
			(hide yes)
			(effects
				(font
					(size 1 1)
					(thickness 0.15)
				)
				(justify mirror)
			)
		)
		(property "Manufacturer" "TDK"
			(at 0 0 90)
			(unlocked yes)
			(layer "B.Fab")
			(hide yes)
			(effects
				(font
					(size 1 1)
					(thickness 0.15)
				)
				(justify mirror)
			)
		)
		(property "License" "Apache-2.0"
			(at 0 0 90)
			(unlocked yes)
			(layer "B.Fab")
			(hide yes)
			(effects
				(font
					(size 1 1)
					(thickness 0.15)
				)
				(justify mirror)
			)
		)
		(property "Val" "2u2"
			(at 0 0 90)
			(unlocked yes)
			(layer "B.Fab")
			(hide yes)
			(effects
				(font
					(size 1 1)
					(thickness 0.15)
				)
				(justify mirror)
			)
		)
		(property "Voltage" ""
			(at 0 0 90)
			(unlocked yes)
			(layer "B.Fab")
			(hide yes)
			(effects
				(font
					(size 1 1)
					(thickness 0.15)
				)
				(justify mirror)
			)
		)
		(property "Dielectric" ""
			(at 0 0 90)
			(unlocked yes)
			(layer "B.Fab")
			(hide yes)
			(effects
				(font
					(size 1 1)
					(thickness 0.15)
				)
				(justify mirror)
			)
		)
		(property "Author" "Antmicro"
			(at 0 0 90)
			(unlocked yes)
			(layer "B.Fab")
			(hide yes)
			(effects
				(font
					(size 1 1)
					(thickness 0.15)
				)
				(justify mirror)
			)
		)
		(sheetname "/PD and TB DC-DC/")
		(sheetfile "PD_and_TB_DC_DC.kicad_sch")
		(attr smd)
		(fp_rect
			(start -0.925 0.47)
			(end 0.925 -0.47)
			(stroke
				(width 0.05)
				(type default)
			)
			(fill no)
			(layer "B.CrtYd")
		)
		(fp_line
			(start 0.504 -0.248)
			(end -0.494 -0.248)
			(stroke
				(width 0.15)
				(type solid)
			)
			(layer "B.Fab")
		)
		(fp_line
			(start -0.494 -0.248)
			(end -0.494 0.25)
			(stroke
				(width 0.15)
				(type solid)
			)
			(layer "B.Fab")
		)
		(fp_line
			(start 0.504 0.25)
			(end 0.504 -0.248)
			(stroke
				(width 0.15)
				(type solid)
			)
			(layer "B.Fab")
		)
		(fp_line
			(start -0.494 0.25)
			(end 0.504 0.25)
			(stroke
				(width 0.15)
				(type solid)
			)
			(layer "B.Fab")
		)
		(fp_text user "Author: Antmicro"
			(at -0.939 -3.399 270)
			(layer "B.Fab")
			(effects
				(font
					(size 0.7 0.7)
					(thickness 0.15)
				)
				(justify left bottom mirror)
			)
		)
		(fp_text user "License: Apache-2.0"
			(at -0.939 -5.799 270)
			(layer "B.Fab")
			(effects
				(font
					(size 0.7 0.7)
					(thickness 0.15)
				)
				(justify left bottom mirror)
			)
		)
		(fp_text user "${REFERENCE}"
			(at -0.939 -4.599 270)
			(layer "B.Fab")
			(effects
				(font
					(size 0.7 0.7)
					(thickness 0.15)
				)
				(justify left bottom mirror)
			)
		)
		(pad "1" smd roundrect
			(at -0.48 0 90)
			(size 0.59 0.64)
			(layers "B.Cu" "B.Mask" "B.Paste")
			(roundrect_rratio 0.25)
			(net 172 "Net-(U3-LDO_1V8A)")
			(pintype "passive")
		)
		(pad "2" smd roundrect
			(at 0.48 0 90)
			(size 0.59 0.64)
			(layers "B.Cu" "B.Mask" "B.Paste")
			(roundrect_rratio 0.25)
			(net 23 "GND")
			(pintype "passive")
		)
	)
	(footprint "antmicro-footprints:C_0402_1005Metric"
		(layer "B.Cu")
		(at 145.631866 80.260117 180)
		(descr "Capacitor SMD 0402")
		(tags "capacitor SMD 0402")
		(property "Reference" "C240"
			(at -17.768134 -9.464883 0)
			(layer "B.SilkS")
			(effects
				(font
					(size 0.7 0.7)
					(thickness 0.15)
				)
				(justify mirror)
			)
		)
		(property "Value" "C_1u_25V_0402"
			(at -1.022927 -2.155213 0)
			(layer "B.Fab")
			(effects
				(font
					(size 0.7 0.7)
					(thickness 0.15)
				)
				(justify left bottom mirror)
			)
		)
		(property "Datasheet" "https://www.murata.com/products/productdetail?partno=GRM155R61E105KE11%23"
			(at 0 0 0)
			(layer "B.Fab")
			(hide yes)
			(effects
				(font
					(size 1.27 1.27)
					(thickness 0.15)
				)
				(justify mirror)
			)
		)
		(property "Description" "SMD Multilayer Ceramic Capacitor, 1 µF, 25 V, 0402 [1005 Metric], ± 10%, X5R, GRM Series"
			(at 0 0 0)
			(layer "B.Fab")
			(hide yes)
			(effects
				(font
					(size 1.27 1.27)
					(thickness 0.15)
				)
				(justify mirror)
			)
		)
		(property "MPN" "GRM155R61E105KE11J"
			(at 0 0 180)
			(unlocked yes)
			(layer "B.Fab")
			(hide yes)
			(effects
				(font
					(size 1 1)
					(thickness 0.15)
				)
				(justify mirror)
			)
		)
		(property "Manufacturer" "Murata"
			(at 0 0 180)
			(unlocked yes)
			(layer "B.Fab")
			(hide yes)
			(effects
				(font
					(size 1 1)
					(thickness 0.15)
				)
				(justify mirror)
			)
		)
		(property "License" "Apache-2.0"
			(at 0 0 180)
			(unlocked yes)
			(layer "B.Fab")
			(hide yes)
			(effects
				(font
					(size 1 1)
					(thickness 0.15)
				)
				(justify mirror)
			)
		)
		(property "Author" "Antmicro"
			(at 0 0 180)
			(unlocked yes)
			(layer "B.Fab")
			(hide yes)
			(effects
				(font
					(size 1 1)
					(thickness 0.15)
				)
				(justify mirror)
			)
		)
		(property "Val" "1u"
			(at 0 0 180)
			(unlocked yes)
			(layer "B.Fab")
			(hide yes)
			(effects
				(font
					(size 1 1)
					(thickness 0.15)
				)
				(justify mirror)
			)
		)
		(property "Voltage" "25V"
			(at 0 0 180)
			(unlocked yes)
			(layer "B.Fab")
			(hide yes)
			(effects
				(font
					(size 1 1)
					(thickness 0.15)
				)
				(justify mirror)
			)
		)
		(property "Dielectric" "X5R"
			(at 0 0 180)
			(unlocked yes)
			(layer "B.Fab")
			(hide yes)
			(effects
				(font
					(size 1 1)
					(thickness 0.15)
				)
				(justify mirror)
			)
		)
		(sheetname "/X710-AT2 power/")
		(sheetfile "x710-at2-power.kicad_sch")
		(attr smd)
		(fp_rect
			(start -0.925 0.47)
			(end 0.925 -0.47)
			(stroke
				(width 0.05)
				(type default)
			)
			(fill no)
			(layer "B.CrtYd")
		)
		(fp_line
			(start 0.504 0.25)
			(end 0.504 -0.248)
			(stroke
				(width 0.15)
				(type solid)
			)
			(layer "B.Fab")
		)
		(fp_line
			(start 0.504 -0.248)
			(end -0.494 -0.248)
			(stroke
				(width 0.15)
				(type solid)
			)
			(layer "B.Fab")
		)
		(fp_line
			(start -0.494 0.25)
			(end 0.504 0.25)
			(stroke
				(width 0.15)
				(type solid)
			)
			(layer "B.Fab")
		)
		(fp_line
			(start -0.494 -0.248)
			(end -0.494 0.25)
			(stroke
				(width 0.15)
				(type solid)
			)
			(layer "B.Fab")
		)
		(fp_text user "${REFERENCE}"
			(at -0.939 -4.599 0)
			(layer "B.Fab")
			(effects
				(font
					(size 0.7 0.7)
					(thickness 0.15)
				)
				(justify left bottom mirror)
			)
		)
		(fp_text user "License: Apache-2.0"
			(at -0.939 -5.799 0)
			(layer "B.Fab")
			(effects
				(font
					(size 0.7 0.7)
					(thickness 0.15)
				)
				(justify left bottom mirror)
			)
		)
		(fp_text user "Author: Antmicro"
			(at -0.939 -3.399 0)
			(layer "B.Fab")
			(effects
				(font
					(size 0.7 0.7)
					(thickness 0.15)
				)
				(justify left bottom mirror)
			)
		)
		(pad "1" smd roundrect
			(at -0.48 0 180)
			(size 0.59 0.64)
			(layers "B.Cu" "B.Mask" "B.Paste")
			(roundrect_rratio 0.25)
			(net 23 "GND")
			(pintype "passive")
		)
		(pad "2" smd roundrect
			(at 0.48 0 180)
			(size 0.59 0.64)
			(layers "B.Cu" "B.Mask" "B.Paste")
			(roundrect_rratio 0.25)
			(net 1 "VCCA")
			(pintype "passive")
		)
	)
	(footprint "antmicro-footprints:TP_SMD_0.75mm"
		(layer "B.Cu")
		(at 148.9 91 180)
		(property "Reference" "TP36"
			(at -18.1 -10.500001 0)
			(layer "B.SilkS")
			(effects
				(font
					(size 0.7 0.7)
					(thickness 0.15)
				)
				(justify mirror)
			)
		)
		(property "Value" "TP_0.75mm_SMD"
			(at 0 -1.2 0)
			(layer "B.Fab")
			(effects
				(font
					(size 0.7 0.7)
					(thickness 0.15)
				)
				(justify left bottom mirror)
			)
		)
		(property "Description" "SMT test point"
			(at 0 0 0)
			(layer "B.Fab")
			(hide yes)
			(effects
				(font
					(size 1.27 1.27)
					(thickness 0.15)
				)
				(justify mirror)
			)
		)
		(property "MPN" ""
			(at 0 0 180)
			(unlocked yes)
			(layer "B.Fab")
			(hide yes)
			(effects
				(font
					(size 1 1)
					(thickness 0.15)
				)
				(justify mirror)
			)
		)
		(property "Manufacturer" ""
			(at 0 0 180)
			(unlocked yes)
			(layer "B.Fab")
			(hide yes)
			(effects
				(font
					(size 1 1)
					(thickness 0.15)
				)
				(justify mirror)
			)
		)
		(property "Author" "Antmicro"
			(at 0 0 180)
			(unlocked yes)
			(layer "B.Fab")
			(hide yes)
			(effects
				(font
					(size 1 1)
					(thickness 0.15)
				)
				(justify mirror)
			)
		)
		(property "License" "Apache-2.0"
			(at 0 0 180)
			(unlocked yes)
			(layer "B.Fab")
			(hide yes)
			(effects
				(font
					(size 1 1)
					(thickness 0.15)
				)
				(justify mirror)
			)
		)
		(sheetname "/X710-AT2 Misc/")
		(sheetfile "x710-at2-mics.kicad_sch")
		(attr exclude_from_pos_files exclude_from_bom)
		(fp_circle
			(center 0 0)
			(end 0.475 0)
			(stroke
				(width 0.05)
				(type default)
			)
			(fill no)
			(layer "B.CrtYd")
		)
		(fp_text user "Author: Antmicro"
			(at -0.4 -3.901 0)
			(layer "B.Fab")
			(effects
				(font
					(size 0.7 0.7)
					(thickness 0.15)
				)
				(justify left bottom mirror)
			)
		)
		(fp_text user "${REFERENCE}"
			(at -0.4 -2.7 0)
			(layer "B.Fab")
			(effects
				(font
					(size 0.7 0.7)
					(thickness 0.15)
				)
				(justify left bottom mirror)
			)
		)
		(fp_text user "License: Apache-2.0"
			(at -0.4 -5.101 0)
			(layer "B.Fab")
			(effects
				(font
					(size 0.7 0.7)
					(thickness 0.15)
				)
				(justify left bottom mirror)
			)
		)
		(pad "1" smd circle
			(at 0 0 180)
			(size 0.75 0.75)
			(layers "B.Cu" "B.Mask")
			(net 445 "Net-(U14D-SMBD)")
			(pinfunction "1")
			(pintype "passive")
		)
	)
	(footprint "antmicro-footprints:R_0402_1005Metric"
		(layer "B.Cu")
		(at 118.5 89.75 90)
		(descr "Resistor SMD 0402")
		(tags "resistor SMD 0402")
		(property "Reference" "R75"
			(at -5.85 0.3 270)
			(layer "B.SilkS")
			(effects
				(font
					(size 0.7 0.7)
					(thickness 0.15)
				)
				(justify left bottom mirror)
			)
		)
		(property "Value" "R_8k2_0402"
			(at -1.011843 -1.772047 270)
			(layer "B.Fab")
			(effects
				(font
					(size 0.7 0.7)
					(thickness 0.15)
				)
				(justify left bottom mirror)
			)
		)
		(property "Datasheet" "https://www.bourns.com/docs/product-datasheets/cr.pdf"
			(at 0 0 270)
			(layer "B.Fab")
			(hide yes)
			(effects
				(font
					(size 1.27 1.27)
					(thickness 0.15)
				)
				(justify mirror)
			)
		)
		(property "Description" "SMD Chip Resistor"
			(at 0 0 270)
			(layer "B.Fab")
			(hide yes)
			(effects
				(font
					(size 1.27 1.27)
					(thickness 0.15)
				)
				(justify mirror)
			)
		)
		(property "MPN" "CR0402-FX-8201GLF"
			(at 0 0 90)
			(unlocked yes)
			(layer "B.Fab")
			(hide yes)
			(effects
				(font
					(size 1 1)
					(thickness 0.15)
				)
				(justify mirror)
			)
		)
		(property "Manufacturer" "Bourns"
			(at 0 0 90)
			(unlocked yes)
			(layer "B.Fab")
			(hide yes)
			(effects
				(font
					(size 1 1)
					(thickness 0.15)
				)
				(justify mirror)
			)
		)
		(property "License" "Apache-2.0"
			(at 0 0 90)
			(unlocked yes)
			(layer "B.Fab")
			(hide yes)
			(effects
				(font
					(size 1 1)
					(thickness 0.15)
				)
				(justify mirror)
			)
		)
		(property "Author" "Antmicro"
			(at 0 0 90)
			(unlocked yes)
			(layer "B.Fab")
			(hide yes)
			(effects
				(font
					(size 1 1)
					(thickness 0.15)
				)
				(justify mirror)
			)
		)
		(property "Val" "8k2"
			(at 0 0 90)
			(unlocked yes)
			(layer "B.Fab")
			(hide yes)
			(effects
				(font
					(size 1 1)
					(thickness 0.15)
				)
				(justify mirror)
			)
		)
		(property "Tolerance" "1%"
			(at 0 0 90)
			(unlocked yes)
			(layer "B.Fab")
			(hide yes)
			(effects
				(font
					(size 1 1)
					(thickness 0.15)
				)
				(justify mirror)
			)
		)
		(sheetname "/TB Controller - Power/")
		(sheetfile "tb-power.kicad_sch")
		(attr smd)
		(fp_rect
			(start -0.925 0.47)
			(end 0.925 -0.47)
			(stroke
				(width 0.05)
				(type default)
			)
			(fill no)
			(layer "B.CrtYd")
		)
		(fp_rect
			(start -0.5 0.25)
			(end 0.5 -0.25)
			(stroke
				(width 0.15)
				(type solid)
			)
			(fill no)
			(layer "B.Fab")
		)
		(fp_text user "License: Apache-2.0"
			(at -0.95 -5.169 270)
			(layer "B.Fab")
			(effects
				(font
					(size 0.7 0.7)
					(thickness 0.15)
				)
				(justify left bottom mirror)
			)
		)
		(fp_text user "Author: Antmicro"
			(at -0.95 -4.169 270)
			(layer "B.Fab")
			(effects
				(font
					(size 0.7 0.7)
					(thickness 0.15)
				)
				(justify left bottom mirror)
			)
		)
		(fp_text user "${REFERENCE}"
			(at -0.95 -3.168 270)
			(layer "B.Fab")
			(effects
				(font
					(size 0.7 0.7)
					(thickness 0.15)
				)
				(justify left bottom mirror)
			)
		)
		(pad "1" smd roundrect
			(at -0.48 0 90)
			(size 0.59 0.64)
			(layers "B.Cu" "B.Mask" "B.Paste")
			(roundrect_rratio 0.25)
			(net 435 "Net-(R75-Pad1)")
			(pintype "passive")
		)
		(pad "2" smd roundrect
			(at 0.48 0 90)
			(size 0.59 0.64)
			(layers "B.Cu" "B.Mask" "B.Paste")
			(roundrect_rratio 0.25)
			(net 57 "+3V3_TB")
			(pintype "passive")
		)
	)
	(footprint "antmicro-footprints:C_0402_1005Metric"
		(layer "B.Cu")
		(at 149.331866 78.260118 180)
		(descr "Capacitor SMD 0402")
		(tags "capacitor SMD 0402")
		(property "Reference" "C246"
			(at -19.468135 -9.464883 0)
			(layer "B.SilkS")
			(effects
				(font
					(size 0.7 0.7)
					(thickness 0.15)
				)
				(justify mirror)
			)
		)
		(property "Value" "C_1u_25V_0402"
			(at -1.022927 -2.155213 0)
			(layer "B.Fab")
			(effects
				(font
					(size 0.7 0.7)
					(thickness 0.15)
				)
				(justify left bottom mirror)
			)
		)
		(property "Datasheet" "https://www.murata.com/products/productdetail?partno=GRM155R61E105KE11%23"
			(at 0 0 0)
			(layer "B.Fab")
			(hide yes)
			(effects
				(font
					(size 1.27 1.27)
					(thickness 0.15)
				)
				(justify mirror)
			)
		)
		(property "Description" "SMD Multilayer Ceramic Capacitor, 1 µF, 25 V, 0402 [1005 Metric], ± 10%, X5R, GRM Series"
			(at 0 0 0)
			(layer "B.Fab")
			(hide yes)
			(effects
				(font
					(size 1.27 1.27)
					(thickness 0.15)
				)
				(justify mirror)
			)
		)
		(property "MPN" "GRM155R61E105KE11J"
			(at 0 0 180)
			(unlocked yes)
			(layer "B.Fab")
			(hide yes)
			(effects
				(font
					(size 1 1)
					(thickness 0.15)
				)
				(justify mirror)
			)
		)
		(property "Manufacturer" "Murata"
			(at 0 0 180)
			(unlocked yes)
			(layer "B.Fab")
			(hide yes)
			(effects
				(font
					(size 1 1)
					(thickness 0.15)
				)
				(justify mirror)
			)
		)
		(property "License" "Apache-2.0"
			(at 0 0 180)
			(unlocked yes)
			(layer "B.Fab")
			(hide yes)
			(effects
				(font
					(size 1 1)
					(thickness 0.15)
				)
				(justify mirror)
			)
		)
		(property "Author" "Antmicro"
			(at 0 0 180)
			(unlocked yes)
			(layer "B.Fab")
			(hide yes)
			(effects
				(font
					(size 1 1)
					(thickness 0.15)
				)
				(justify mirror)
			)
		)
		(property "Val" "1u"
			(at 0 0 180)
			(unlocked yes)
			(layer "B.Fab")
			(hide yes)
			(effects
				(font
					(size 1 1)
					(thickness 0.15)
				)
				(justify mirror)
			)
		)
		(property "Voltage" "25V"
			(at 0 0 180)
			(unlocked yes)
			(layer "B.Fab")
			(hide yes)
			(effects
				(font
					(size 1 1)
					(thickness 0.15)
				)
				(justify mirror)
			)
		)
		(property "Dielectric" "X5R"
			(at 0 0 180)
			(unlocked yes)
			(layer "B.Fab")
			(hide yes)
			(effects
				(font
					(size 1 1)
					(thickness 0.15)
				)
				(justify mirror)
			)
		)
		(sheetname "/X710-AT2 power/")
		(sheetfile "x710-at2-power.kicad_sch")
		(attr smd)
		(fp_rect
			(start -0.925 0.47)
			(end 0.925 -0.47)
			(stroke
				(width 0.05)
				(type default)
			)
			(fill no)
			(layer "B.CrtYd")
		)
		(fp_line
			(start 0.504 0.25)
			(end 0.504 -0.248)
			(stroke
				(width 0.15)
				(type solid)
			)
			(layer "B.Fab")
		)
		(fp_line
			(start 0.504 -0.248)
			(end -0.494 -0.248)
			(stroke
				(width 0.15)
				(type solid)
			)
			(layer "B.Fab")
		)
		(fp_line
			(start -0.494 0.25)
			(end 0.504 0.25)
			(stroke
				(width 0.15)
				(type solid)
			)
			(layer "B.Fab")
		)
		(fp_line
			(start -0.494 -0.248)
			(end -0.494 0.25)
			(stroke
				(width 0.15)
				(type solid)
			)
			(layer "B.Fab")
		)
		(fp_text user "License: Apache-2.0"
			(at -0.939 -5.799 0)
			(layer "B.Fab")
			(effects
				(font
					(size 0.7 0.7)
					(thickness 0.15)
				)
				(justify left bottom mirror)
			)
		)
		(fp_text user "${REFERENCE}"
			(at -0.939 -4.599 0)
			(layer "B.Fab")
			(effects
				(font
					(size 0.7 0.7)
					(thickness 0.15)
				)
				(justify left bottom mirror)
			)
		)
		(fp_text user "Author: Antmicro"
			(at -0.939 -3.399 0)
			(layer "B.Fab")
			(effects
				(font
					(size 0.7 0.7)
					(thickness 0.15)
				)
				(justify left bottom mirror)
			)
		)
		(pad "1" smd roundrect
			(at -0.48 0 180)
			(size 0.59 0.64)
			(layers "B.Cu" "B.Mask" "B.Paste")
			(roundrect_rratio 0.25)
			(net 23 "GND")
			(pintype "passive")
		)
		(pad "2" smd roundrect
			(at 0.48 0 180)
			(size 0.59 0.64)
			(layers "B.Cu" "B.Mask" "B.Paste")
			(roundrect_rratio 0.25)
			(net 9 "VCCD")
			(pintype "passive")
		)
	)
	(gr_line
		(start 115 45)
		(end 115 155)
		(stroke
			(width 0.05)
			(type default)
		)
		(layer "Edge.Cuts")
	)
	(gr_line
		(start 115 155)
		(end 185 155)
		(stroke
			(width 0.05)
			(type default)
		)
		(layer "Edge.Cuts")
	)
	(gr_line
		(start 185 45)
		(end 115 45)
		(stroke
			(width 0.05)
			(type default)
		)
		(layer "Edge.Cuts")
	)
	(gr_line
		(start 185 155)
		(end 185 45)
		(stroke
			(width 0.05)
			(type default)
		)
		(layer "Edge.Cuts")
	)
	(gr_text "Thunderbolt to 10GbE adapter\nRev. 1.1.0 04/2026"
		(at 183.5 104.5 90)
		(layer "F.Cu")
		(effects
			(font
				(size 0.6 0.6)
				(thickness 0.125)
				(bold yes)
			)
			(justify left bottom)
		)
	)
	(via
		(at 145.375 81.25)
		(size 0.45)
		(drill 0.2)
		(layers "F.Cu" "B.Cu")
		(remove_unused_layers yes)
		(keep_end_layers yes)
		(zone_layer_connections "In5.Cu")
		(net 1)
	)
	(via
		(at 152.325 65.725)
		(size 0.45)
		(drill 0.2)
		(layers "F.Cu" "B.Cu")
		(remove_unused_layers yes)
		(keep_end_layers yes)
		(zone_layer_connections "In5.Cu")
		(net 1)
	)
	(via
		(at 152.975 65.05)
		(size 0.45)
		(drill 0.2)
		(layers "F.Cu" "B.Cu")
		(remove_unused_layers yes)
		(keep_end_layers yes)
		(zone_layer_connections "In5.Cu")
		(net 1)
	)
	(via
		(at 150.565 76.25)
		(size 0.45)
		(drill 0.2)
		(layers "F.Cu" "B.Cu")
		(remove_unused_layers yes)
		(keep_end_layers yes)
		(zone_layer_connections "In5.Cu")
		(net 1)
	)
	(via
		(at 145.375 77.25)
		(size 0.45)
		(drill 0.2)
		(layers "F.Cu" "B.Cu")
		(remove_unused_layers yes)
		(keep_end_layers yes)
		(zone_layer_connections "In5.Cu")
		(net 1)
	)
	(via
		(at 152.295 78.25)
		(size 0.45)
		(drill 0.2)
		(layers "F.Cu" "B.Cu")
		(remove_unused_layers yes)
		(keep_end_layers yes)
		(zone_layer_connections "In5.Cu")
		(net 1)
	)
	(via
		(at 150.565 77.25)
		(size 0.45)
		(drill 0.2)
		(layers "F.Cu" "B.Cu")
		(remove_unused_layers yes)
		(keep_end_layers yes)
		(zone_layer_connections "In5.Cu")
		(net 1)
	)
	(via
		(at 152.325 64.375)
		(size 0.45)
		(drill 0.2)
		(layers "F.Cu" "B.Cu")
		(remove_unused_layers yes)
		(keep_end_layers yes)
		(zone_layer_connections "In5.Cu")
		(net 1)
	)
	(via
		(at 150.565 78.25)
		(size 0.45)
		(drill 0.2)
		(layers "F.Cu" "B.Cu")
		(remove_unused_layers yes)
		(keep_end_layers yes)
		(zone_layer_connections "In5.Cu")
		(net 1)
	)
	(via
		(at 151.65 65.05)
		(size 0.45)
		(drill 0.2)
		(layers "F.Cu" "B.Cu")
		(remove_unused_layers yes)
		(keep_end_layers yes)
		(zone_layer_connections "In5.Cu")
		(net 1)
	)
	(via
		(at 149.625 64.375)
		(size 0.45)
		(drill 0.2)
		(layers "F.Cu" "B.Cu")
		(remove_unused_layers yes)
		(keep_end_layers yes)
		(zone_layer_connections "In5.Cu")
		(net 1)
	)
	(via
		(at 152.295 79.25)
		(size 0.45)
		(drill 0.2)
		(layers "F.Cu" "B.Cu")
		(remove_unused_layers yes)
		(keep_end_layers yes)
		(zone_layer_connections "In5.Cu")
		(net 1)
	)
	(via
		(at 150.975 64.375)
		(size 0.45)
		(drill 0.2)
		(layers "F.Cu" "B.Cu")
		(remove_unused_layers yes)
		(keep_end_layers yes)
		(zone_layer_connections "In5.Cu")
		(net 1)
	)
	(via
		(at 145.375 79.25)
		(size 0.45)
		(drill 0.2)
		(layers "F.Cu" "B.Cu")
		(remove_unused_layers yes)
		(keep_end_layers yes)
		(zone_layer_connections "In5.Cu")
		(net 1)
	)
	(via
		(at 150.975 65.725)
		(size 0.45)
		(drill 0.2)
		(layers "F.Cu" "B.Cu")
		(remove_unused_layers yes)
		(keep_end_layers yes)
		(zone_layer_connections "In5.Cu")
		(net 1)
	)
	(via
		(at 149.625 65.725)
		(size 0.45)
		(drill 0.2)
		(layers "F.Cu" "B.Cu")
		(remove_unused_layers yes)
		(keep_end_layers yes)
		(zone_layer_connections "In5.Cu")
		(net 1)
	)
	(via
		(at 148.95 65.05)
		(size 0.45)
		(drill 0.2)
		(layers "F.Cu" "B.Cu")
		(remove_unused_layers yes)
		(keep_end_layers yes)
		(zone_layer_connections "In5.Cu")
		(net 1)
	)
	(via
		(at 152.295 76.25)
		(size 0.45)
		(drill 0.2)
		(layers "F.Cu" "B.Cu")
		(remove_unused_layers yes)
		(keep_end_layers yes)
		(zone_layer_connections "In5.Cu")
		(net 1)
	)
	(via
		(at 152.295 77.25)
		(size 0.45)
		(drill 0.2)
		(layers "F.Cu" "B.Cu")
		(remove_unused_layers yes)
		(keep_end_layers yes)
		(zone_layer_connections "In5.Cu")
		(net 1)
	)
	(via
		(at 145.375 80.25)
		(size 0.45)
		(drill 0.2)
		(layers "F.Cu" "B.Cu")
		(remove_unused_layers yes)
		(keep_end_layers yes)
		(zone_layer_connections "In5.Cu")
		(net 1)
	)
	(via
		(at 150.3 65.05)
		(size 0.45)
		(drill 0.2)
		(layers "F.Cu" "B.Cu")
		(remove_unused_layers yes)
		(keep_end_layers yes)
		(zone_layer_connections "In5.Cu")
		(net 1)
	)
	(via
		(at 145.375 78.25)
		(size 0.45)
		(drill 0.2)
		(layers "F.Cu" "B.Cu")
		(remove_unused_layers yes)
		(keep_end_layers yes)
		(zone_layer_connections "In5.Cu")
		(net 1)
	)
	(via
		(at 144.51 76.75)
		(size 0.45)
		(drill 0.2)
		(layers "F.Cu" "B.Cu")
		(remove_unused_layers yes)
		(keep_end_layers yes)
		(zone_layer_connections)
		(net 2)
	)
	(segment
		(start 144.515 76.75)
		(end 144.17 76.75)
		(width 0.15)
		(layer "B.Cu")
		(net 2)
	)
	(via
		(at 144.51 75.75)
		(size 0.45)
		(drill 0.2)
		(layers "F.Cu" "B.Cu")
		(remove_unused_layers yes)
		(keep_end_layers yes)
		(zone_layer_connections)
		(net 3)
	)
	(segment
		(start 144.515 75.75)
		(end 144.17 75.75)
		(width 0.15)
		(layer "B.Cu")
		(net 3)
	)
	(via
		(at 146.24 89.75)
		(size 0.45)
		(drill 0.2)
		(layers "F.Cu" "B.Cu")
		(remove_unused_layers yes)
		(keep_end_layers yes)
		(zone_layer_connections)
		(net 4)
	)
	(via
		(at 126.65 87.75)
		(size 0.45)
		(drill 0.2)
		(layers "F.Cu" "B.Cu")
		(remove_unused_layers yes)
		(keep_end_layers yes)
		(zone_layer_connections)
		(net 4)
	)
	(segment
		(start 126.654 87.746)
		(end 126.65 87.75)
		(width 0.1)
		(layer "B.Cu")
		(net 4)
	)
	(segment
		(start 126.654 87.73)
		(end 126.654 87.746)
		(width 0.1)
		(layer "B.Cu")
		(net 4)
	)
	(segment
		(start 146.6 95.6)
		(end 146.6 92.5)
		(width 0.1)
		(layer "In3.Cu")
		(net 4)
	)
	(segment
		(start 135.45 92.824264)
		(end 140.225736 97.6)
		(width 0.1)
		(layer "In3.Cu")
		(net 4)
	)
	(segment
		(start 146.6 92.5)
		(end 144.95 90.85)
		(width 0.1)
		(layer "In3.Cu")
		(net 4)
	)
	(segment
		(start 140.225736 97.6)
		(end 144.6 97.6)
		(width 0.1)
		(layer "In3.Cu")
		(net 4)
	)
	(segment
		(start 144.6 97.6)
		(end 146.6 95.6)
		(width 0.1)
		(layer "In3.Cu")
		(net 4)
	)
	(segment
		(start 126.65 87.75)
		(end 127.7 88.8)
		(width 0.1)
		(layer "In3.Cu")
		(net 4)
	)
	(segment
		(start 133.35 88.8)
		(end 135.45 90.9)
		(width 0.1)
		(layer "In3.Cu")
		(net 4)
	)
	(segment
		(start 145.15 89.75)
		(end 146.24 89.75)
		(width 0.1)
		(layer "In3.Cu")
		(net 4)
	)
	(segment
		(start 127.7 88.8)
		(end 133.35 88.8)
		(width 0.1)
		(layer "In3.Cu")
		(net 4)
	)
	(segment
		(start 135.45 90.9)
		(end 135.45 92.824264)
		(width 0.1)
		(layer "In3.Cu")
		(net 4)
	)
	(segment
		(start 144.95 90.85)
		(end 144.95 89.95)
		(width 0.1)
		(layer "In3.Cu")
		(net 4)
	)
	(segment
		(start 144.95 89.95)
		(end 145.15 89.75)
		(width 0.1)
		(layer "In3.Cu")
		(net 4)
	)
	(via
		(at 159.9 94.4)
		(size 0.45)
		(drill 0.2)
		(layers "F.Cu" "B.Cu")
		(remove_unused_layers yes)
		(keep_end_layers yes)
		(zone_layer_connections "In2.Cu")
		(net 5)
	)
	(via
		(at 159.9 93.4)
		(size 0.45)
		(drill 0.2)
		(layers "F.Cu" "B.Cu")
		(remove_unused_layers yes)
		(keep_end_layers yes)
		(zone_layer_connections "In2.Cu")
		(net 5)
	)
	(via
		(at 159.215 89.25)
		(size 0.45)
		(drill 0.2)
		(layers "F.Cu" "B.Cu")
		(remove_unused_layers yes)
		(keep_end_layers yes)
		(zone_layer_connections "In2.Cu")
		(net 5)
	)
	(via
		(at 159.215 87.25)
		(size 0.45)
		(drill 0.2)
		(layers "F.Cu" "B.Cu")
		(remove_unused_layers yes)
		(keep_end_layers yes)
		(zone_layer_connections "In2.Cu")
		(net 5)
	)
	(via
		(at 160.9 94.4)
		(size 0.45)
		(drill 0.2)
		(layers "F.Cu" "B.Cu")
		(remove_unused_layers yes)
		(keep_end_layers yes)
		(zone_layer_connections "In2.Cu")
		(net 5)
	)
	(via
		(at 159.215 90.25)
		(size 0.45)
		(drill 0.2)
		(layers "F.Cu" "B.Cu")
		(remove_unused_layers yes)
		(keep_end_layers yes)
		(zone_layer_connections "In2.Cu")
		(net 5)
	)
	(via
		(at 159.215 88.25)
		(size 0.45)
		(drill 0.2)
		(layers "F.Cu" "B.Cu")
		(remove_unused_layers yes)
		(keep_end_layers yes)
		(zone_layer_connections "In2.Cu")
		(net 5)
	)
	(via
		(at 160.9 93.4)
		(size 0.45)
		(drill 0.2)
		(layers "F.Cu" "B.Cu")
		(remove_unused_layers yes)
		(keep_end_layers yes)
		(zone_layer_connections "In2.Cu")
		(net 5)
	)
	(via
		(at 143.599998 101.5)
		(size 0.45)
		(drill 0.2)
		(layers "F.Cu" "B.Cu")
		(remove_unused_layers yes)
		(keep_end_layers yes)
		(zone_layer_connections "In2.Cu")
		(net 6)
	)
	(via
		(at 155.755 87.25)
		(size 0.45)
		(drill 0.2)
		(layers "F.Cu" "B.Cu")
		(remove_unused_layers yes)
		(keep_end_layers yes)
		(zone_layer_connections "In2.Cu")
		(net 6)
	)
	(via
		(at 141.599999 101.5)
		(size 0.45)
		(drill 0.2)
		(layers "F.Cu" "B.Cu")
		(remove_unused_layers yes)
		(keep_end_layers yes)
		(zone_layer_connections "In2.Cu")
		(net 6)
	)
	(via
		(at 155.755 86.25)
		(size 0.45)
		(drill 0.2)
		(layers "F.Cu" "B.Cu")
		(remove_unused_layers yes)
		(keep_end_layers yes)
		(zone_layer_connections "In2.Cu")
		(net 6)
	)
	(via
		(at 141.6 100.5)
		(size 0.45)
		(drill 0.2)
		(layers "F.Cu" "B.Cu")
		(remove_unused_layers yes)
		(keep_end_layers yes)
		(zone_layer_connections "In2.Cu")
		(net 6)
	)
	(via
		(at 144.599998 101.5)
		(size 0.45)
		(drill 0.2)
		(layers "F.Cu" "B.Cu")
		(remove_unused_layers yes)
		(keep_end_layers yes)
		(zone_layer_connections "In2.Cu")
		(net 6)
	)
	(via
		(at 142.599999 101.5)
		(size 0.45)
		(drill 0.2)
		(layers "F.Cu" "B.Cu")
		(remove_unused_layers yes)
		(keep_end_layers yes)
		(zone_layer_connections "In2.Cu")
		(net 6)
	)
	(via
		(at 173 82.75)
		(size 0.45)
		(drill 0.2)
		(layers "F.Cu" "B.Cu")
		(remove_unused_layers yes)
		(keep_end_layers yes)
		(zone_layer_connections)
		(net 6)
	)
	(via
		(at 142.599999 100.5)
		(size 0.45)
		(drill 0.2)
		(layers "F.Cu" "B.Cu")
		(remove_unused_layers yes)
		(keep_end_layers yes)
		(zone_layer_connections "In2.Cu")
		(net 6)
	)
	(via
		(at 155.755 88.25)
		(size 0.45)
		(drill 0.2)
		(layers "F.Cu" "B.Cu")
		(remove_unused_layers yes)
		(keep_end_layers yes)
		(zone_layer_connections "In2.Cu")
		(net 6)
	)
	(via
		(at 155.755 84.25)
		(size 0.45)
		(drill 0.2)
		(layers "F.Cu" "B.Cu")
		(remove_unused_layers yes)
		(keep_end_layers yes)
		(zone_layer_connections "In2.Cu")
		(net 6)
	)
	(via
		(at 143.600001 100.5)
		(size 0.45)
		(drill 0.2)
		(layers "F.Cu" "B.Cu")
		(remove_unused_layers yes)
		(keep_end_layers yes)
		(zone_layer_connections "In2.Cu")
		(net 6)
	)
	(via
		(at 144.600001 100.5)
		(size 0.45)
		(drill 0.2)
		(layers "F.Cu" "B.Cu")
		(remove_unused_layers yes)
		(keep_end_layers yes)
		(zone_layer_connections "In2.Cu")
		(net 6)
	)
	(via
		(at 155.755 85.25)
		(size 0.45)
		(drill 0.2)
		(layers "F.Cu" "B.Cu")
		(remove_unused_layers yes)
		(keep_end_layers yes)
		(zone_layer_connections "In2.Cu")
		(net 6)
	)
	(segment
		(start 183.75 84.75)
		(end 175 84.75)
		(width 0.1)
		(layer "B.Cu")
		(net 6)
	)
	(segment
		(start 175 84.75)
		(end 173 82.75)
		(width 0.1)
		(layer "B.Cu")
		(net 6)
	)
	(segment
		(start 159.25 83.75)
		(end 159 83.75)
		(width 0.1)
		(layer "In5.Cu")
		(net 6)
	)
	(segment
		(start 158.5 83.25)
		(end 158.15 83.25)
		(width 0.1)
		(layer "In5.Cu")
		(net 6)
	)
	(segment
		(start 160.75 82.75)
		(end 160.25 83.25)
		(width 0.1)
		(layer "In5.Cu")
		(net 6)
	)
	(segment
		(start 157.3 83.75)
		(end 156.8 84.25)
		(width 0.1)
		(layer "In5.Cu")
		(net 6)
	)
	(segment
		(start 173 82.75)
		(end 160.75 82.75)
		(width 0.1)
		(layer "In5.Cu")
		(net 6)
	)
	(segment
		(start 156.8 84.25)
		(end 155.755 84.25)
		(width 0.1)
		(layer "In5.Cu")
		(net 6)
	)
	(segment
		(start 160.25 83.25)
		(end 159.75 83.25)
		(width 0.1)
		(layer "In5.Cu")
		(net 6)
	)
	(segment
		(start 159 83.75)
		(end 158.5 83.25)
		(width 0.1)
		(layer "In5.Cu")
		(net 6)
	)
	(segment
		(start 158.15 83.25)
		(end 157.65 83.75)
		(width 0.1)
		(layer "In5.Cu")
		(net 6)
	)
	(segment
		(start 157.65 83.75)
		(end 157.3 83.75)
		(width 0.1)
		(layer "In5.Cu")
		(net 6)
	)
	(segment
		(start 159.75 83.25)
		(end 159.25 83.75)
		(width 0.1)
		(layer "In5.Cu")
		(net 6)
	)
	(segment
		(start 166.1 72.1)
		(end 167.9 72.1)
		(width 0.25)
		(layer "F.Cu")
		(net 7)
	)
	(segment
		(start 164.48 75.4)
		(end 165.52 75.4)
		(width 0.25)
		(layer "F.Cu")
		(net 7)
	)
	(segment
		(start 128.77 87.77)
		(end 128.8 87.8)
		(width 0.1)
		(layer "F.Cu")
		(net 7)
	)
	(segment
		(start 176.52 76.52)
		(end 175.822358 76.52)
		(width 0.25)
		(layer "F.Cu")
		(net 7)
	)
	(segment
		(start 124.54 91.579)
		(end 122.821 91.579)
		(width 0.1)
		(layer "F.Cu")
		(net 7)
	)
	(segment
		(start 135 83.2)
		(end 135 83.72)
		(width 0.25)
		(layer "F.Cu")
		(net 7)
	)
	(segment
		(start 165.265 61.52)
		(end 165.645 61.9)
		(width 0.1)
		(layer "F.Cu")
		(net 7)
	)
	(segment
		(start 170.6 72.58)
		(end 170.555 72.58)
		(width 0.1)
		(layer "F.Cu")
		(net 7)
	)
	(segment
		(start 123.36 89.04)
		(end 123.2 89.2)
		(width 0.1)
		(layer "F.Cu")
		(net 7)
	)
	(segment
		(start 141.830001 94.674999)
		(end 141.830001 93.675001)
		(width 0.1)
		(layer "F.Cu")
		(net 7)
	)
	(segment
		(start 155.26 68.595)
		(end 156.21 68.595)
		(width 0.15)
		(layer "F.Cu")
		(net 7)
	)
	(segment
		(start 165.813 73.825999)
		(end 165.813 72.387)
		(width 0.25)
		(layer "F.Cu")
		(net 7)
	)
	(segment
		(start 122.821 91.579)
		(end 122.8 91.6)
		(width 0.1)
		(layer "F.Cu")
		(net 7)
	)
	(segment
		(start 134.8 83)
		(end 135 83.2)
		(width 0.25)
		(layer "F.Cu")
		(net 7)
	)
	(segment
		(start 136.300001 83.72)
		(end 136.404 83.823999)
		(width 0.25)
		(layer "F.Cu")
		(net 7)
	)
	(segment
		(start 165.813 73.825999)
		(end 165.813 75.107)
		(width 0.25)
		(layer "F.Cu")
		(net 7)
	)
	(segment
		(start 176.525 76.525)
		(end 176.52 76.52)
		(width 0.25)
		(layer "F.Cu")
		(net 7)
	)
	(segment
		(start 129.95 84.3)
		(end 132.3 84.3)
		(width 0.25)
		(layer "F.Cu")
		(net 7)
	)
	(segment
		(start 117.962 63.928)
		(end 117.962 62.638)
		(width 0.25)
		(layer "F.Cu")
		(net 7)
	)
	(segment
		(start 166.665 60.715)
		(end 166.65 60.7)
		(width 0.25)
		(layer "F.Cu")
		(net 7)
	)
	(segment
		(start 175.113 76.687)
		(end 175.28 76.52)
		(width 0.25)
		(layer "F.Cu")
		(net 7)
	)
	(segment
		(start 135 83.72)
		(end 136.300001 83.72)
		(width 0.25)
		(layer "F.Cu")
		(net 7)
	)
	(segment
		(start 127.564 87.77)
		(end 128.77 87.77)
		(width 0.1)
		(layer "F.Cu")
		(net 7)
	)
	(segment
		(start 165.813 72.387)
		(end 166.1 72.1)
		(width 0.25)
		(layer "F.Cu")
		(net 7)
	)
	(segment
		(start 141.829999 92.829999)
		(end 141.8 92.8)
		(width 0.1)
		(layer "F.Cu")
		(net 7)
	)
	(segment
		(start 174.205 72.58)
		(end 174.225 72.6)
		(width 0.1)
		(layer "F.Cu")
		(net 7)
	)
	(segment
		(start 166.665 61.9)
		(end 166.665 60.715)
		(width 0.25)
		(layer "F.Cu")
		(net 7)
	)
	(segment
		(start 133.6 83)
		(end 134.8 83)
		(width 0.25)
		(layer "F.Cu")
		(net 7)
	)
	(segment
		(start 175.28 76.52)
		(end 175.822358 76.52)
		(width 0.25)
		(layer "F.Cu")
		(net 7)
	)
	(segment
		(start 170.555 72.58)
		(end 170.05 72.075)
		(width 0.1)
		(layer "F.Cu")
		(net 7)
	)
	(segment
		(start 176.975 76.525)
		(end 176.525 76.525)
		(width 0.25)
		(layer "F.Cu")
		(net 7)
	)
	(segment
		(start 124.54 89.04)
		(end 123.36 89.04)
		(width 0.1)
		(layer "F.Cu")
		(net 7)
	)
	(segment
		(start 117.962 62.638)
		(end 118 62.6)
		(width 0.25)
		(layer "F.Cu")
		(net 7)
	)
	(segment
		(start 141.830001 93.675001)
		(end 141.829999 93.674999)
		(width 0.1)
		(layer "F.Cu")
		(net 7)
	)
	(segment
		(start 165.645 61.9)
		(end 166.665 61.9)
		(width 0.1)
		(layer "F.Cu")
		(net 7)
	)
	(segment
		(start 156.21 68.595)
		(end 157.16 68.595)
		(width 0.15)
		(layer "F.Cu")
		(net 7)
	)
	(segment
		(start 165.813 75.107)
		(end 165.52 75.4)
		(width 0.25)
		(layer "F.Cu")
		(net 7)
	)
	(segment
		(start 173.6 72.58)
		(end 174.205 72.58)
		(width 0.1)
		(layer "F.Cu")
		(net 7)
	)
	(segment
		(start 141.829999 93.674999)
		(end 141.829999 92.829999)
		(width 0.1)
		(layer "F.Cu")
		(net 7)
	)
	(segment
		(start 132.3 84.3)
		(end 133.6 83)
		(width 0.25)
		(layer "F.Cu")
		(net 7)
	)
	(segment
		(start 130.899 70.2)
		(end 131.6 70.2)
		(width 0.25)
		(layer "F.Cu")
		(net 7)
	)
	(segment
		(start 174.151 76.687)
		(end 175.113 76.687)
		(width 0.25)
		(layer "F.Cu")
		(net 7)
	)
	(via
		(at 140.2 89.8)
		(size 0.45)
		(drill 0.2)
		(layers "F.Cu" "B.Cu")
		(remove_unused_layers yes)
		(keep_end_layers yes)
		(free yes)
		(zone_layer_connections "In6.Cu")
		(net 7)
	)
	(via
		(at 152.295 75.25)
		(size 0.45)
		(drill 0.2)
		(layers "F.Cu" "B.Cu")
		(remove_unused_layers yes)
		(keep_end_layers yes)
		(zone_layer_connections "In6.Cu")
		(net 7)
	)
	(via
		(at 130 86.6)
		(size 0.45)
		(drill 0.2)
		(layers "F.Cu" "B.Cu")
		(remove_unused_layers yes)
		(keep_end_layers yes)
		(free yes)
		(zone_layer_connections "In2.Cu")
		(net 7)
	)
	(via
		(at 129.4 87.8)
		(size 0.45)
		(drill 0.2)
		(layers "F.Cu" "B.Cu")
		(remove_unused_layers yes)
		(keep_end_layers yes)
		(free yes)
		(zone_layer_connections "In2.Cu")
		(net 7)
	)
	(via
		(at 140.2 91.6)
		(size 0.45)
		(drill 0.2)
		(layers "F.Cu" "B.Cu")
		(remove_unused_layers yes)
		(keep_end_layers yes)
		(free yes)
		(zone_layer_connections "In6.Cu")
		(net 7)
	)
	(via
		(at 122.8 91.6)
		(size 0.45)
		(drill 0.2)
		(layers "F.Cu" "B.Cu")
		(remove_unused_layers yes)
		(keep_end_layers yes)
		(zone_layer_connections "In2.Cu")
		(net 7)
	)
	(via
		(at 162 68.3)
		(size 0.45)
		(drill 0.2)
		(layers "F.Cu" "B.Cu")
		(remove_unused_layers yes)
		(keep_end_layers yes)
		(zone_layer_connections "In2.Cu")
		(net 7)
	)
	(via
		(at 139.6 91)
		(size 0.45)
		(drill 0.2)
		(layers "F.Cu" "B.Cu")
		(remove_unused_layers yes)
		(keep_end_layers yes)
		(free yes)
		(zone_layer_connections "In6.Cu")
		(net 7)
	)
	(via
		(at 130 86)
		(size 0.45)
		(drill 0.2)
		(layers "F.Cu" "B.Cu")
		(remove_unused_layers yes)
		(keep_end_layers yes)
		(free yes)
		(zone_layer_connections "In2.Cu")
		(net 7)
	)
	(via
		(at 128.8 86.6)
		(size 0.45)
		(drill 0.2)
		(layers "F.Cu" "B.Cu")
		(remove_unused_layers yes)
		(keep_end_layers yes)
		(free yes)
		(zone_layer_connections "In2.Cu")
		(net 7)
	)
	(via
		(at 154.31 67.605)
		(size 0.45)
		(drill 0.2)
		(layers "F.Cu" "B.Cu")
		(remove_unused_layers yes)
		(keep_end_layers yes)
		(zone_layer_connections "In2.Cu")
		(net 7)
	)
	(via
		(at 140.2 92.8)
		(size 0.45)
		(drill 0.2)
		(layers "F.Cu" "B.Cu")
		(remove_unused_layers yes)
		(keep_end_layers yes)
		(free yes)
		(zone_layer_connections "In6.Cu")
		(net 7)
	)
	(via
		(at 158.11 65.655)
		(size 0.45)
		(drill 0.2)
		(layers "F.Cu" "B.Cu")
		(remove_unused_layers yes)
		(keep_end_layers yes)
		(zone_layer_connections "In2.Cu")
		(net 7)
	)
	(via
		(at 129.4 86)
		(size 0.45)
		(drill 0.2)
		(layers "F.Cu" "B.Cu")
		(remove_unused_layers yes)
		(keep_end_layers yes)
		(free yes)
		(zone_layer_connections "In2.Cu")
		(net 7)
	)
	(via
		(at 128.8 86)
		(size 0.45)
		(drill 0.2)
		(layers "F.Cu" "B.Cu")
		(remove_unused_layers yes)
		(keep_end_layers yes)
		(free yes)
		(zone_layer_connections "In2.Cu")
		(net 7)
	)
	(via
		(at 148.95 68.925)
		(size 0.45)
		(drill 0.2)
		(layers "F.Cu" "B.Cu")
		(remove_unused_layers yes)
		(keep_end_layers yes)
		(zone_layer_connections "In2.Cu")
		(net 7)
	)
	(via
		(at 140.2 90.4)
		(size 0.45)
		(drill 0.2)
		(layers "F.Cu" "B.Cu")
		(remove_unused_layers yes)
		(keep_end_layers yes)
		(free yes)
		(zone_layer_connections "In6.Cu")
		(net 7)
	)
	(via
		(at 170.05 72.075)
		(size 0.45)
		(drill 0.2)
		(layers "F.Cu" "B.Cu")
		(remove_unused_layers yes)
		(keep_end_layers yes)
		(zone_layer_connections "In2.Cu")
		(net 7)
	)
	(via
		(at 166.65 60.7)
		(size 0.45)
		(drill 0.2)
		(layers "F.Cu" "B.Cu")
		(remove_unused_layers yes)
		(keep_end_layers yes)
		(zone_layer_connections "In2.Cu")
		(net 7)
	)
	(via
		(at 139.6 89.8)
		(size 0.45)
		(drill 0.2)
		(layers "F.Cu" "B.Cu")
		(remove_unused_layers yes)
		(keep_end_layers yes)
		(free yes)
		(zone_layer_connections "In6.Cu")
		(net 7)
	)
	(via
		(at 129.4 87.2)
		(size 0.45)
		(drill 0.2)
		(layers "F.Cu" "B.Cu")
		(remove_unused_layers yes)
		(keep_end_layers yes)
		(free yes)
		(zone_layer_connections "In2.Cu")
		(net 7)
	)
	(via
		(at 151.65 68.925)
		(size 0.45)
		(drill 0.2)
		(layers "F.Cu" "B.Cu")
		(remove_unused_layers yes)
		(keep_end_layers yes)
		(zone_layer_connections "In2.Cu")
		(net 7)
	)
	(via
		(at 130 87.2)
		(size 0.45)
		(drill 0.2)
		(layers "F.Cu" "B.Cu")
		(remove_unused_layers yes)
		(keep_end_layers yes)
		(free yes)
		(zone_layer_connections "In2.Cu")
		(net 7)
	)
	(via
		(at 150.3 68.925)
		(size 0.45)
		(drill 0.2)
		(layers "F.Cu" "B.Cu")
		(remove_unused_layers yes)
		(keep_end_layers yes)
		(zone_layer_connections "In2.Cu")
		(net 7)
	)
	(via
		(at 157.16 65.655)
		(size 0.45)
		(drill 0.2)
		(layers "F.Cu" "B.Cu")
		(remove_unused_layers yes)
		(keep_end_layers yes)
		(zone_layer_connections "In2.Cu")
		(net 7)
	)
	(via
		(at 144 92.8)
		(size 0.45)
		(drill 0.2)
		(layers "F.Cu" "B.Cu")
		(remove_unused_layers yes)
		(keep_end_layers yes)
		(zone_layer_connections "In6.Cu")
		(net 7)
	)
	(via
		(at 155.26 67.605)
		(size 0.45)
		(drill 0.2)
		(layers "F.Cu" "B.Cu")
		(remove_unused_layers yes)
		(keep_end_layers yes)
		(zone_layer_connections "In2.Cu")
		(net 7)
	)
	(via
		(at 128.8 87.8)
		(size 0.45)
		(drill 0.2)
		(layers "F.Cu" "B.Cu")
		(remove_unused_layers yes)
		(keep_end_layers yes)
		(free yes)
		(zone_layer_connections "In2.Cu")
		(net 7)
	)
	(via
		(at 140.2 92.2)
		(size 0.45)
		(drill 0.2)
		(layers "F.Cu" "B.Cu")
		(remove_unused_layers yes)
		(keep_end_layers yes)
		(free yes)
		(zone_layer_connections "In6.Cu")
		(net 7)
	)
	(via
		(at 123.2 89.2)
		(size 0.45)
		(drill 0.2)
		(layers "F.Cu" "B.Cu")
		(remove_unused_layers yes)
		(keep_end_layers yes)
		(zone_layer_connections "In2.Cu")
		(net 7)
	)
	(via
		(at 147.97 71.75)
		(size 0.45)
		(drill 0.2)
		(layers "F.Cu" "B.Cu")
		(remove_unused_layers yes)
		(keep_end_layers yes)
		(zone_layer_connections "In2.Cu")
		(net 7)
	)
	(via
		(at 147.97 87.75)
		(size 0.45)
		(drill 0.2)
		(layers "F.Cu" "B.Cu")
		(remove_unused_layers yes)
		(keep_end_layers yes)
		(zone_layer_connections "In6.Cu")
		(net 7)
	)
	(via
		(at 176.975 76.525)
		(size 0.45)
		(drill 0.2)
		(layers "F.Cu" "B.Cu")
		(remove_unused_layers yes)
		(keep_end_layers yes)
		(zone_layer_connections "In2.Cu")
		(net 7)
	)
	(via
		(at 139.6 91.6)
		(size 0.45)
		(drill 0.2)
		(layers "F.Cu" "B.Cu")
		(remove_unused_layers yes)
		(keep_end_layers yes)
		(free yes)
		(zone_layer_connections "In6.Cu")
		(net 7)
	)
	(via
		(at 129.4 86.6)
		(size 0.45)
		(drill 0.2)
		(layers "F.Cu" "B.Cu")
		(remove_unused_layers yes)
		(keep_end_layers yes)
		(free yes)
		(zone_layer_connections "In2.Cu")
		(net 7)
	)
	(via
		(at 174.225 72.6)
		(size 0.45)
		(drill 0.2)
		(layers "F.Cu" "B.Cu")
		(remove_unused_layers yes)
		(keep_end_layers yes)
		(zone_layer_connections "In2.Cu")
		(net 7)
	)
	(via
		(at 140.2 91)
		(size 0.45)
		(drill 0.2)
		(layers "F.Cu" "B.Cu")
		(remove_unused_layers yes)
		(keep_end_layers yes)
		(free yes)
		(zone_layer_connections "In6.Cu")
		(net 7)
	)
	(via
		(at 153 68.925)
		(size 0.45)
		(drill 0.2)
		(layers "F.Cu" "B.Cu")
		(remove_unused_layers yes)
		(keep_end_layers yes)
		(zone_layer_connections "In2.Cu")
		(net 7)
	)
	(via
		(at 156.21 68.595)
		(size 0.45)
		(drill 0.2)
		(layers "F.Cu" "B.Cu")
		(remove_unused_layers yes)
		(keep_end_layers yes)
		(zone_layer_connections "In2.Cu")
		(net 7)
	)
	(via
		(at 157.16 67.605)
		(size 0.45)
		(drill 0.2)
		(layers "F.Cu" "B.Cu")
		(remove_unused_layers yes)
		(keep_end_layers yes)
		(zone_layer_connections "In2.Cu")
		(net 7)
	)
	(via
		(at 145.375 76.25)
		(size 0.45)
		(drill 0.2)
		(layers "F.Cu" "B.Cu")
		(remove_unused_layers yes)
		(keep_end_layers yes)
		(zone_layer_connections "In6.Cu")
		(net 7)
	)
	(via
		(at 131.6 70.2)
		(size 0.45)
		(drill 0.2)
		(layers "F.Cu" "B.Cu")
		(remove_unused_layers yes)
		(keep_end_layers yes)
		(zone_layer_connections "In2.Cu")
		(net 7)
	)
	(via
		(at 139.6 90.4)
		(size 0.45)
		(drill 0.2)
		(layers "F.Cu" "B.Cu")
		(remove_unused_layers yes)
		(keep_end_layers yes)
		(free yes)
		(zone_layer_connections "In6.Cu")
		(net 7)
	)
	(via
		(at 167.9 72.1)
		(size 0.45)
		(drill 0.2)
		(layers "F.Cu" "B.Cu")
		(remove_unused_layers yes)
		(keep_end_layers yes)
		(zone_layer_connections "In2.Cu")
		(net 7)
	)
	(via
		(at 129.95 84.3)
		(size 0.45)
		(drill 0.2)
		(layers "F.Cu" "B.Cu")
		(remove_unused_layers yes)
		(keep_end_layers yes)
		(zone_layer_connections "In2.Cu")
		(net 7)
	)
	(via
		(at 141.8 92.8)
		(size 0.45)
		(drill 0.2)
		(layers "F.Cu" "B.Cu")
		(remove_unused_layers yes)
		(keep_end_layers yes)
		(zone_layer_connections "In6.Cu")
		(net 7)
	)
	(via
		(at 147.105 81.25)
		(size 0.45)
		(drill 0.2)
		(layers "F.Cu" "B.Cu")
		(remove_unused_layers yes)
		(keep_end_layers yes)
		(zone_layer_connections "In6.Cu")
		(net 7)
	)
	(via
		(at 130 87.8)
		(size 0.45)
		(drill 0.2)
		(layers "F.Cu" "B.Cu")
		(remove_unused_layers yes)
		(keep_end_layers yes)
		(free yes)
		(zone_layer_connections "In2.Cu")
		(net 7)
	)
	(via
		(at 118 62.6)
		(size 0.45)
		(drill 0.2)
		(layers "F.Cu" "B.Cu")
		(remove_unused_layers yes)
		(keep_end_layers yes)
		(zone_layer_connections "In2.Cu")
		(net 7)
	)
	(via
		(at 148.835 76.25)
		(size 0.45)
		(drill 0.2)
		(layers "F.Cu" "B.Cu")
		(remove_unused_layers yes)
		(keep_end_layers yes)
		(zone_layer_connections "In6.Cu")
		(net 7)
	)
	(via
		(at 128.8 87.2)
		(size 0.45)
		(drill 0.2)
		(layers "F.Cu" "B.Cu")
		(remove_unused_layers yes)
		(keep_end_layers yes)
		(free yes)
		(zone_layer_connections "In2.Cu")
		(net 7)
	)
	(segment
		(start 152.768301 73.206699)
		(end 153.348888 73.206699)
		(width 0.15)
		(layer "B.Cu")
		(net 7)
	)
	(segment
		(start 153.843189 73.701)
		(end 154.856 73.701)
		(width 0.15)
		(layer "B.Cu")
		(net 7)
	)
	(segment
		(start 147.92 86.925)
		(end 147.92 87.695)
		(width 0.3)
		(layer "B.Cu")
		(net 7)
	)
	(segment
		(start 176.975 76.525)
		(end 177.525 76.525)
		(width 0.1)
		(layer "B.Cu")
		(net 7)
	)
	(segment
		(start 146.681866 92.965118)
		(end 145.45 92.965118)
		(width 0.1)
		(layer "B.Cu")
		(net 7)
	)
	(segment
		(start 144 92.8)
		(end 145.284882 92.8)
		(width 0.1)
		(layer "B.Cu")
		(net 7)
	)
	(segment
		(start 161.981866 69.02)
		(end 161.981866 68.318134)
		(width 0.1)
		(layer "B.Cu")
		(net 7)
	)
	(segment
		(start 161.981866 68.318134)
		(end 162 68.3)
		(width 0.1)
		(layer "B.Cu")
		(net 7)
	)
	(segment
		(start 147.681866 92.965117)
		(end 146.681867 92.965117)
		(width 0.1)
		(layer "B.Cu")
		(net 7)
	)
	(segment
		(start 152.52 73.455)
		(end 152.768301 73.206699)
		(width 0.15)
		(layer "B.Cu")
		(net 7)
	)
	(segment
		(start 182.2 77.2)
		(end 183.75 78.75)
		(width 0.1)
		(layer "B.Cu")
		(net 7)
	)
	(segment
		(start 152.52 74.225)
		(end 152.52 73.455)
		(width 0.15)
		(layer "B.Cu")
		(net 7)
	)
	(segment
		(start 164.514882 75.485118)
		(end 167.9 72.1)
		(width 0.25)
		(layer "B.Cu")
		(net 7)
	)
	(segment
		(start 153.348888 73.206699)
		(end 153.843189 73.701)
		(width 0.15)
		(layer "B.Cu")
		(net 7)
	)
	(segment
		(start 145.284882 92.8)
		(end 145.45 92.965118)
		(width 0.1)
		(layer "B.Cu")
		(net 7)
	)
	(segment
		(start 162.861866 75.485118)
		(end 164.514882 75.485118)
		(width 0.25)
		(layer "B.Cu")
		(net 7)
	)
	(segment
		(start 177.525 76.525)
		(end 178.2 77.2)
		(width 0.1)
		(layer "B.Cu")
		(net 7)
	)
	(segment
		(start 154.856 73.701)
		(end 155.45 74.295)
		(width 0.15)
		(layer "B.Cu")
		(net 7)
	)
	(segment
		(start 147.92 87.695)
		(end 147.975 87.75)
		(width 0.3)
		(layer "B.Cu")
		(net 7)
	)
	(segment
		(start 147.951866 86.935117)
		(end 147.951866 84.931866)
		(width 0.25)
		(layer "B.Cu")
		(net 7)
	)
	(segment
		(start 146.681867 92.965117)
		(end 146.681866 92.965118)
		(width 0.1)
		(layer "B.Cu")
		(net 7)
	)
	(segment
		(start 178.2 77.2)
		(end 182.2 77.2)
		(width 0.1)
		(layer "B.Cu")
		(net 7)
	)
	(segment
		(start 147.98 70.525)
		(end 147.98 71.525)
		(width 0.15)
		(layer "B.Cu")
		(net 7)
	)
	(segment
		(start 147.951866 84.931866)
		(end 147.945 84.925)
		(width 0.25)
		(layer "B.Cu")
		(net 7)
	)
	(via
		(at 147.97 89.75)
		(size 0.45)
		(drill 0.2)
		(layers "F.Cu" "B.Cu")
		(remove_unused_layers yes)
		(keep_end_layers yes)
		(zone_layer_connections)
		(net 8)
	)
	(via
		(at 125.4 91.55)
		(size 0.45)
		(drill 0.2)
		(layers "F.Cu" "B.Cu")
		(remove_unused_layers yes)
		(keep_end_layers yes)
		(zone_layer_connections)
		(net 8)
	)
	(segment
		(start 125.389 91.539)
		(end 125.4 91.55)
		(width 0.1)
		(layer "B.Cu")
		(net 8)
	)
	(segment
		(start 125.385 91.539)
		(end 125.389 91.539)
		(width 0.1)
		(layer "B.Cu")
		(net 8)
	)
	(segment
		(start 147.3 92.1)
		(end 146.7 91.5)
		(width 0.1)
		(layer "In3.Cu")
		(net 8)
	)
	(segment
		(start 128.000002 89.599998)
		(end 133.035784 89.599998)
		(width 0.1)
		(layer "In3.Cu")
		(net 8)
	)
	(segment
		(start 146.7 91)
		(end 147 90.7)
		(width 0.1)
		(layer "In3.Cu")
		(net 8)
	)
	(segment
		(start 147.5 97.7)
		(end 148.2 97)
		(width 0.1)
		(layer "In3.Cu")
		(net 8)
	)
	(segment
		(start 145.5 98.5)
		(end 147.2 98.5)
		(width 0.1)
		(layer "In3.Cu")
		(net 8)
	)
	(segment
		(start 148.2 97)
		(end 148.2 96.7)
		(width 0.1)
		(layer "In3.Cu")
		(net 8)
	)
	(segment
		(start 147.2 98.5)
		(end 147.5 98.2)
		(width 0.1)
		(layer "In3.Cu")
		(net 8)
	)
	(segment
		(start 146.7 91.5)
		(end 146.7 91)
		(width 0.1)
		(layer "In3.Cu")
		(net 8)
	)
	(segment
		(start 147.5 98.2)
		(end 147.5 97.7)
		(width 0.1)
		(layer "In3.Cu")
		(net 8)
	)
	(segment
		(start 147.3 95.8)
		(end 147.3 92.1)
		(width 0.1)
		(layer "In3.Cu")
		(net 8)
	)
	(segment
		(start 147.3 90.7)
		(end 147.55 90.45)
		(width 0.1)
		(layer "In3.Cu")
		(net 8)
	)
	(segment
		(start 147.55 90.45)
		(end 147.55 90.17)
		(width 0.1)
		(layer "In3.Cu")
		(net 8)
	)
	(segment
		(start 139.7 98.2)
		(end 145.2 98.2)
		(width 0.1)
		(layer "In3.Cu")
		(net 8)
	)
	(segment
		(start 126.8 90.8)
		(end 128.000002 89.599998)
		(width 0.1)
		(layer "In3.Cu")
		(net 8)
	)
	(segment
		(start 126.15 90.8)
		(end 126.8 90.8)
		(width 0.1)
		(layer "In3.Cu")
		(net 8)
	)
	(segment
		(start 134.65 91.214214)
		(end 134.65 93.15)
		(width 0.1)
		(layer "In3.Cu")
		(net 8)
	)
	(segment
		(start 133.035784 89.599998)
		(end 134.65 91.214214)
		(width 0.1)
		(layer "In3.Cu")
		(net 8)
	)
	(segment
		(start 125.4 91.55)
		(end 126.15 90.8)
		(width 0.1)
		(layer "In3.Cu")
		(net 8)
	)
	(segment
		(start 134.65 93.15)
		(end 139.7 98.2)
		(width 0.1)
		(layer "In3.Cu")
		(net 8)
	)
	(segment
		(start 145.2 98.2)
		(end 145.5 98.5)
		(width 0.1)
		(layer "In3.Cu")
		(net 8)
	)
	(segment
		(start 147.55 90.17)
		(end 147.97 89.75)
		(width 0.1)
		(layer "In3.Cu")
		(net 8)
	)
	(segment
		(start 148.2 96.7)
		(end 147.3 95.8)
		(width 0.1)
		(layer "In3.Cu")
		(net 8)
	)
	(segment
		(start 147 90.7)
		(end 147.3 90.7)
		(width 0.1)
		(layer "In3.Cu")
		(net 8)
	)
	(via
		(at 137.099999 101.5)
		(size 0.45)
		(drill 0.2)
		(layers "F.Cu" "B.Cu")
		(remove_unused_layers yes)
		(keep_end_layers yes)
		(zone_layer_connections "In2.Cu")
		(net 9)
	)
	(via
		(at 135.100001 100.5)
		(size 0.45)
		(drill 0.2)
		(layers "F.Cu" "B.Cu")
		(remove_unused_layers yes)
		(keep_end_layers yes)
		(zone_layer_connections "In2.Cu")
		(net 9)
	)
	(via
		(at 139.100001 100.5)
		(size 0.45)
		(drill 0.2)
		(layers "F.Cu" "B.Cu")
		(remove_unused_layers yes)
		(keep_end_layers yes)
		(zone_layer_connections "In2.Cu")
		(net 9)
	)
	(via
		(at 140.1 100.5)
		(size 0.45)
		(drill 0.2)
		(layers "F.Cu" "B.Cu")
		(remove_unused_layers yes)
		(keep_end_layers yes)
		(zone_layer_connections "In2.Cu")
		(net 9)
	)
	(via
		(at 134.100002 101.5)
		(size 0.45)
		(drill 0.2)
		(layers "F.Cu" "B.Cu")
		(remove_unused_layers yes)
		(keep_end_layers yes)
		(zone_layer_connections "In2.Cu")
		(net 9)
	)
	(via
		(at 135.100001 101.5)
		(size 0.45)
		(drill 0.2)
		(layers "F.Cu" "B.Cu")
		(remove_unused_layers yes)
		(keep_end_layers yes)
		(zone_layer_connections "In2.Cu")
		(net 9)
	)
	(via
		(at 133.100003 100.5)
		(size 0.45)
		(drill 0.2)
		(layers "F.Cu" "B.Cu")
		(remove_unused_layers yes)
		(keep_end_layers yes)
		(zone_layer_connections "In2.Cu")
		(net 9)
	)
	(via
		(at 138.1 101.5)
		(size 0.45)
		(drill 0.2)
		(layers "F.Cu" "B.Cu")
		(remove_unused_layers yes)
		(keep_end_layers yes)
		(zone_layer_connections "In2.Cu")
		(net 9)
	)
	(via
		(at 148.835 78.25)
		(size 0.45)
		(drill 0.2)
		(layers "F.Cu" "B.Cu")
		(remove_unused_layers yes)
		(keep_end_layers yes)
		(zone_layer_connections "In2.Cu")
		(net 9)
	)
	(via
		(at 136.100001 100.5)
		(size 0.45)
		(drill 0.2)
		(layers "F.Cu" "B.Cu")
		(remove_unused_layers yes)
		(keep_end_layers yes)
		(zone_layer_connections "In2.Cu")
		(net 9)
	)
	(via
		(at 136.1 101.5)
		(size 0.45)
		(drill 0.2)
		(layers "F.Cu" "B.Cu")
		(remove_unused_layers yes)
		(keep_end_layers yes)
		(zone_layer_connections "In2.Cu")
		(net 9)
	)
	(via
		(at 152.295 81.25)
		(size 0.45)
		(drill 0.2)
		(layers "F.Cu" "B.Cu")
		(remove_unused_layers yes)
		(keep_end_layers yes)
		(zone_layer_connections "In2.Cu")
		(net 9)
	)
	(via
		(at 150.565 80.25)
		(size 0.45)
		(drill 0.2)
		(layers "F.Cu" "B.Cu")
		(remove_unused_layers yes)
		(keep_end_layers yes)
		(zone_layer_connections "In2.Cu")
		(net 9)
	)
	(via
		(at 147.105 76.25)
		(size 0.45)
		(drill 0.2)
		(layers "F.Cu" "B.Cu")
		(remove_unused_layers yes)
		(keep_end_layers yes)
		(zone_layer_connections "In2.Cu")
		(net 9)
	)
	(via
		(at 134.100003 100.5)
		(size 0.45)
		(drill 0.2)
		(layers "F.Cu" "B.Cu")
		(remove_unused_layers yes)
		(keep_end_layers yes)
		(zone_layer_connections "In2.Cu")
		(net 9)
	)
	(via
		(at 148.835 80.25)
		(size 0.45)
		(drill 0.2)
		(layers "F.Cu" "B.Cu")
		(remove_unused_layers yes)
		(keep_end_layers yes)
		(zone_layer_connections "In2.Cu")
		(net 9)
	)
	(via
		(at 139.099998 101.5)
		(size 0.45)
		(drill 0.2)
		(layers "F.Cu" "B.Cu")
		(remove_unused_layers yes)
		(keep_end_layers yes)
		(zone_layer_connections "In2.Cu")
		(net 9)
	)
	(via
		(at 138.099999 100.5)
		(size 0.45)
		(drill 0.2)
		(layers "F.Cu" "B.Cu")
		(remove_unused_layers yes)
		(keep_end_layers yes)
		(zone_layer_connections "In2.Cu")
		(net 9)
	)
	(via
		(at 148.835 81.25)
		(size 0.45)
		(drill 0.2)
		(layers "F.Cu" "B.Cu")
		(remove_unused_layers yes)
		(keep_end_layers yes)
		(zone_layer_connections "In2.Cu")
		(net 9)
	)
	(via
		(at 152.295 80.25)
		(size 0.45)
		(drill 0.2)
		(layers "F.Cu" "B.Cu")
		(remove_unused_layers yes)
		(keep_end_layers yes)
		(zone_layer_connections "In2.Cu")
		(net 9)
	)
	(via
		(at 148.835 77.25)
		(size 0.45)
		(drill 0.2)
		(layers "F.Cu" "B.Cu")
		(remove_unused_layers yes)
		(keep_end_layers yes)
		(zone_layer_connections "In2.Cu")
		(net 9)
	)
	(via
		(at 148.835 79.25)
		(size 0.45)
		(drill 0.2)
		(layers "F.Cu" "B.Cu")
		(remove_unused_layers yes)
		(keep_end_layers yes)
		(zone_layer_connections "In2.Cu")
		(net 9)
	)
	(via
		(at 174.75 78.75)
		(size 0.45)
		(drill 0.2)
		(layers "F.Cu" "B.Cu")
		(remove_unused_layers yes)
		(keep_end_layers yes)
		(zone_layer_connections)
		(net 9)
	)
	(via
		(at 145.375 75.25)
		(size 0.45)
		(drill 0.2)
		(layers "F.Cu" "B.Cu")
		(remove_unused_layers yes)
		(keep_end_layers yes)
		(zone_layer_connections "In2.Cu")
		(net 9)
	)
	(via
		(at 137.1 100.5)
		(size 0.45)
		(drill 0.2)
		(layers "F.Cu" "B.Cu")
		(remove_unused_layers yes)
		(keep_end_layers yes)
		(zone_layer_connections "In2.Cu")
		(net 9)
	)
	(via
		(at 147.105 79.25)
		(size 0.45)
		(drill 0.2)
		(layers "F.Cu" "B.Cu")
		(remove_unused_layers yes)
		(keep_end_layers yes)
		(zone_layer_connections "In2.Cu")
		(net 9)
	)
	(via
		(at 147.97 74.75)
		(size 0.45)
		(drill 0.2)
		(layers "F.Cu" "B.Cu")
		(remove_unused_layers yes)
		(keep_end_layers yes)
		(zone_layer_connections "In2.Cu")
		(net 9)
	)
	(via
		(at 147.105 78.25)
		(size 0.45)
		(drill 0.2)
		(layers "F.Cu" "B.Cu")
		(remove_unused_layers yes)
		(keep_end_layers yes)
		(zone_layer_connections "In2.Cu")
		(net 9)
	)
	(via
		(at 150.565 81.25)
		(size 0.45)
		(drill 0.2)
		(layers "F.Cu" "B.Cu")
		(remove_unused_layers yes)
		(keep_end_layers yes)
		(zone_layer_connections "In2.Cu")
		(net 9)
	)
	(via
		(at 133.100003 101.5)
		(size 0.45)
		(drill 0.2)
		(layers "F.Cu" "B.Cu")
		(remove_unused_layers yes)
		(keep_end_layers yes)
		(zone_layer_connections "In2.Cu")
		(net 9)
	)
	(via
		(at 147.105 77.25)
		(size 0.45)
		(drill 0.2)
		(layers "F.Cu" "B.Cu")
		(remove_unused_layers yes)
		(keep_end_layers yes)
		(zone_layer_connections "In2.Cu")
		(net 9)
	)
	(via
		(at 150.565 79.25)
		(size 0.45)
		(drill 0.2)
		(layers "F.Cu" "B.Cu")
		(remove_unused_layers yes)
		(keep_end_layers yes)
		(zone_layer_connections "In2.Cu")
		(net 9)
	)
	(via
		(at 147.105 80.25)
		(size 0.45)
		(drill 0.2)
		(layers "F.Cu" "B.Cu")
		(remove_unused_layers yes)
		(keep_end_layers yes)
		(zone_layer_connections "In2.Cu")
		(net 9)
	)
	(via
		(at 140.099997 101.5)
		(size 0.45)
		(drill 0.2)
		(layers "F.Cu" "B.Cu")
		(remove_unused_layers yes)
		(keep_end_layers yes)
		(zone_layer_connections "In2.Cu")
		(net 9)
	)
	(segment
		(start 147.93 75.275)
		(end 147.975 75.23)
		(width 0.5)
		(layer "B.Cu")
		(net 9)
	)
	(segment
		(start 179.91 78.75)
		(end 181.41 80.25)
		(width 0.1)
		(layer "B.Cu")
		(net 9)
	)
	(segment
		(start 147.975 75.23)
		(end 147.975 74.75)
		(width 0.5)
		(layer "B.Cu")
		(net 9)
	)
	(segment
		(start 174.75 78.75)
		(end 179.91 78.75)
		(width 0.1)
		(layer "B.Cu")
		(net 9)
	)
	(segment
		(start 183.75 80.25)
		(end 181.41 80.25)
		(width 0.1)
		(layer "B.Cu")
		(net 9)
	)
	(segment
		(start 168.15 78.75)
		(end 174.75 78.75)
		(width 0.1)
		(layer "In3.Cu")
		(net 9)
	)
	(segment
		(start 163 75.75)
		(end 165.05 77.8)
		(width 0.1)
		(layer "In3.Cu")
		(net 9)
	)
	(segment
		(start 152.295 80.25)
		(end 153.525 80.25)
		(width 0.1)
		(layer "In3.Cu")
		(net 9)
	)
	(segment
		(start 153.525 80.25)
		(end 157.275 76.5)
		(width 0.1)
		(layer "In3.Cu")
		(net 9)
	)
	(segment
		(start 167.2 77.8)
		(end 168.15 78.75)
		(width 0.1)
		(layer "In3.Cu")
		(net 9)
	)
	(segment
		(start 158.25 76.5)
		(end 159 75.75)
		(width 0.1)
		(layer "In3.Cu")
		(net 9)
	)
	(segment
		(start 159 75.75)
		(end 163 75.75)
		(width 0.1)
		(layer "In3.Cu")
		(net 9)
	)
	(segment
		(start 157.275 76.5)
		(end 158.25 76.5)
		(width 0.1)
		(layer "In3.Cu")
		(net 9)
	)
	(segment
		(start 165.05 77.8)
		(end 167.2 77.8)
		(width 0.1)
		(layer "In3.Cu")
		(net 9)
	)
	(via
		(at 148.4 94.5)
		(size 0.45)
		(drill 0.2)
		(layers "F.Cu" "B.Cu")
		(remove_unused_layers yes)
		(keep_end_layers yes)
		(zone_layer_connections "In6.Cu")
		(net 10)
	)
	(via
		(at 149 96)
		(size 0.45)
		(drill 0.2)
		(layers "F.Cu" "B.Cu")
		(remove_unused_layers yes)
		(keep_end_layers yes)
		(zone_layer_connections "In6.Cu")
		(net 10)
	)
	(via
		(at 157.485 85.25)
		(size 0.45)
		(drill 0.2)
		(layers "F.Cu" "B.Cu")
		(remove_unused_layers yes)
		(keep_end_layers yes)
		(zone_layer_connections "In6.Cu")
		(net 10)
	)
	(via
		(at 149 95)
		(size 0.45)
		(drill 0.2)
		(layers "F.Cu" "B.Cu")
		(remove_unused_layers yes)
		(keep_end_layers yes)
		(zone_layer_connections "In6.Cu")
		(net 10)
	)
	(via
		(at 149 94)
		(size 0.45)
		(drill 0.2)
		(layers "F.Cu" "B.Cu")
		(remove_unused_layers yes)
		(keep_end_layers yes)
		(zone_layer_connections "In6.Cu")
		(net 10)
	)
	(via
		(at 157.485 88.25)
		(size 0.45)
		(drill 0.2)
		(layers "F.Cu" "B.Cu")
		(remove_unused_layers yes)
		(keep_end_layers yes)
		(zone_layer_connections "In6.Cu")
		(net 10)
	)
	(via
		(at 157.485 89.25)
		(size 0.45)
		(drill 0.2)
		(layers "F.Cu" "B.Cu")
		(remove_unused_layers yes)
		(keep_end_layers yes)
		(zone_layer_connections "In6.Cu")
		(net 10)
	)
	(via
		(at 148.4 95.5)
		(size 0.45)
		(drill 0.2)
		(layers "F.Cu" "B.Cu")
		(remove_unused_layers yes)
		(keep_end_layers yes)
		(zone_layer_connections "In6.Cu")
		(net 10)
	)
	(via
		(at 157.485 84.25)
		(size 0.45)
		(drill 0.2)
		(layers "F.Cu" "B.Cu")
		(remove_unused_layers yes)
		(keep_end_layers yes)
		(zone_layer_connections "In6.Cu")
		(net 10)
	)
	(via
		(at 158.35 85.75)
		(size 0.45)
		(drill 0.2)
		(layers "F.Cu" "B.Cu")
		(remove_unused_layers yes)
		(keep_end_layers yes)
		(zone_layer_connections "In6.Cu")
		(net 10)
	)
	(via
		(at 147.97 88.75)
		(size 0.45)
		(drill 0.2)
		(layers "F.Cu" "B.Cu")
		(remove_unused_layers yes)
		(keep_end_layers yes)
		(zone_layer_connections)
		(net 11)
	)
	(via
		(at 125.4 89)
		(size 0.45)
		(drill 0.2)
		(layers "F.Cu" "B.Cu")
		(remove_unused_layers yes)
		(keep_end_layers yes)
		(zone_layer_connections)
		(net 11)
	)
	(segment
		(start 125.385 89)
		(end 125.4 89)
		(width 0.1)
		(layer "B.Cu")
		(net 11)
	)
	(segment
		(start 149.2 99.5)
		(end 149.6 99.1)
		(width 0.1)
		(layer "In3.Cu")
		(net 11)
	)
	(segment
		(start 125.4 90.2)
		(end 123.8 91.8)
		(width 0.1)
		(layer "In3.Cu")
		(net 11)
	)
	(segment
		(start 147.6 95.6)
		(end 147.6 92.6)
		(width 0.1)
		(layer "In3.Cu")
		(net 11)
	)
	(segment
		(start 132.2 95.1)
		(end 134.3 95.1)
		(width 0.1)
		(layer "In3.Cu")
		(net 11)
	)
	(segment
		(start 123.8 91.8)
		(end 123.8 93.2)
		(width 0.1)
		(layer "In3.Cu")
		(net 11)
	)
	(segment
		(start 149.6 97.6)
		(end 147.6 95.6)
		(width 0.1)
		(layer "In3.Cu")
		(net 11)
	)
	(segment
		(start 148.425 91.775)
		(end 148.425 89.225)
		(width 0.1)
		(layer "In3.Cu")
		(net 11)
	)
	(segment
		(start 128.6 93.8)
		(end 129.2 94.4)
		(width 0.1)
		(layer "In3.Cu")
		(net 11)
	)
	(segment
		(start 147.97 88.77)
		(end 147.97 88.75)
		(width 0.1)
		(layer "In3.Cu")
		(net 11)
	)
	(segment
		(start 135.4 96.2)
		(end 135.4 97.5)
		(width 0.1)
		(layer "In3.Cu")
		(net 11)
	)
	(segment
		(start 135.4 97.5)
		(end 136.5 98.6)
		(width 0.1)
		(layer "In3.Cu")
		(net 11)
	)
	(segment
		(start 148.425 89.225)
		(end 147.97 88.77)
		(width 0.1)
		(layer "In3.Cu")
		(net 11)
	)
	(segment
		(start 124.4 93.8)
		(end 128.6 93.8)
		(width 0.1)
		(layer "In3.Cu")
		(net 11)
	)
	(segment
		(start 123.8 93.2)
		(end 124.4 93.8)
		(width 0.1)
		(layer "In3.Cu")
		(net 11)
	)
	(segment
		(start 129.2 94.4)
		(end 131.5 94.4)
		(width 0.1)
		(layer "In3.Cu")
		(net 11)
	)
	(segment
		(start 137.8 98.599999)
		(end 144.799999 98.599999)
		(width 0.1)
		(layer "In3.Cu")
		(net 11)
	)
	(segment
		(start 131.5 94.4)
		(end 132.2 95.1)
		(width 0.1)
		(layer "In3.Cu")
		(net 11)
	)
	(segment
		(start 147.6 92.6)
		(end 148.425 91.775)
		(width 0.1)
		(layer "In3.Cu")
		(net 11)
	)
	(segment
		(start 136.5 98.6)
		(end 137.799999 98.6)
		(width 0.1)
		(layer "In3.Cu")
		(net 11)
	)
	(segment
		(start 149.6 99.1)
		(end 149.6 97.6)
		(width 0.1)
		(layer "In3.Cu")
		(net 11)
	)
	(segment
		(start 144.799999 98.599999)
		(end 145.7 99.5)
		(width 0.1)
		(layer "In3.Cu")
		(net 11)
	)
	(segment
		(start 145.7 99.5)
		(end 149.2 99.5)
		(width 0.1)
		(layer "In3.Cu")
		(net 11)
	)
	(segment
		(start 134.3 95.1)
		(end 135.4 96.2)
		(width 0.1)
		(layer "In3.Cu")
		(net 11)
	)
	(segment
		(start 125.4 89)
		(end 125.4 90.2)
		(width 0.1)
		(layer "In3.Cu")
		(net 11)
	)
	(segment
		(start 137.799999 98.6)
		(end 137.8 98.599999)
		(width 0.1)
		(layer "In3.Cu")
		(net 11)
	)
	(via
		(at 154.025 88.25)
		(size 0.45)
		(drill 0.2)
		(layers "F.Cu" "B.Cu")
		(remove_unused_layers yes)
		(keep_end_layers yes)
		(zone_layer_connections "In2.Cu" "In5.Cu")
		(net 12)
	)
	(via
		(at 152.95 94.3)
		(size 0.45)
		(drill 0.2)
		(layers "F.Cu" "B.Cu")
		(remove_unused_layers yes)
		(keep_end_layers yes)
		(zone_layer_connections "In2.Cu" "In5.Cu")
		(net 12)
	)
	(via
		(at 152.25 94.3)
		(size 0.45)
		(drill 0.2)
		(layers "F.Cu" "B.Cu")
		(remove_unused_layers yes)
		(keep_end_layers yes)
		(zone_layer_connections "In2.Cu" "In5.Cu")
		(net 12)
	)
	(via
		(at 152.25 93.3)
		(size 0.45)
		(drill 0.2)
		(layers "F.Cu" "B.Cu")
		(remove_unused_layers yes)
		(keep_end_layers yes)
		(zone_layer_connections "In2.Cu" "In5.Cu")
		(net 12)
	)
	(via
		(at 152.2 92.4)
		(size 0.45)
		(drill 0.2)
		(layers "F.Cu" "B.Cu")
		(remove_unused_layers yes)
		(keep_end_layers yes)
		(zone_layer_connections "In2.Cu" "In5.Cu")
		(net 12)
	)
	(via
		(at 152.95 93.3)
		(size 0.45)
		(drill 0.2)
		(layers "F.Cu" "B.Cu")
		(remove_unused_layers yes)
		(keep_end_layers yes)
		(zone_layer_connections "In2.Cu" "In5.Cu")
		(net 12)
	)
	(via
		(at 154.025 86.25)
		(size 0.45)
		(drill 0.2)
		(layers "F.Cu" "B.Cu")
		(remove_unused_layers yes)
		(keep_end_layers yes)
		(zone_layer_connections "In2.Cu" "In5.Cu")
		(net 12)
	)
	(via
		(at 152.6 93.8)
		(size 0.45)
		(drill 0.2)
		(layers "F.Cu" "B.Cu")
		(remove_unused_layers yes)
		(keep_end_layers yes)
		(zone_layer_connections "In2.Cu" "In5.Cu")
		(net 12)
	)
	(via
		(at 152.5 92.85)
		(size 0.45)
		(drill 0.2)
		(layers "F.Cu" "B.Cu")
		(remove_unused_layers yes)
		(keep_end_layers yes)
		(zone_layer_connections "In2.Cu" "In5.Cu")
		(net 12)
	)
	(via
		(at 151.85 92.85)
		(size 0.45)
		(drill 0.2)
		(layers "F.Cu" "B.Cu")
		(remove_unused_layers yes)
		(keep_end_layers yes)
		(zone_layer_connections "In2.Cu" "In5.Cu")
		(net 12)
	)
	(via
		(at 154.025 84.25)
		(size 0.45)
		(drill 0.2)
		(layers "F.Cu" "B.Cu")
		(remove_unused_layers yes)
		(keep_end_layers yes)
		(zone_layer_connections "In2.Cu" "In5.Cu")
		(net 12)
	)
	(via
		(at 154.025 85.25)
		(size 0.45)
		(drill 0.2)
		(layers "F.Cu" "B.Cu")
		(remove_unused_layers yes)
		(keep_end_layers yes)
		(zone_layer_connections "In2.Cu" "In5.Cu")
		(net 12)
	)
	(via
		(at 153.05 92.8)
		(size 0.45)
		(drill 0.2)
		(layers "F.Cu" "B.Cu")
		(remove_unused_layers yes)
		(keep_end_layers yes)
		(zone_layer_connections "In2.Cu" "In5.Cu")
		(net 12)
	)
	(segment
		(start 143 59.6)
		(end 145.4 59.6)
		(width 0.25)
		(layer "F.Cu")
		(net 13)
	)
	(segment
		(start 145.37 62.23)
		(end 145.8 61.8)
		(width 0.25)
		(layer "F.Cu")
		(net 13)
	)
	(segment
		(start 142.8 59.4)
		(end 143 59.6)
		(width 0.25)
		(layer "F.Cu")
		(net 13)
	)
	(segment
		(start 145.8 61.8)
		(end 145.8 60.7)
		(width 0.25)
		(layer "F.Cu")
		(net 13)
	)
	(segment
		(start 144.574 62.204)
		(end 144.6 62.23)
		(width 0.25)
		(layer "F.Cu")
		(net 13)
	)
	(segment
		(start 144.6 62.23)
		(end 145.37 62.23)
		(width 0.25)
		(layer "F.Cu")
		(net 13)
	)
	(segment
		(start 145.35 55.55)
		(end 145.35 56.6)
		(width 0.5)
		(layer "F.Cu")
		(net 13)
	)
	(segment
		(start 143.35 62.204)
		(end 144.574 62.204)
		(width 0.25)
		(layer "F.Cu")
		(net 13)
	)
	(segment
		(start 143.78 55.3)
		(end 145.1 55.3)
		(width 0.5)
		(layer "F.Cu")
		(net 13)
	)
	(segment
		(start 142.8 57.693)
		(end 142.8 59.4)
		(width 0.25)
		(layer "F.Cu")
		(net 13)
	)
	(segment
		(start 146.5 60.7)
		(end 145.8 60.7)
		(width 0.1)
		(layer "F.Cu")
		(net 13)
	)
	(segment
		(start 145.1 55.3)
		(end 145.35 55.55)
		(width 0.5)
		(layer "F.Cu")
		(net 13)
	)
	(segment
		(start 145.8 60.7)
		(end 145.8 60)
		(width 0.25)
		(layer "F.Cu")
		(net 13)
	)
	(segment
		(start 145.8 60)
		(end 145.4 59.6)
		(width 0.25)
		(layer "F.Cu")
		(net 13)
	)
	(segment
		(start 136.52 60.4)
		(end 135.6 60.4)
		(width 0.1)
		(layer "F.Cu")
		(net 13)
	)
	(via
		(at 135.6 60.4)
		(size 0.45)
		(drill 0.2)
		(layers "F.Cu" "B.Cu")
		(remove_unused_layers yes)
		(keep_end_layers yes)
		(zone_layer_connections)
		(net 13)
	)
	(via
		(at 146.5 60.7)
		(size 0.45)
		(drill 0.2)
		(layers "F.Cu" "B.Cu")
		(remove_unused_layers yes)
		(keep_end_layers yes)
		(zone_layer_connections)
		(net 13)
	)
	(segment
		(start 136.25 58.75)
		(end 135.6 59.4)
		(width 0.1)
		(layer "B.Cu")
		(net 13)
	)
	(segment
		(start 136.25 57.75)
		(end 136.25 58.75)
		(width 0.1)
		(layer "B.Cu")
		(net 13)
	)
	(segment
		(start 135.6 60.4)
		(end 143 60.4)
		(width 0.1)
		(layer "B.Cu")
		(net 13)
	)
	(segment
		(start 143.3 60.7)
		(end 146.5 60.7)
		(width 0.1)
		(layer "B.Cu")
		(net 13)
	)
	(segment
		(start 135.6 59.4)
		(end 135.6 60.4)
		(width 0.1)
		(layer "B.Cu")
		(net 13)
	)
	(segment
		(start 143 60.4)
		(end 143.3 60.7)
		(width 0.1)
		(layer "B.Cu")
		(net 13)
	)
	(via
		(at 164.85 94.4)
		(size 0.45)
		(drill 0.2)
		(layers "F.Cu" "B.Cu")
		(remove_unused_layers yes)
		(keep_end_layers yes)
		(zone_layer_connections "In2.Cu")
		(net 14)
	)
	(via
		(at 159.215 84.25)
		(size 0.45)
		(drill 0.2)
		(layers "F.Cu" "B.Cu")
		(remove_unused_layers yes)
		(keep_end_layers yes)
		(zone_layer_connections "In2.Cu")
		(net 14)
	)
	(via
		(at 159.215 82.25)
		(size 0.45)
		(drill 0.2)
		(layers "F.Cu" "B.Cu")
		(remove_unused_layers yes)
		(keep_end_layers yes)
		(zone_layer_connections "In2.Cu")
		(net 14)
	)
	(via
		(at 159.215 85.25)
		(size 0.45)
		(drill 0.2)
		(layers "F.Cu" "B.Cu")
		(remove_unused_layers yes)
		(keep_end_layers yes)
		(zone_layer_connections "In2.Cu")
		(net 14)
	)
	(via
		(at 163.85 94.4)
		(size 0.45)
		(drill 0.2)
		(layers "F.Cu" "B.Cu")
		(remove_unused_layers yes)
		(keep_end_layers yes)
		(zone_layer_connections "In2.Cu")
		(net 14)
	)
	(via
		(at 159.215 83.25)
		(size 0.45)
		(drill 0.2)
		(layers "F.Cu" "B.Cu")
		(remove_unused_layers yes)
		(keep_end_layers yes)
		(zone_layer_connections "In2.Cu")
		(net 14)
	)
	(via
		(at 163.85 93.4)
		(size 0.45)
		(drill 0.2)
		(layers "F.Cu" "B.Cu")
		(remove_unused_layers yes)
		(keep_end_layers yes)
		(zone_layer_connections "In2.Cu")
		(net 14)
	)
	(via
		(at 164.85 93.4)
		(size 0.45)
		(drill 0.2)
		(layers "F.Cu" "B.Cu")
		(remove_unused_layers yes)
		(keep_end_layers yes)
		(zone_layer_connections "In2.Cu")
		(net 14)
	)
	(via
		(at 146.24 88.75)
		(size 0.45)
		(drill 0.2)
		(layers "F.Cu" "B.Cu")
		(remove_unused_layers yes)
		(keep_end_layers yes)
		(zone_layer_connections)
		(net 15)
	)
	(via
		(at 125.4 86.45)
		(size 0.45)
		(drill 0.2)
		(layers "F.Cu" "B.Cu")
		(remove_unused_layers yes)
		(keep_end_layers yes)
		(zone_layer_connections)
		(net 15)
	)
	(segment
		(start 125.385 86.46)
		(end 125.39 86.46)
		(width 0.1)
		(layer "B.Cu")
		(net 15)
	)
	(segment
		(start 125.39 86.46)
		(end 125.4 86.45)
		(width 0.1)
		(layer "B.Cu")
		(net 15)
	)
	(segment
		(start 144.3 91.25)
		(end 144.05 91)
		(width 0.1)
		(layer "In3.Cu")
		(net 15)
	)
	(segment
		(start 144.5 97.3)
		(end 146.2 95.6)
		(width 0.1)
		(layer "In3.Cu")
		(net 15)
	)
	(segment
		(start 135.85 90.675)
		(end 135.85 92.65)
		(width 0.1)
		(layer "In3.Cu")
		(net 15)
	)
	(segment
		(start 125.4 86.45)
		(end 126.45 86.45)
		(width 0.1)
		(layer "In3.Cu")
		(net 15)
	)
	(segment
		(start 133.575 88.4)
		(end 135.85 90.675)
		(width 0.1)
		(layer "In3.Cu")
		(net 15)
	)
	(segment
		(start 128.4 88.4)
		(end 133.575 88.4)
		(width 0.1)
		(layer "In3.Cu")
		(net 15)
	)
	(segment
		(start 144.05 89.95)
		(end 145.25 88.75)
		(width 0.1)
		(layer "In3.Cu")
		(net 15)
	)
	(segment
		(start 135.85 92.65)
		(end 140.5 97.3)
		(width 0.1)
		(layer "In3.Cu")
		(net 15)
	)
	(segment
		(start 126.45 86.45)
		(end 128.4 88.4)
		(width 0.1)
		(layer "In3.Cu")
		(net 15)
	)
	(segment
		(start 145.25 88.75)
		(end 146.24 88.75)
		(width 0.1)
		(layer "In3.Cu")
		(net 15)
	)
	(segment
		(start 144.05 91)
		(end 144.05 89.95)
		(width 0.1)
		(layer "In3.Cu")
		(net 15)
	)
	(segment
		(start 146.2 95.6)
		(end 146.2 92.8)
		(width 0.1)
		(layer "In3.Cu")
		(net 15)
	)
	(segment
		(start 146.2 92.8)
		(end 144.65 91.25)
		(width 0.1)
		(layer "In3.Cu")
		(net 15)
	)
	(segment
		(start 144.65 91.25)
		(end 144.3 91.25)
		(width 0.1)
		(layer "In3.Cu")
		(net 15)
	)
	(segment
		(start 140.5 97.3)
		(end 144.5 97.3)
		(width 0.1)
		(layer "In3.Cu")
		(net 15)
	)
	(via
		(at 147.105 89.25)
		(size 0.45)
		(drill 0.2)
		(layers "F.Cu" "B.Cu")
		(remove_unused_layers yes)
		(keep_end_layers yes)
		(zone_layer_connections)
		(net 16)
	)
	(via
		(at 126.65 90.25)
		(size 0.45)
		(drill 0.2)
		(layers "F.Cu" "B.Cu")
		(remove_unused_layers yes)
		(keep_end_layers yes)
		(zone_layer_connections)
		(net 16)
	)
	(segment
		(start 126.654 90.269)
		(end 126.654 90.254)
		(width 0.1)
		(layer "B.Cu")
		(net 16)
	)
	(segment
		(start 126.654 90.254)
		(end 126.65 90.25)
		(width 0.1)
		(layer "B.Cu")
		(net 16)
	)
	(segment
		(start 145.75 90.6)
		(end 146.1 90.25)
		(width 0.1)
		(layer "In3.Cu")
		(net 16)
	)
	(segment
		(start 133.201473 89.199999)
		(end 135.050001 91.048527)
		(width 0.1)
		(layer "In3.Cu")
		(net 16)
	)
	(segment
		(start 145.1 97.9)
		(end 145.7 97.3)
		(width 0.1)
		(layer "In3.Cu")
		(net 16)
	)
	(segment
		(start 146.35 90.25)
		(end 146.65 89.95)
		(width 0.1)
		(layer "In3.Cu")
		(net 16)
	)
	(segment
		(start 126.65 90.25)
		(end 127.700001 89.199999)
		(width 0.1)
		(layer "In3.Cu")
		(net 16)
	)
	(segment
		(start 145.7 97.3)
		(end 146.7 97.3)
		(width 0.1)
		(layer "In3.Cu")
		(net 16)
	)
	(segment
		(start 147 97)
		(end 147 92.35)
		(width 0.1)
		(layer "In3.Cu")
		(net 16)
	)
	(segment
		(start 135.050001 92.950001)
		(end 140 97.9)
		(width 0.1)
		(layer "In3.Cu")
		(net 16)
	)
	(segment
		(start 140 97.9)
		(end 145.1 97.9)
		(width 0.1)
		(layer "In3.Cu")
		(net 16)
	)
	(segment
		(start 146.8 89.25)
		(end 147.105 89.25)
		(width 0.1)
		(layer "In3.Cu")
		(net 16)
	)
	(segment
		(start 145.75 91.1)
		(end 145.75 90.6)
		(width 0.1)
		(layer "In3.Cu")
		(net 16)
	)
	(segment
		(start 146.7 97.3)
		(end 147 97)
		(width 0.1)
		(layer "In3.Cu")
		(net 16)
	)
	(segment
		(start 146.65 89.4)
		(end 146.8 89.25)
		(width 0.1)
		(layer "In3.Cu")
		(net 16)
	)
	(segment
		(start 146.1 90.25)
		(end 146.35 90.25)
		(width 0.1)
		(layer "In3.Cu")
		(net 16)
	)
	(segment
		(start 146.65 89.95)
		(end 146.65 89.4)
		(width 0.1)
		(layer "In3.Cu")
		(net 16)
	)
	(segment
		(start 147 92.35)
		(end 145.75 91.1)
		(width 0.1)
		(layer "In3.Cu")
		(net 16)
	)
	(segment
		(start 127.700001 89.199999)
		(end 133.201473 89.199999)
		(width 0.1)
		(layer "In3.Cu")
		(net 16)
	)
	(segment
		(start 135.050001 91.048527)
		(end 135.050001 92.950001)
		(width 0.1)
		(layer "In3.Cu")
		(net 16)
	)
	(segment
		(start 120.148 103.352)
		(end 120.648 103.352)
		(width 0.1)
		(layer "F.Cu")
		(net 17)
	)
	(segment
		(start 120.75 102.85)
		(end 120.4 102.5)
		(width 0.1)
		(layer "F.Cu")
		(net 17)
	)
	(segment
		(start 120.75 103.25)
		(end 120.75 102.85)
		(width 0.1)
		(layer "F.Cu")
		(net 17)
	)
	(segment
		(start 115.92 104.1)
		(end 115.9 104.1)
		(width 0.25)
		(layer "F.Cu")
		(net 17)
	)
	(segment
		(start 120.648 103.352)
		(end 120.75 103.25)
		(width 0.1)
		(layer "F.Cu")
		(net 17)
	)
	(segment
		(start 120.4 102.5)
		(end 120.35 102.5)
		(width 0.1)
		(layer "F.Cu")
		(net 17)
	)
	(via
		(at 120.35 102.5)
		(size 0.45)
		(drill 0.2)
		(layers "F.Cu" "B.Cu")
		(remove_unused_layers yes)
		(keep_end_layers yes)
		(zone_layer_connections)
		(net 17)
	)
	(via
		(at 115.9 104.1)
		(size 0.45)
		(drill 0.2)
		(layers "F.Cu" "B.Cu")
		(remove_unused_layers yes)
		(keep_end_layers yes)
		(zone_layer_connections)
		(net 17)
	)
	(via
		(at 117.5 99.75)
		(size 0.45)
		(drill 0.2)
		(layers "F.Cu" "B.Cu")
		(remove_unused_layers yes)
		(keep_end_layers yes)
		(zone_layer_connections)
		(net 17)
	)
	(segment
		(start 117.5 101)
		(end 116.45 102.05)
		(width 0.1)
		(layer "B.Cu")
		(net 17)
	)
	(segment
		(start 116.45 102.05)
		(end 116.45 103.55)
		(width 0.1)
		(layer "B.Cu")
		(net 17)
	)
	(segment
		(start 117.5 99.75)
		(end 117.5 101)
		(width 0.1)
		(layer "B.Cu")
		(net 17)
	)
	(segment
		(start 116.45 103.55)
		(end 115.9 104.1)
		(width 0.1)
		(layer "B.Cu")
		(net 17)
	)
	(segment
		(start 119.35 102.5)
		(end 117.5 100.65)
		(width 0.1)
		(layer "In3.Cu")
		(net 17)
	)
	(segment
		(start 120.35 102.5)
		(end 119.35 102.5)
		(width 0.1)
		(layer "In3.Cu")
		(net 17)
	)
	(segment
		(start 117.5 100.65)
		(end 117.5 99.75)
		(width 0.1)
		(layer "In3.Cu")
		(net 17)
	)
	(segment
		(start 165.02 67.02)
		(end 165 67)
		(width 0.25)
		(layer "F.Cu")
		(net 18)
	)
	(segment
		(start 164.48 80.4)
		(end 165.3 80.4)
		(width 0.1)
		(layer "F.Cu")
		(net 18)
	)
	(segment
		(start 168.862 77.338)
		(end 168.7 77.5)
		(width 0.25)
		(layer "F.Cu")
		(net 18)
	)
	(segment
		(start 165.162 67.942)
		(end 165.02 67.8)
		(width 0.25)
		(layer "F.Cu")
		(net 18)
	)
	(segment
		(start 164.08 67.8)
		(end 165.02 67.8)
		(width 0.1)
		(layer "F.Cu")
		(net 18)
	)
	(segment
		(start 174.341 79.341)
		(end 174.4 79.4)
		(width 0.1)
		(layer "F.Cu")
		(net 18)
	)
	(segment
		(start 165.162 73.825999)
		(end 165.162 69.526999)
		(width 0.25)
		(layer "F.Cu")
		(net 18)
	)
	(segment
		(start 169.852 77.338)
		(end 168.862 77.338)
		(width 0.25)
		(layer "F.Cu")
		(net 18)
	)
	(segment
		(start 165.162 69.526999)
		(end 165.162 67.942)
		(width 0.25)
		(layer "F.Cu")
		(net 18)
	)
	(segment
		(start 169.739 79.361)
		(end 169.7 79.4)
		(width 0.1)
		(layer "F.Cu")
		(net 18)
	)
	(segment
		(start 170.375 79.361)
		(end 169.739 79.361)
		(width 0.1)
		(layer "F.Cu")
		(net 18)
	)
	(segment
		(start 165.02 67.8)
		(end 165.02 67.02)
		(width 0.25)
		(layer "F.Cu")
		(net 18)
	)
	(segment
		(start 174.151 77.338)
		(end 169.852 77.338)
		(width 0.1)
		(layer "F.Cu")
		(net 18)
	)
	(segment
		(start 173.585 79.341)
		(end 174.341 79.341)
		(width 0.1)
		(layer "F.Cu")
		(net 18)
	)
	(segment
		(start 164.48 77.4)
		(end 165.3 77.4)
		(width 0.1)
		(layer "F.Cu")
		(net 18)
	)
	(segment
		(start 168 77.48)
		(end 168.68 77.48)
		(width 0.25)
		(layer "F.Cu")
		(net 18)
	)
	(segment
		(start 168.68 77.48)
		(end 168.7 77.5)
		(width 0.25)
		(layer "F.Cu")
		(net 18)
	)
	(via
		(at 151.43 89.75)
		(size 0.45)
		(drill 0.2)
		(layers "F.Cu" "B.Cu")
		(remove_unused_layers yes)
		(keep_end_layers yes)
		(zone_layer_connections "In6.Cu")
		(net 18)
	)
	(via
		(at 147 98)
		(size 0.45)
		(drill 0.2)
		(layers "F.Cu" "B.Cu")
		(remove_unused_layers yes)
		(keep_end_layers yes)
		(zone_layer_connections "In2.Cu" "In6.Cu")
		(net 18)
	)
	(via
		(at 155.755 83.25)
		(size 0.45)
		(drill 0.2)
		(layers "F.Cu" "B.Cu")
		(remove_unused_layers yes)
		(keep_end_layers yes)
		(zone_layer_connections "In6.Cu")
		(net 18)
	)
	(via
		(at 149 99)
		(size 0.45)
		(drill 0.2)
		(layers "F.Cu" "B.Cu")
		(remove_unused_layers yes)
		(keep_end_layers yes)
		(zone_layer_connections "In2.Cu" "In6.Cu")
		(net 18)
	)
	(via
		(at 162.75 128.25)
		(size 0.45)
		(drill 0.2)
		(layers "F.Cu" "B.Cu")
		(remove_unused_layers yes)
		(keep_end_layers yes)
		(zone_layer_connections)
		(net 18)
	)
	(via
		(at 146.999999 99)
		(size 0.45)
		(drill 0.2)
		(layers "F.Cu" "B.Cu")
		(remove_unused_layers yes)
		(keep_end_layers yes)
		(zone_layer_connections "In2.Cu" "In6.Cu")
		(net 18)
	)
	(via
		(at 174.4 79.4)
		(size 0.45)
		(drill 0.2)
		(layers "F.Cu" "B.Cu")
		(remove_unused_layers yes)
		(keep_end_layers yes)
		(zone_layer_connections "In2.Cu")
		(net 18)
	)
	(via
		(at 165.3 80.4)
		(size 0.45)
		(drill 0.2)
		(layers "F.Cu" "B.Cu")
		(remove_unused_layers yes)
		(keep_end_layers yes)
		(zone_layer_connections "In2.Cu")
		(net 18)
	)
	(via
		(at 148.000001 99)
		(size 0.45)
		(drill 0.2)
		(layers "F.Cu" "B.Cu")
		(remove_unused_layers yes)
		(keep_end_layers yes)
		(zone_layer_connections "In2.Cu" "In6.Cu")
		(net 18)
	)
	(via
		(at 155.755 89.25)
		(size 0.45)
		(drill 0.2)
		(layers "F.Cu" "B.Cu")
		(remove_unused_layers yes)
		(keep_end_layers yes)
		(zone_layer_connections "In6.Cu")
		(net 18)
	)
	(via
		(at 169.7 79.4)
		(size 0.45)
		(drill 0.2)
		(layers "F.Cu" "B.Cu")
		(remove_unused_layers yes)
		(keep_end_layers yes)
		(zone_layer_connections "In2.Cu")
		(net 18)
	)
	(via
		(at 148 98)
		(size 0.45)
		(drill 0.2)
		(layers "F.Cu" "B.Cu")
		(remove_unused_layers yes)
		(keep_end_layers yes)
		(zone_layer_connections "In2.Cu" "In6.Cu")
		(net 18)
	)
	(via
		(at 168.7 77.5)
		(size 0.45)
		(drill 0.2)
		(layers "F.Cu" "B.Cu")
		(remove_unused_layers yes)
		(keep_end_layers yes)
		(zone_layer_connections "In2.Cu")
		(net 18)
	)
	(via
		(at 146 98)
		(size 0.45)
		(drill 0.2)
		(layers "F.Cu" "B.Cu")
		(remove_unused_layers yes)
		(keep_end_layers yes)
		(zone_layer_connections "In2.Cu" "In6.Cu")
		(net 18)
	)
	(via
		(at 165 67)
		(size 0.45)
		(drill 0.2)
		(layers "F.Cu" "B.Cu")
		(remove_unused_layers yes)
		(keep_end_layers yes)
		(zone_layer_connections "In2.Cu")
		(net 18)
	)
	(via
		(at 152.295 90.25)
		(size 0.45)
		(drill 0.2)
		(layers "F.Cu" "B.Cu")
		(remove_unused_layers yes)
		(keep_end_layers yes)
		(zone_layer_connections "In6.Cu")
		(net 18)
	)
	(via
		(at 149 98)
		(size 0.45)
		(drill 0.2)
		(layers "F.Cu" "B.Cu")
		(remove_unused_layers yes)
		(keep_end_layers yes)
		(zone_layer_connections "In2.Cu" "In6.Cu")
		(net 18)
	)
	(via
		(at 162.8 77.7)
		(size 0.45)
		(drill 0.2)
		(layers "F.Cu" "B.Cu")
		(remove_unused_layers yes)
		(keep_end_layers yes)
		(zone_layer_connections "In2.Cu")
		(net 18)
	)
	(via
		(at 163.5 128.25)
		(size 0.45)
		(drill 0.2)
		(layers "F.Cu" "B.Cu")
		(remove_unused_layers yes)
		(keep_end_layers yes)
		(zone_layer_connections)
		(net 18)
	)
	(via
		(at 165.3 77.4)
		(size 0.45)
		(drill 0.2)
		(layers "F.Cu" "B.Cu")
		(remove_unused_layers yes)
		(keep_end_layers yes)
		(zone_layer_connections "In2.Cu")
		(net 18)
	)
	(via
		(at 146 99)
		(size 0.45)
		(drill 0.2)
		(layers "F.Cu" "B.Cu")
		(remove_unused_layers yes)
		(keep_end_layers yes)
		(zone_layer_connections "In2.Cu" "In6.Cu")
		(net 18)
	)
	(segment
		(start 152.714 91.563189)
		(end 152.8 91.477189)
		(width 0.15)
		(layer "B.Cu")
		(net 18)
	)
	(segment
		(start 153.62 92.005)
		(end 153.424 92.201)
		(width 0.15)
		(layer "B.Cu")
		(net 18)
	)
	(segment
		(start 163.5 128.25)
		(end 162.75 128.25)
		(width 0.75)
		(layer "B.Cu")
		(net 18)
	)
	(segment
		(start 162.55 130.5)
		(end 162.55 132)
		(width 0.75)
		(layer "B.Cu")
		(net 18)
	)
	(segment
		(start 151.849 87.849)
		(end 151.849 82.896)
		(width 0.15)
		(layer "B.Cu")
		(net 18)
	)
	(segment
		(start 151.43 89.75)
		(end 151.43 89.966981)
		(width 0.5)
		(layer "B.Cu")
		(net 18)
	)
	(segment
		(start 152.3 90.525)
		(end 152.3 90.055)
		(width 0.15)
		(layer "B.Cu")
		(net 18)
	)
	(segment
		(start 152.295 90.101983)
		(end 152.381866 90.015117)
		(width 0.5)
		(layer "B.Cu")
		(net 18)
	)
	(segment
		(start 152.978189 92.201)
		(end 152.714 91.936811)
		(width 0.15)
		(layer "B.Cu")
		(net 18)
	)
	(segment
		(start 151.43 89.966981)
		(end 151.381865 90.015116)
		(width 0.5)
		(layer "B.Cu")
		(net 18)
	)
	(segment
		(start 150.901868 90.015116)
		(end 150.231867 90.685117)
		(width 0.5)
		(layer "B.Cu")
		(net 18)
	)
	(segment
		(start 151.849 82.896)
		(end 152.52 82.225)
		(width 0.15)
		(layer "B.Cu")
		(net 18)
	)
	(segment
		(start 174.4 79.4)
		(end 178.45 79.4)
		(width 0.1)
		(layer "B.Cu")
		(net 18)
	)
	(segment
		(start 183.75 81.75)
		(end 180.8 81.75)
		(width 0.1)
		(layer "B.Cu")
		(net 18)
	)
	(segment
		(start 154.2 92.005)
		(end 153.62 92.005)
		(width 0.15)
		(layer "B.Cu")
		(net 18)
	)
	(segment
		(start 162.75 128.25)
		(end 162.75 129.23)
		(width 0.75)
		(layer "B.Cu")
		(net 18)
	)
	(segment
		(start 153.05 89.225)
		(end 153.05 88.505)
		(width 0.15)
		(layer "B.Cu")
		(net 18)
	)
	(segment
		(start 162.861866 76.985117)
		(end 162.861866 77.638134)
		(width 0.1)
		(layer "B.Cu")
		(net 18)
	)
	(segment
		(start 151.381865 90.015116)
		(end 150.901868 90.015116)
		(width 0.5)
		(layer "B.Cu")
		(net 18)
	)
	(segment
		(start 162.55 130.5)
		(end 162.55 129.47)
		(width 0.75)
		(layer "B.Cu")
		(net 18)
	)
	(segment
		(start 153.424 92.201)
		(end 152.978189 92.201)
		(width 0.15)
		(layer "B.Cu")
		(net 18)
	)
	(segment
		(start 152.3 90.055)
		(end 152.35 90.005)
		(width 0.15)
		(layer "B.Cu")
		(net 18)
	)
	(segment
		(start 152.714 91.936811)
		(end 152.714 91.563189)
		(width 0.15)
		(layer "B.Cu")
		(net 18)
	)
	(segment
		(start 152.65 88.105)
		(end 152.105 88.105)
		(width 0.15)
		(layer "B.Cu")
		(net 18)
	)
	(segment
		(start 162.861866 77.638134)
		(end 162.8 77.7)
		(width 0.1)
		(layer "B.Cu")
		(net 18)
	)
	(segment
		(start 178.45 79.4)
		(end 180.8 81.75)
		(width 0.1)
		(layer "B.Cu")
		(net 18)
	)
	(segment
		(start 152.35 89.925)
		(end 153.05 89.225)
		(width 0.15)
		(layer "B.Cu")
		(net 18)
	)
	(segment
		(start 152.8 91.477189)
		(end 152.8 91.025)
		(width 0.15)
		(layer "B.Cu")
		(net 18)
	)
	(segment
		(start 162.55 129.47)
		(end 162.77 129.25)
		(width 0.75)
		(layer "B.Cu")
		(net 18)
	)
	(segment
		(start 152.8 91.025)
		(end 152.3 90.525)
		(width 0.15)
		(layer "B.Cu")
		(net 18)
	)
	(segment
		(start 152.35 90.005)
		(end 152.35 89.925)
		(width 0.15)
		(layer "B.Cu")
		(net 18)
	)
	(segment
		(start 153.05 88.505)
		(end 152.65 88.105)
		(width 0.15)
		(layer "B.Cu")
		(net 18)
	)
	(segment
		(start 152.105 88.105)
		(end 151.849 87.849)
		(width 0.15)
		(layer "B.Cu")
		(net 18)
	)
	(segment
		(start 162.75 129.23)
		(end 162.77 129.25)
		(width 0.75)
		(layer "B.Cu")
		(net 18)
	)
	(segment
		(start 152.295 90.25)
		(end 152.295 90.101983)
		(width 0.5)
		(layer "B.Cu")
		(net 18)
	)
	(segment
		(start 149.4 117.8)
		(end 159.85 128.25)
		(width 1)
		(layer "In5.Cu")
		(net 18)
	)
	(segment
		(start 159.85 128.25)
		(end 162.75 128.25)
		(width 1)
		(layer "In5.Cu")
		(net 18)
	)
	(segment
		(start 163.5 128.25)
		(end 162.75 128.25)
		(width 1)
		(layer "In5.Cu")
		(net 18)
	)
	(segment
		(start 146.999999 99)
		(end 146.999999 108.749999)
		(width 1)
		(layer "In5.Cu")
		(net 18)
	)
	(segment
		(start 149.4 111.15)
		(end 149.4 117.8)
		(width 1)
		(layer "In5.Cu")
		(net 18)
	)
	(segment
		(start 146.999999 99)
		(end 147 98)
		(width 1)
		(layer "In5.Cu")
		(net 18)
	)
	(segment
		(start 146.999999 108.749999)
		(end 149.4 111.15)
		(width 1)
		(layer "In5.Cu")
		(net 18)
	)
	(segment
		(start 139.02 145.5)
		(end 139.02 144.68)
		(width 0.25)
		(layer "F.Cu")
		(net 19)
	)
	(segment
		(start 139.02 144.68)
		(end 139.5 144.2)
		(width 0.25)
		(layer "F.Cu")
		(net 19)
	)
	(via
		(at 158.35 87.75)
		(size 0.45)
		(drill 0.2)
		(layers "F.Cu" "B.Cu")
		(remove_unused_layers yes)
		(keep_end_layers yes)
		(zone_layer_connections "In2.Cu")
		(net 20)
	)
	(via
		(at 146.355 96.675)
		(size 0.45)
		(drill 0.2)
		(layers "F.Cu" "B.Cu")
		(remove_unused_layers yes)
		(keep_end_layers yes)
		(zone_layer_connections "In2.Cu")
		(net 20)
	)
	(via
		(at 153.7 92.95)
		(size 0.45)
		(drill 0.2)
		(layers "F.Cu" "B.Cu")
		(remove_unused_layers yes)
		(keep_end_layers yes)
		(free yes)
		(zone_layer_connections "In5.Cu")
		(net 21)
	)
	(via
		(at 154.025 87.25)
		(size 0.45)
		(drill 0.2)
		(layers "F.Cu" "B.Cu")
		(remove_unused_layers yes)
		(keep_end_layers yes)
		(zone_layer_connections "In5.Cu")
		(net 21)
	)
	(via
		(at 154.35 92.95)
		(size 0.45)
		(drill 0.2)
		(layers "F.Cu" "B.Cu")
		(remove_unused_layers yes)
		(keep_end_layers yes)
		(free yes)
		(zone_layer_connections "In5.Cu")
		(net 21)
	)
	(segment
		(start 153.7 92.95)
		(end 154.35 92.95)
		(width 0.5)
		(layer "In5.Cu")
		(net 21)
	)
	(via
		(at 155.755 90.25)
		(size 0.45)
		(drill 0.2)
		(layers "F.Cu" "B.Cu")
		(remove_unused_layers yes)
		(keep_end_layers yes)
		(zone_layer_connections)
		(net 22)
	)
	(segment
		(start 124.999 149.549)
		(end 125 149.55)
		(width 0.25)
		(layer "F.Cu")
		(net 23)
	)
	(segment
		(start 133.685 125.79)
		(end 133.875 125.6)
		(width 0.1)
		(layer "F.Cu")
		(net 23)
	)
	(segment
		(start 143.35 61.253)
		(end 144.583 61.253)
		(width 0.25)
		(layer "F.Cu")
		(net 23)
	)
	(segment
		(start 139.991421 119.45)
		(end 139.991421 119.491421)
		(width 0.1)
		(layer "F.Cu")
		(net 23)
	)
	(segment
		(start 130.125 125.575)
		(end 130.45 125.25)
		(width 0.1)
		(layer "F.Cu")
		(net 23)
	)
	(segment
		(start 142.750002 109.150002)
		(end 142.5 108.9)
		(width 0.1)
		(layer "F.Cu")
		(net 23)
	)
	(segment
		(start 129.8 120.05)
		(end 129.8 119.89)
		(width 0.1)
		(layer "F.Cu")
		(net 23)
	)
	(segment
		(start 124.6 121.35)
		(end 124.116 120.866)
		(width 0.1)
		(layer "F.Cu")
		(net 23)
	)
	(segment
		(start 126.66 128.55)
		(end 126.66 128.334)
		(width 0.1)
		(layer "F.Cu")
		(net 23)
	)
	(segment
		(start 137.5 133.884)
		(end 137.864 133.52)
		(width 0.1)
		(layer "F.Cu")
		(net 23)
	)
	(segment
		(start 128.5 119.35)
		(end 128.5 119.134)
		(width 0.1)
		(layer "F.Cu")
		(net 23)
	)
	(segment
		(start 118.4 71.8)
		(end 118.95 71.8)
		(width 0.25)
		(layer "F.Cu")
		(net 23)
	)
	(segment
		(start 131.26 119.35)
		(end 131.26 119.134)
		(width 0.1)
		(layer "F.Cu")
		(net 23)
	)
	(segment
		(start 125.9 125.25)
		(end 126.225 124.925)
		(width 0.1)
		(layer "F.Cu")
		(net 23)
	)
	(segment
		(start 124.116 120.534)
		(end 124.116 120.73)
		(width 0.1)
		(layer "F.Cu")
		(net 23)
	)
	(segment
		(start 158.944999 97.434999)
		(end 158.944999 98.155001)
		(width 0.1)
		(layer "F.Cu")
		(net 23)
	)
	(segment
		(start 125.25 125.25)
		(end 125.575 124.925)
		(width 0.1)
		(layer "F.Cu")
		(net 23)
	)
	(segment
		(start 125.74 118.89)
		(end 125.74 119.14)
		(width 0.1)
		(layer "F.Cu")
		(net 23)
	)
	(segment
		(start 126.66 129.01)
		(end 126.66 128.55)
		(width 0.1)
		(layer "F.Cu")
		(net 23)
	)
	(segment
		(start 141.5 123.65)
		(end 141.5 123.75)
		(width 0.1)
		(layer "F.Cu")
		(net 23)
	)
	(segment
		(start 133.1 128.55)
		(end 133.56 128.55)
		(width 0.1)
		(layer "F.Cu")
		(net 23)
	)
	(segment
		(start 129.8 121.95)
		(end 129.5 121.65)
		(width 0.1)
		(layer "F.Cu")
		(net 23)
	)
	(segment
		(start 117.52 141.498)
		(end 117.546 141.524)
		(width 0.25)
		(layer "F.Cu")
		(net 23)
	)
	(segment
		(start 124.116 122.484)
		(end 124.116 122.57)
		(width 0.1)
		(layer "F.Cu")
		(net 23)
	)
	(segment
		(start 127.801 58.825)
		(end 131.624561 58.825)
		(width 0.75)
		(layer "F.Cu")
		(net 23)
	)
	(segment
		(start 131.1 126.55)
		(end 131.75 127.2)
		(width 0.1)
		(layer "F.Cu")
		(net 23)
	)
	(segment
		(start 117.546 141.524)
		(end 117.546 142.454)
		(width 0.25)
		(layer "F.Cu")
		(net 23)
	)
	(segment
		(start 118.701 131.2)
		(end 118.601 131.1)
		(width 0.25)
		(layer "F.Cu")
		(net 23)
	)
	(segment
		(start 131.425 127.525)
		(end 131.1 127.2)
		(width 0.1)
		(layer "F.Cu")
		(net 23)
	)
	(segment
		(start 162.78 45.82)
		(end 162.8 45.8)
		(width 0.1)
		(layer "F.Cu")
		(net 23)
	)
	(segment
		(start 123.9 124.41)
		(end 124.41 124.41)
		(width 0.1)
		(layer "F.Cu")
		(net 23)
	)
	(segment
		(start 125.249 146.751)
		(end 125.25 146.75)
		(width 0.25)
		(layer "F.Cu")
		(net 23)
	)
	(segment
		(start 131.75 126.55)
		(end 132.075 126.875)
		(width 0.1)
		(layer "F.Cu")
		(net 23)
	)
	(segment
		(start 135 137)
		(end 135.25 137.25)
		(width 0.1)
		(layer "F.Cu")
		(net 23)
	)
	(segment
		(start 141.915 79.25)
		(end 141.915 78.25)
		(width 0.3)
		(layer "F.Cu")
		(net 23)
	)
	(segment
		(start 116 139.7)
		(end 116 140.5)
		(width 0.1)
		(layer "F.Cu")
		(net 23)
	)
	(segment
		(start 133.56 124.87)
		(end 133.98 124.87)
		(width 0.1)
		(layer "F.Cu")
		(net 23)
	)
	(segment
		(start 126.55 125.9)
		(end 126.875 126.225)
		(width 0.1)
		(layer "F.Cu")
		(net 23)
	)
	(segment
		(start 138.600003 92.600003)
		(end 139.4 93.4)
		(width 0.5)
		(layer "F.Cu")
		(net 23)
	)
	(segment
		(start 135.67 109.150001)
		(end 134.750001 109.150001)
		(width 0.1)
		(layer "F.Cu")
		(net 23)
	)
	(segment
		(start 123.9 128.55)
		(end 123.9 128.09)
		(width 0.1)
		(layer "F.Cu")
		(net 23)
	)
	(segment
		(start 127.85 123.3)
		(end 128.175 123.625)
		(width 0.1)
		(layer "F.Cu")
		(net 23)
	)
	(segment
		(start 119.75 71.75)
		(end 120.5 71)
		(width 0.25)
		(layer "F.Cu")
		(net 23)
	)
	(segment
		(start 132.075 124.275)
		(end 131.75 123.95)
		(width 0.1)
		(layer "F.Cu")
		(net 23)
	)
	(segment
		(start 127.525 122.975)
		(end 127.2 123.3)
		(width 0.1)
		(layer "F.Cu")
		(net 23)
	)
	(segment
		(start 132.075 127.525)
		(end 131.75 127.2)
		(width 0.1)
		(layer "F.Cu")
		(net 23)
	)
	(segment
		(start 124.999 149.1)
		(end 124.999 148.501)
		(width 0.25)
		(layer "F.Cu")
		(net 23)
	)
	(segment
		(start 156.435 95.530499)
		(end 156.435 94.935)
		(width 0.1)
		(layer "F.Cu")
		(net 23)
	)
	(segment
		(start 136.29 137.5)
		(end 136.48 137.69)
		(width 0.1)
		(layer "F.Cu")
		(net 23)
	)
	(segment
		(start 135.88 131.58)
		(end 135.9 131.6)
		(width 0.1)
		(layer "F.Cu")
		(net 23)
	)
	(segment
		(start 142.78 73.75)
		(end 142.78 72.75)
		(width 0.3)
		(layer "F.Cu")
		(net 23)
	)
	(segment
		(start 133.1 124.87)
		(end 133.56 124.87)
		(width 0.1)
		(layer "F.Cu")
		(net 23)
	)
	(segment
		(start 128.5 127.85)
		(end 128.225 128.125)
		(width 0.1)
		(layer "F.Cu")
		(net 23)
	)
	(segment
		(start 165.22 63.52)
		(end 164.7 63)
		(width 0.1)
		(layer "F.Cu")
		(net 23)
	)
	(segment
		(start 133.1 123.03)
		(end 133.56 123.03)
		(width 0.1)
		(layer "F.Cu")
		(net 23)
	)
	(segment
		(start 127.85 124.6)
		(end 127.2 125.25)
		(width 0.1)
		(layer "F.Cu")
		(net 23)
	)
	(segment
		(start 131.1 121.35)
		(end 130.775 121.675)
		(width 0.1)
		(layer "F.Cu")
		(net 23)
	)
	(segment
		(start 133.1 119.35)
		(end 133.56 119.35)
		(width 0.1)
		(layer "F.Cu")
		(net 23)
	)
	(segment
		(start 145.27 61.27)
		(end 145.3 61.3)
		(width 0.25)
		(layer "F.Cu")
		(net 23)
	)
	(segment
		(start 164.48 79.4)
		(end 164.48 78.4)
		(width 0.1)
		(layer "F.Cu")
		(net 23)
	)
	(segment
		(start 128.7 53.15)
		(end 131.35 53.15)
		(width 0.75)
		(layer "F.Cu")
		(net 23)
	)
	(segment
		(start 134.5 136)
		(end 134.75 136.25)
		(width 0.1)
		(layer "F.Cu")
		(net 23)
	)
	(segment
		(start 117.546 142.454)
		(end 117.5 142.5)
		(width 0.25)
		(layer "F.Cu")
		(net 23)
	)
	(segment
		(start 129.927302 100.027302)
		(end 129.851 99.951)
		(width 0.1)
		(layer "F.Cu")
		(net 23)
	)
	(segment
		(start 130.34 128.55)
		(end 130.34 129.01)
		(width 0.1)
		(layer "F.Cu")
		(net 23)
	)
	(segment
		(start 133.301 59.2)
		(end 132.6 59.2)
		(width 0.5)
		(layer "F.Cu")
		(net 23)
	)
	(segment
		(start 134.75 136.75)
		(end 135 137)
		(width 0.1)
		(layer "F.Cu")
		(net 23)
	)
	(segment
		(start 133.654 79.454)
		(end 133 78.8)
		(width 0.25)
		(layer "F.Cu")
		(net 23)
	)
	(segment
		(start 131.151 101.8)
		(end 130.2 101.8)
		(width 0.1)
		(layer "F.Cu")
		(net 23)
	)
	(segment
		(start 127.6 90.345)
		(end 127.6 91.8)
		(width 0.1)
		(layer "F.Cu")
		(net 23)
	)
	(segment
		(start 129.8 123.3)
		(end 130.125 123.625)
		(width 0.1)
		(layer "F.Cu")
		(net 23)
	)
	(segment
		(start 124.6 122.65)
		(end 124.196 122.65)
		(width 0.1)
		(layer "F.Cu")
		(net 23)
	)
	(segment
		(start 133.88 135.504)
		(end 133.996 135.504)
		(width 0.1)
		(layer "F.Cu")
		(net 23)
	)
	(segment
		(start 127.525 128.175)
		(end 127.200001 127.85)
		(width 0.1)
		(layer "F.Cu")
		(net 23)
	)
	(segment
		(start 131.75 123.95)
		(end 132.075 123.625)
		(width 0.1)
		(layer "F.Cu")
		(net 23)
	)
	(segment
		(start 158.944999 98.155001)
		(end 158.9 98.2)
		(width 0.1)
		(layer "F.Cu")
		(net 23)
	)
	(segment
		(start 126.875 126.225)
		(end 126.55 126.55)
		(width 0.1)
		(layer "F.Cu")
		(net 23)
	)
	(segment
		(start 127.2 124.6)
		(end 127.525 124.275)
		(width 0.1)
		(layer "F.Cu")
		(net 23)
	)
	(segment
		(start 131.1 127.85)
		(end 131.425 127.525)
		(width 0.1)
		(layer "F.Cu")
		(net 23)
	)
	(segment
		(start 142.78 73.75)
		(end 142.78 74.75)
		(width 0.3)
		(layer "F.Cu")
		(net 23)
	)
	(segment
		(start 131.624561 58.825)
		(end 133.645 56.804561)
		(width 0.75)
		(layer "F.Cu")
		(net 23)
	)
	(segment
		(start 131.75 126.55)
		(end 132.075 126.225)
		(width 0.1)
		(layer "F.Cu")
		(net 23)
	)
	(segment
		(start 123.44 124.41)
		(end 123.9 124.41)
		(width 0.1)
		(layer "F.Cu")
		(net 23)
	)
	(segment
		(start 165.265 62.48)
		(end 165.22 62.48)
		(width 0.1)
		(layer "F.Cu")
		(net 23)
	)
	(segment
		(start 129.943073 100.027302)
		(end 129.927302 100.027302)
		(width 0.1)
		(layer "F.Cu")
		(net 23)
	)
	(segment
		(start 126.875 126.875)
		(end 126.55 127.2)
		(width 0.1)
		(layer "F.Cu")
		(net 23)
	)
	(segment
		(start 129.8 123.3)
		(end 129.475 123.625)
		(width 0.1)
		(layer "F.Cu")
		(net 23)
	)
	(segment
		(start 119.75 148.05)
		(end 119.5 148.3)
		(width 0.25)
		(layer "F.Cu")
		(net 23)
	)
	(segment
		(start 132.88 134.62)
		(end 132.88 134.74)
		(width 0.1)
		(layer "F.Cu")
		(net 23)
	)
	(segment
		(start 133.875 125.6)
		(end 133.875 124.975)
		(width 0.1)
		(layer "F.Cu")
		(net 23)
	)
	(segment
		(start 124.6 120.7)
		(end 124.146 120.7)
		(width 0.1)
		(layer "F.Cu")
		(net 23)
	)
	(segment
		(start 123.9 119.35)
		(end 123.9 118.89)
		(width 0.1)
		(layer "F.Cu")
		(net 23)
	)
	(segment
		(start 150.249998 112.150002)
		(end 150.2 112.2)
		(width 0.1)
		(layer "F.Cu")
		(net 23)
	)
	(segment
		(start 129.8 121.35)
		(end 130.125 121.675)
		(width 0.1)
		(layer "F.Cu")
		(net 23)
	)
	(segment
		(start 125.249 148.251)
		(end 125.15 148.35)
		(width 0.25)
		(layer "F.Cu")
		(net 23)
	)
	(segment
		(start 128.825 127.525)
		(end 129.15 127.2)
		(width 0.1)
		(layer "F.Cu")
		(net 23)
	)
	(segment
		(start 130.45 121.35)
		(end 130.125 121.675)
		(width 0.1)
		(layer "F.Cu")
		(net 23)
	)
	(segment
		(start 128.175 123.625)
		(end 128.5 123.95)
		(width 0.1)
		(layer "F.Cu")
		(net 23)
	)
	(segment
		(start 130.45 121.35)
		(end 130.775 121.025)
		(width 0.1)
		(layer "F.Cu")
		(net 23)
	)
	(segment
		(start 127.2 122)
		(end 127.525 121.675)
		(width 0.1)
		(layer "F.Cu")
		(net 23)
	)
	(segment
		(start 124.54 86.5)
		(end 123.25 86.5)
		(width 0.1)
		(layer "F.Cu")
		(net 23)
	)
	(segment
		(start 119.75 147.498)
		(end 119.75 148.05)
		(width 0.25)
		(layer "F.Cu")
		(net 23)
	)
	(segment
		(start 165.22 62.48)
		(end 164.7 63)
		(width 0.1)
		(layer "F.Cu")
		(net 23)
	)
	(segment
		(start 123.9 123.49)
		(end 124.14 123.49)
		(width 0.1)
		(layer "F.Cu")
		(net 23)
	)
	(segment
		(start 135.150001 112.150001)
		(end 134.8 111.8)
		(width 0.1)
		(layer "F.Cu")
		(net 23)
	)
	(segment
		(start 133.56 129.01)
		(end 133.56 128.55)
		(width 0.1)
		(layer "F.Cu")
		(net 23)
	)
	(segment
		(start 131.75 125.25)
		(end 132.075 124.925)
		(width 0.1)
		(layer "F.Cu")
		(net 23)
	)
	(segment
		(start 129.15 123.95)
		(end 129.475 123.625)
		(width 0.1)
		(layer "F.Cu")
		(net 23)
	)
	(segment
		(start 116.52 145.6)
		(end 116.52 146.38)
		(width 0.25)
		(layer "F.Cu")
		(net 23)
	)
	(segment
		(start 129.42 119.35)
		(end 129.42 119.134)
		(width 0.1)
		(layer "F.Cu")
		(net 23)
	)
	(segment
		(start 145.08 115.92)
		(end 145.8 115.92)
		(width 0.25)
		(layer "F.Cu")
		(net 23)
	)
	(segment
		(start 131.35 53.15)
		(end 133.645 55.445)
		(width 0.75)
		(layer "F.Cu")
		(net 23)
	)
	(segment
		(start 124.6 125.25)
		(end 124.925 124.925)
		(width 0.1)
		(layer "F.Cu")
		(net 23)
	)
	(segment
		(start 124.48 70)
		(end 124.48 69.27)
		(width 0.1)
		(layer "F.Cu")
		(net 23)
	)
	(segment
		(start 125.25 125.25)
		(end 124.925 124.925)
		(width 0.1)
		(layer "F.Cu")
		(net 23)
	)
	(segment
		(start 133.875 124.975)
		(end 134 124.85)
		(width 0.1)
		(layer "F.Cu")
		(net 23)
	)
	(segment
		(start 134.5 137)
		(end 134.75 137.25)
		(width 0.1)
		(layer "F.Cu")
		(net 23)
	)
	(segment
		(start 158.769999 109.15)
		(end 158 109.15)
		(width 0.1)
		(layer "F.Cu")
		(net 23)
	)
	(segment
		(start 130.45 123.3)
		(end 130.125 123.625)
		(width 0.1)
		(layer "F.Cu")
		(net 23)
	)
	(segment
		(start 125.25 122.65)
		(end 125.575 122.975)
		(width 0.1)
		(layer "F.Cu")
		(net 23)
	)
	(segment
		(start 124.48 69.27)
		(end 124.5 69.25)
		(width 0.1)
		(layer "F.Cu")
		(net 23)
	)
	(segment
		(start 141.88 63.4)
		(end 142.6 63.4)
		(width 0.5)
		(layer "F.Cu")
		(net 23)
	)
	(segment
		(start 130.34 118.495)
		(end 130.338 118.493)
		(width 0.1)
		(layer "F.Cu")
		(net 23)
	)
	(segment
		(start 161.07 49.35)
		(end 161.4 49.02)
		(width 0.25)
		(layer "F.Cu")
		(net 23)
	)
	(segment
		(start 124.6 121.35)
		(end 124.3 121.65)
		(width 0.1)
		(layer "F.Cu")
		(net 23)
	)
	(segment
		(start 159.9 102.85)
		(end 159.9 102.700001)
		(width 0.25)
		(layer "F.Cu")
		(net 23)
	)
	(segment
		(start 131.201 101.75)
		(end 131.151 101.8)
		(width 0.1)
		(layer "F.Cu")
		(net 23)
	)
	(segment
		(start 130.45 121.35)
		(end 130.775 121.675)
		(width 0.1)
		(layer "F.Cu")
		(net 23)
	)
	(segment
		(start 142.500002 112.150002)
		(end 142.5 112.15)
		(width 0.1)
		(layer "F.Cu")
		(net 23)
	)
	(segment
		(start 119.5 149.1)
		(end 119.5 149.55)
		(width 0.25)
		(layer "F.Cu")
		(net 23)
	)
	(segment
		(start 124.82 119.83)
		(end 124.6 120.05)
		(width 0.1)
		(layer "F.Cu")
		(net 23)
	)
	(segment
		(start 124.41 124.41)
		(end 124.41 124.14)
		(width 0.1)
		(layer "F.Cu")
		(net 23)
	)
	(segment
		(start 123.9 127.17)
		(end 124.07 127.17)
		(width 0.1)
		(layer "F.Cu")
		(net 23)
	)
	(segment
		(start 141.915 82.25)
		(end 141.915 83.25)
		(width 0.3)
		(layer "F.Cu")
		(net 23)
	)
	(segment
		(start 128.125 128.125)
		(end 127.85 127.85)
		(width 0.1)
		(layer "F.Cu")
		(net 23)
	)
	(segment
		(start 125.9 125.25)
		(end 125.575 124.925)
		(width 0.1)
		(layer "F.Cu")
		(net 23)
	)
	(segment
		(start 124.36 119.81)
		(end 124.116 119.81)
		(width 0.1)
		(layer "F.Cu")
		(net 23)
	)
	(segment
		(start 127.9 140.3)
		(end 127.2 141)
		(width 0.5)
		(layer "F.Cu")
		(net 23)
	)
	(segment
		(start 126.66 128.334)
		(end 126.66 127.96)
		(width 0.1)
		(layer "F.Cu")
		(net 23)
	)
	(segment
		(start 124.41 124.41)
		(end 124.6 124.6)
		(width 0.1)
		(layer "F.Cu")
		(net 23)
	)
	(segment
		(start 132.52 130.2)
		(end 132 130.2)
		(width 0.25)
		(layer "F.Cu")
		(net 23)
	)
	(segment
		(start 135.5 136)
		(end 135.25 136.25)
		(width 0.1)
		(layer "F.Cu")
		(net 23)
	)
	(segment
		(start 128.175 125.575)
		(end 128.5 125.9)
		(width 0.1)
		(layer "F.Cu")
		(net 23)
	)
	(segment
		(start 126.55 121.35)
		(end 126.875 121.675)
		(width 0.1)
		(layer "F.Cu")
		(net 23)
	)
	(segment
		(start 169.852 76.687)
		(end 168.887 76.687)
		(width 0.25)
		(layer "F.Cu")
		(net 23)
	)
	(segment
		(start 131.1 122)
		(end 131.425 121.675)
		(width 0.1)
		(layer "F.Cu")
		(net 23)
	)
	(segment
		(start 130 94.75)
		(end 130.25 95)
		(width 0.1)
		(layer "F.Cu")
		(net 23)
	)
	(segment
		(start 124.6 123.95)
		(end 124.275 123.625)
		(width 0.1)
		(layer "F.Cu")
		(net 23)
	)
	(segment
		(start 119.5 148.3)
		(end 119.5 149.1)
		(width 0.25)
		(layer "F.Cu")
		(net 23)
	)
	(segment
		(start 135.5 137)
		(end 135.25 136.75)
		(width 0.1)
		(layer "F.Cu")
		(net 23)
	)
	(segment
		(start 165.98 67.8)
		(end 165.98 67.02)
		(width 0.25)
		(layer "F.Cu")
		(net 23)
	)
	(segment
		(start 121.234085 89.034085)
		(end 121.2 89)
		(width 0.25)
		(layer "F.Cu")
		(net 23)
	)
	(segment
		(start 149.704 127.096)
		(end 149.7 127.1)
		(width 0.25)
		(layer "F.Cu")
		(net 23)
	)
	(segment
		(start 123.9 125.33)
		(end 124.116 125.33)
		(width 0.1)
		(layer "F.Cu")
		(net 23)
	)
	(segment
		(start 143.525001 96.674999)
		(end 143.6 96.6)
		(width 0.1)
		(layer "F.Cu")
		(net 23)
	)
	(segment
		(start 167.9 67)
		(end 167.9 67.1)
		(width 0.1)
		(layer "F.Cu")
		(net 23)
	)
	(segment
		(start 132.075 126.875)
		(end 131.75 127.2)
		(width 0.1)
		(layer "F.Cu")
		(net 23)
	)
	(segment
		(start 128.225 128.125)
		(end 128.125 128.125)
		(width 0.1)
		(layer "F.Cu")
		(net 23)
	)
	(segment
		(start 132.4 127.2)
		(end 132.075 126.875)
		(width 0.1)
		(layer "F.Cu")
		(net 23)
	)
	(segment
		(start 117.06 113.94)
		(end 117.6 113.94)
		(width 0.1)
		(layer "F.Cu")
		(net 23)
	)
	(segment
		(start 124.196 122.65)
		(end 124.116 122.57)
		(width 0.1)
		(layer "F.Cu")
		(net 23)
	)
	(segment
		(start 160.625 50.725)
		(end 160.65 50.75)
		(width 0.25)
		(layer "F.Cu")
		(net 23)
	)
	(segment
		(start 139.991421 119.491421)
		(end 140 119.5)
		(width 0.1)
		(layer "F.Cu")
		(net 23)
	)
	(segment
		(start 133.47 93.8)
		(end 133.52 93.75)
		(width 0.25)
		(layer "F.Cu")
		(net 23)
	)
	(segment
		(start 158.05 112.15)
		(end 158.769997 112.150001)
		(width 0.1)
		(layer "F.Cu")
		(net 23)
	)
	(segment
		(start 115.92 107.1)
		(end 115.9 107.1)
		(width 0.1)
		(layer "F.Cu")
		(net 23)
	)
	(segment
		(start 127.2 125.9)
		(end 127.85 125.25)
		(width 0.1)
		(layer "F.Cu")
		(net 23)
	)
	(segment
		(start 123.9 126.25)
		(end 124.116 126.25)
		(width 0.1)
		(layer "F.Cu")
		(net 23)
	)
	(segment
		(start 131.75 125.9)
		(end 132.075 125.575)
		(width 0.1)
		(layer "F.Cu")
		(net 23)
	)
	(segment
		(start 119.73 67.5)
		(end 119.73 65.5)
		(width 0.1)
		(layer "F.Cu")
		(net 23)
	)
	(segment
		(start 123.44 119.81)
		(end 123.9 119.81)
		(width 0.1)
		(layer "F.Cu")
		(net 23)
	)
	(segment
		(start 156.435 95.530499)
		(end 156.435 96.465499)
		(width 0.1)
		(layer "F.Cu")
		(net 23)
	)
	(segment
		(start 124.82 118.89)
		(end 124.82 119.35)
		(width 0.1)
		(layer "F.Cu")
		(net 23)
	)
	(segment
		(start 130.45 120.7)
		(end 130.775 121.025)
		(width 0.1)
		(layer "F.Cu")
		(net 23)
	)
	(segment
		(start 126.225 128.175)
		(end 126.384 128.334)
		(width 0.1)
		(layer "F.Cu")
		(net 23)
	)
	(segment
		(start 135 84.68)
		(end 135.48 84.68)
		(width 0.25)
		(layer "F.Cu")
		(net 23)
	)
	(segment
		(start 166.48 75.4)
		(end 167.2 75.4)
		(width 0.25)
		(layer "F.Cu")
		(net 23)
	)
	(segment
		(start 129.8 127.85)
		(end 130.45 127.2)
		(width 0.1)
		(layer "F.Cu")
		(net 23)
	)
	(segment
		(start 134.5 137.5)
		(end 134.75 137.25)
		(width 0.1)
		(layer "F.Cu")
		(net 23)
	)
	(segment
		(start 128.5 128.4)
		(end 128.225 128.125)
		(width 0.1)
		(layer "F.Cu")
		(net 23)
	)
	(segment
		(start 156.435 94.935)
		(end 156.4 94.9)
		(width 0.1)
		(layer "F.Cu")
		(net 23)
	)
	(segment
		(start 136 137.5)
		(end 135.5 137.5)
		(width 0.1)
		(layer "F.Cu")
		(net 23)
	)
	(segment
		(start 130.68 71.4)
		(end 131.4 71.4)
		(width 0.25)
		(layer "F.Cu")
		(net 23)
	)
	(segment
		(start 129.8 122)
		(end 130.125 121.675)
		(width 0.1)
		(layer "F.Cu")
		(net 23)
	)
	(segment
		(start 160.73 60.42)
		(end 160.75 60.4)
		(width 0.5)
		(layer "F.Cu")
		(net 23)
	)
	(segment
		(start 124.6 120.05)
		(end 124.36 119.81)
		(width 0.1)
		(layer "F.Cu")
		(net 23)
	)
	(segment
		(start 129.475 127.525)
		(end 129.8 127.2)
		(width 0.1)
		(layer "F.Cu")
		(net 23)
	)
	(segment
		(start 127.85 124.6)
		(end 127.525 124.275)
		(width 0.1)
		(layer "F.Cu")
		(net 23)
	)
	(segment
		(start 165.813 67.967)
		(end 165.98 67.8)
		(width 0.25)
		(layer "F.Cu")
		(net 23)
	)
	(segment
		(start 128.5 123.3)
		(end 128.825 123.625)
		(width 0.1)
		(layer "F.Cu")
		(net 23)
	)
	(segment
		(start 131.75 124.6)
		(end 132.075 124.275)
		(width 0.1)
		(layer "F.Cu")
		(net 23)
	)
	(segment
		(start 119 71.75)
		(end 119.75 71.75)
		(width 0.25)
		(layer "F.Cu")
		(net 23)
	)
	(segment
		(start 130.34 119.35)
		(end 130.34 118.495)
		(width 0.1)
		(layer "F.Cu")
		(net 23)
	)
	(segment
		(start 127.2 121.35)
		(end 127.85 120.7)
		(width 0.1)
		(layer "F.Cu")
		(net 23)
	)
	(segment
		(start 158.799499 97.580499)
		(end 158.944999 97.434999)
		(width 0.1)
		(layer "F.Cu")
		(net 23)
	)
	(segment
		(start 132.32 140.4)
		(end 131.6 140.4)
		(width 0.25)
		(layer "F.Cu")
		(net 23)
	)
	(segment
		(start 130.45 122)
		(end 130.125 121.675)
		(width 0.1)
		(layer "F.Cu")
		(net 23)
	)
	(segment
		(start 145 115.9)
		(end 145.06 115.9)
		(width 0.25)
		(layer "F.Cu")
		(net 23)
	)
	(segment
		(start 150.300002 109.150002)
		(end 150.3 109.15)
		(width 0.1)
		(layer "F.Cu")
		(net 23)
	)
	(segment
		(start 133.98 124.87)
		(end 134 124.85)
		(width 0.1)
		(layer "F.Cu")
		(net 23)
	)
	(segment
		(start 118 132.4)
		(end 118.601 131.799)
		(width 0.1)
		(layer "F.Cu")
		(net 23)
	)
	(segment
		(start 160.675 49.375)
		(end 160.7 49.35)
		(width 0.25)
		(layer "F.Cu")
		(net 23)
	)
	(segment
		(start 151.255 94.024999)
		(end 151.255 94.005)
		(width 0.25)
		(layer "F.Cu")
		(net 23)
	)
	(segment
		(start 130.34 119.35)
		(end 129.88 119.81)
		(width 0.1)
		(layer "F.Cu")
		(net 23)
	)
	(segment
		(start 132.4 127.2)
		(end 132.075 127.525)
		(width 0.1)
		(layer "F.Cu")
		(net 23)
	)
	(segment
		(start 127.2 121.35)
		(end 127.525 121.675)
		(width 0.1)
		(layer "F.Cu")
		(net 23)
	)
	(segment
		(start 134.750001 109.150001)
		(end 134.75 109.15)
		(width 0.1)
		(layer "F.Cu")
		(net 23)
	)
	(segment
		(start 159.94 49.375)
		(end 158.565 49.375)
		(width 0.25)
		(layer "F.Cu")
		(net 23)
	)
	(segment
		(start 124.25 126.25)
		(end 124.116 126.25)
		(width 0.1)
		(layer "F.Cu")
		(net 23)
	)
	(segment
		(start 133.1 125.79)
		(end 133.56 125.79)
		(width 0.1)
		(layer "F.Cu")
		(net 23)
	)
	(segment
		(start 131.75 123.3)
		(end 131.425 123.625)
		(width 0.1)
		(layer "F.Cu")
		(net 23)
	)
	(segment
		(start 124.116 120.866)
		(end 124.116 120.73)
		(width 0.1)
		(layer "F.Cu")
		(net 23)
	)
	(segment
		(start 124.999 148.501)
		(end 125.15 148.35)
		(width 0.25)
		(layer "F.Cu")
		(net 23)
	)
	(segment
		(start 159.25 102.85)
		(end 159.25 102.650001)
		(width 0.25)
		(layer "F.Cu")
		(net 23)
	)
	(segment
		(start 127.85 120)
		(end 128.04 119.81)
		(width 0.1)
		(layer "F.Cu")
		(net 23)
	)
	(segment
		(start 125.025 96.2)
		(end 125.025 95.275)
		(width 0.25)
		(layer "F.Cu")
		(net 23)
	)
	(segment
		(start 134.620002 92.600002)
		(end 135.77 93.75)
		(width 0.25)
		(layer "F.Cu")
		(net 23)
	)
	(segment
		(start 149.7 76.075)
		(end 149.7 75.75)
		(width 0.5)
		(layer "F.Cu")
		(net 23)
	)
	(segment
		(start 141.4 119.5)
		(end 141.48284 119.5)
		(width 0.1)
		(layer "F.Cu")
		(net 23)
	)
	(segment
		(start 149.702 125.799)
		(end 149.704 125.801)
		(width 0.25)
		(layer "F.Cu")
		(net 23)
	)
	(segment
		(start 116.52 73.9)
		(end 115.8 73.9)
		(width 0.1)
		(layer "F.Cu")
		(net 23)
	)
	(segment
		(start 133.56 125.79)
		(end 133.685 125.79)
		(width 0.1)
		(layer "F.Cu")
		(net 23)
	)
	(segment
		(start 123.9 119.35)
		(end 123.9 119.81)
		(width 0.1)
		(layer "F.Cu")
		(net 23)
	)
	(segment
		(start 131.5 116)
		(end 131.4 116)
		(width 0.1)
		(layer "F.Cu")
		(net 23)
	)
	(segment
		(start 115.92 108.1)
		(end 115.92 108.07)
		(width 0.1)
		(layer "F.Cu")
		(net 23)
	)
	(segment
		(start 128.7 48.65)
		(end 128.7 53.15)
		(width 0.75)
		(layer "F.Cu")
		(net 23)
	)
	(segment
		(start 160.73 61.7)
		(end 160.73 60.42)
		(width 0.5)
		(layer "F.Cu")
		(net 23)
	)
	(segment
		(start 129.8 127.2)
		(end 130.45 127.85)
		(width 0.1)
		(layer "F.Cu")
		(net 23)
	)
	(segment
		(start 168 76.52)
		(end 168.68 76.52)
		(width 0.25)
		(layer "F.Cu")
		(net 23)
	)
	(segment
		(start 126.716 128.334)
		(end 127.2 127.85)
		(width 0.1)
		(layer "F.Cu")
		(net 23)
	)
	(segment
		(start 123.44 127.17)
		(end 123.9 127.17)
		(width 0.1)
		(layer "F.Cu")
		(net 23)
	)
	(segment
		(start 132.52 131.2)
		(end 132 131.2)
		(width 0.25)
		(layer "F.Cu")
		(net 23)
	)
	(segment
		(start 136 137.92)
		(end 135.88 138.04)
		(width 0.1)
		(layer "F.Cu")
		(net 23)
	)
	(segment
		(start 131.75 120.7)
		(end 132.075 121.025)
		(width 0.1)
		(layer "F.Cu")
		(net 23)
	)
	(segment
		(start 128.5 128.55)
		(end 128.5 129.01)
		(width 0.1)
		(layer "F.Cu")
		(net 23)
	)
	(segment
		(start 127.85 122)
		(end 127.525 121.675)
		(width 0.1)
		(layer "F.Cu")
		(net 23)
	)
	(segment
		(start 129.851 99.951)
		(end 128.901 99.951)
		(width 0.1)
		(layer "F.Cu")
		(net 23)
	)
	(segment
		(start 125.9 127.85)
		(end 126.225 127.525)
		(width 0.1)
		(layer "F.Cu")
		(net 23)
	)
	(segment
		(start 128.949 99.951)
		(end 129.4 99.5)
		(width 0.1)
		(layer "F.Cu")
		(net 23)
	)
	(segment
		(start 123.44 120.73)
		(end 123.9 120.73)
		(width 0.1)
		(layer "F.Cu")
		(net 23)
	)
	(segment
		(start 115.92 103.1)
		(end 115.9 103.1)
		(width 0.25)
		(layer "F.Cu")
		(net 23)
	)
	(segment
		(start 133.996 135.504)
		(end 134 135.5)
		(width 0.1)
		(layer "F.Cu")
		(net 23)
	)
	(segment
		(start 118.15 103.852)
		(end 117.548 103.852)
		(width 0.1)
		(layer "F.Cu")
		(net 23)
	)
	(segment
		(start 127.525 128.175)
		(end 127.85 127.85)
		(width 0.1)
		(layer "F.Cu")
		(net 23)
	)
	(segment
		(start 126.55 121.35)
		(end 126.225 121.675)
		(width 0.1)
		(layer "F.Cu")
		(net 23)
	)
	(segment
		(start 135 136.5)
		(end 135.25 136.25)
		(width 0.1)
		(layer "F.Cu")
		(net 23)
	)
	(segment
		(start 139 70.2)
		(end 139.6 69.6)
		(width 0.25)
		(layer "F.Cu")
		(net 23)
	)
	(segment
		(start 119.73 65.5)
		(end 119.73 64.73)
		(width 0.1)
		(layer "F.Cu")
		(net 23)
	)
	(segment
		(start 139.77 128.67)
		(end 139.8 128.7)
		(width 0.1)
		(layer "F.Cu")
		(net 23)
	)
	(segment
		(start 116.8 114.2)
		(end 117.06 113.94)
		(width 0.1)
		(layer "F.Cu")
		(net 23)
	)
	(segment
		(start 124.925 125.575)
		(end 125.25 125.25)
		(width 0.1)
		(layer "F.Cu")
		(net 23)
	)
	(segment
		(start 126.66 128.334)
		(end 126.716 128.334)
		(width 0.1)
		(layer "F.Cu")
		(net 23)
	)
	(segment
		(start 119.8 131.2)
		(end 118.701 131.2)
		(width 0.25)
		(layer "F.Cu")
		(net 23)
	)
	(segment
		(start 134.75 136.75)
		(end 135 136.5)
		(width 0.1)
		(layer "F.Cu")
		(net 23)
	)
	(segment
		(start 130.45 122)
		(end 130.775 121.675)
		(width 0.1)
		(layer "F.Cu")
		(net 23)
	)
	(segment
		(start 127.85 123.3)
		(end 128.175 122.975)
		(width 0.1)
		(layer "F.Cu")
		(net 23)
	)
	(segment
		(start 128.5 128.55)
		(end 128.5 128.4)
		(width 0.1)
		(layer "F.Cu")
		(net 23)
	)
	(segment
		(start 126.55 127.2)
		(end 126.225 127.525)
		(width 0.1)
		(layer "F.Cu")
		(net 23)
	)
	(segment
		(start 131.1 122)
		(end 130.775 121.675)
		(width 0.1)
		(layer "F.Cu")
		(net 23)
	)
	(segment
		(start 129.8 120.7)
		(end 130.45 121.35)
		(width 0.1)
		(layer "F.Cu")
		(net 23)
	)
	(segment
		(start 168.68 76.52)
		(end 168.7 76.5)
		(width 0.25)
		(layer "F.Cu")
		(net 23)
	)
	(segment
		(start 126.875 127.525)
		(end 126.55 127.85)
		(width 0.1)
		(layer "F.Cu")
		(net 23)
	)
	(segment
		(start 124.6 123.3)
		(end 124.275 123.625)
		(width 0.1)
		(layer "F.Cu")
		(net 23)
	)
	(segment
		(start 168.887 76.687)
		(end 168.7 76.5)
		(width 0.25)
		(layer "F.Cu")
		(net 23)
	)
	(segment
		(start 143.35 60.303)
		(end 144.297 60.303)
		(width 0.1)
		(layer "F.Cu")
		(net 23)
	)
	(segment
		(start 126.55 122)
		(end 126.225 121.675)
		(width 0.1)
		(layer "F.Cu")
		(net 23)
	)
	(segment
		(start 130.45 127.2)
		(end 131.1 127.85)
		(width 0.1)
		(layer "F.Cu")
		(net 23)
	)
	(segment
		(start 123.44 125.33)
		(end 123.9 125.33)
		(width 0.1)
		(layer "F.Cu")
		(net 23)
	)
	(segment
		(start 129.8 127.2)
		(end 129.475 126.875)
		(width 0.1)
		(layer "F.Cu")
		(net 23)
	)
	(segment
		(start 124.82 128.55)
		(end 124.769669 128.55)
		(width 0.1)
		(layer "F.Cu")
		(net 23)
	)
	(segment
		(start 132.075 121.025)
		(end 131.75 121.35)
		(width 0.1)
		(layer "F.Cu")
		(net 23)
	)
	(segment
		(start 124.6 125.25)
		(end 124.925 125.575)
		(width 0.1)
		(layer "F.Cu")
		(net 23)
	)
	(segment
		(start 129.88 103.1)
		(end 130.6 103.1)
		(width 0.1)
		(layer "F.Cu")
		(net 23)
	)
	(segment
		(start 117.08 132.4)
		(end 118 132.4)
		(width 0.1)
		(layer "F.Cu")
		(net 23)
	)
	(segment
		(start 127.58 129.33)
		(end 127.58 129.01)
		(width 0.1)
		(layer "F.Cu")
		(net 23)
	)
	(segment
		(start 135 137.5)
		(end 135.25 137.25)
		(width 0.1)
		(layer "F.Cu")
		(net 23)
	)
	(segment
		(start 124.3 126.25)
		(end 124.116 126.25)
		(width 0.1)
		(layer "F.Cu")
		(net 23)
	)
	(segment
		(start 132.5 134.5)
		(end 132.64 134.5)
		(width 0.1)
		(layer "F.Cu")
		(net 23)
	)
	(segment
		(start 132.5 135)
		(end 132.62 135)
		(width 0.1)
		(layer "F.Cu")
		(net 23)
	)
	(segment
		(start 135.5 136.5)
		(end 135.25 136.25)
		(width 0.1)
		(layer "F.Cu")
		(net 23)
	)
	(segment
		(start 139.4 93.4)
		(end 139.8 93.8)
		(width 0.5)
		(layer "F.Cu")
		(net 23)
	)
	(segment
		(start 144.583 61.253)
		(end 144.6 61.27)
		(width 0.25)
		(layer "F.Cu")
		(net 23)
	)
	(segment
		(start 131.75 122)
		(end 132.075 121.675)
		(width 0.1)
		(layer "F.Cu")
		(net 23)
	)
	(segment
		(start 127.85 123.3)
		(end 127.525 122.975)
		(width 0.1)
		(layer "F.Cu")
		(net 23)
	)
	(segment
		(start 123.9 128.09)
		(end 124.116 128.09)
		(width 0.1)
		(layer "F.Cu")
		(net 23)
	)
	(segment
		(start 128.825 127.525)
		(end 128.5 127.85)
		(width 0.1)
		(layer "F.Cu")
		(net 23)
	)
	(segment
		(start 127.2 125.9)
		(end 126.875 126.225)
		(width 0.1)
		(layer "F.Cu")
		(net 23)
	)
	(segment
		(start 130.34 128.55)
		(end 130.125 128.335)
		(width 0.1)
		(layer "F.Cu")
		(net 23)
	)
	(segment
		(start 124.6 120.05)
		(end 124.116 120.534)
		(width 0.1)
		(layer "F.Cu")
		(net 23)
	)
	(segment
		(start 141.915 82.25)
		(end 141.915 81.25)
		(width 0.3)
		(layer "F.Cu")
		(net 23)
	)
	(segment
		(start 136.85 131.58)
		(end 136.88 131.58)
		(width 0.1)
		(layer "F.Cu")
		(net 23)
	)
	(segment
		(start 153.32 46.9)
		(end 153.32 45.9)
		(width 0.1)
		(layer "F.Cu")
		(net 23)
	)
	(segment
		(start 157.251 116.551)
		(end 157.3 116.6)
		(width 0.1)
		(layer "F.Cu")
		(net 23)
	)
	(segment
		(start 141.915 76.25)
		(end 141.915 75.25)
		(width 0.3)
		(layer "F.Cu")
		(net 23)
	)
	(segment
		(start 135 137.5)
		(end 134.75 137.25)
		(width 0.1)
		(layer "F.Cu")
		(net 23)
	)
	(segment
		(start 144.2 102.400002)
		(end 144.15 102.350002)
		(width 0.1)
		(layer "F.Cu")
		(net 23)
	)
	(segment
		(start 130.125 128.335)
		(end 130.125 128.175)
		(width 0.1)
		(layer "F.Cu")
		(net 23)
	)
	(segment
		(start 144.297 60.303)
		(end 144.3 60.3)
		(width 0.1)
		(layer "F.Cu")
		(net 23)
	)
	(segment
		(start 120.88 128.6)
		(end 121.6 128.6)
		(width 0.1)
		(layer "F.Cu")
		(net 23)
	)
	(segment
		(start 129.475 127.525)
		(end 129.15 127.85)
		(width 0.1)
		(layer "F.Cu")
		(net 23)
	)
	(segment
		(start 129.15 123.3)
		(end 129.475 123.625)
		(width 0.1)
		(layer "F.Cu")
		(net 23)
	)
	(segment
		(start 127.2 125.25)
		(end 127.85 125.9)
		(width 0.1)
		(layer "F.Cu")
		(net 23)
	)
	(segment
		(start 130.125 128.175)
		(end 130.45 127.85)
		(width 0.1)
		(layer "F.Cu")
		(net 23)
	)
	(segment
		(start 123.9 129.01)
		(end 123.9 128.55)
		(width 0.1)
		(layer "F.Cu")
		(net 23)
	)
	(segment
		(start 131.26 128.55)
		(end 131.26 129.01)
		(width 0.1)
		(layer "F.Cu")
		(net 23)
	)
	(segment
		(start 139.3 87.5)
		(end 138.85 87.5)
		(width 0.25)
		(layer "F.Cu")
		(net 23)
	)
	(segment
		(start 129.4 99.5)
		(end 129.4 98.82)
		(width 0.1)
		(layer "F.Cu")
		(net 23)
	)
	(segment
		(start 127.58 128.55)
		(end 127.58 129.01)
		(width 0.1)
		(layer "F.Cu")
		(net 23)
	)
	(segment
		(start 132.5 134)
		(end 132.5 134.12)
		(width 0.1)
		(layer "F.Cu")
		(net 23)
	)
	(segment
		(start 137 137.5)
		(end 136.67 137.5)
		(width 0.1)
		(layer "F.Cu")
		(net 23)
	)
	(segment
		(start 131.75 121.35)
		(end 131.425 121.025)
		(width 0.1)
		(layer "F.Cu")
		(net 23)
	)
	(segment
		(start 138.45 119.45)
		(end 138.5 119.5)
		(width 0.1)
		(layer "F.Cu")
		(net 23)
	)
	(segment
		(start 125.249 147.498)
		(end 125.249 148.251)
		(width 0.25)
		(layer "F.Cu")
		(net 23)
	)
	(segment
		(start 160.7 49.35)
		(end 161.07 49.35)
		(width 0.25)
		(layer "F.Cu")
		(net 23)
	)
	(segment
		(start 131.1 120.7)
		(end 130.775 121.025)
		(width 0.1)
		(layer "F.Cu")
		(net 23)
	)
	(segment
		(start 133.1 118.89)
		(end 133.1 119.35)
		(width 0.1)
		(layer "F.Cu")
		(net 23)
	)
	(segment
		(start 164.48 78.4)
		(end 165.4 78.4)
		(width 0.1)
		(layer "F.Cu")
		(net 23)
	)
	(segment
		(start 132.845 86.73)
		(end 134 86.73)
		(width 0.1)
		(layer "F.Cu")
		(net 23)
	)
	(segment
		(start 116.52 70.9)
		(end 115.8 70.9)
		(width 0.1)
		(layer "F.Cu")
		(net 23)
	)
	(segment
		(start 135 136)
		(end 135.25 136.25)
		(width 0.1)
		(layer "F.Cu")
		(net 23)
	)
	(segment
		(start 138.304 85.604)
		(end 138.304 86.524999)
		(width 0.25)
		(layer "F.Cu")
		(net 23)
	)
	(segment
		(start 126.175 128.125)
		(end 126.225 128.175)
		(width 0.1)
		(layer "F.Cu")
		(net 23)
	)
	(segment
		(start 160.65 50.75)
		(end 161.13 50.75)
		(width 0.25)
		(layer "F.Cu")
		(net 23)
	)
	(segment
		(start 129.475 128.175)
		(end 129.8 127.85)
		(width 0.1)
		(layer "F.Cu")
		(net 23)
	)
	(segment
		(start 129.42 129.01)
		(end 129.42 128.55)
		(width 0.1)
		(layer "F.Cu")
		(net 23)
	)
	(segment
		(start 131.425 127.525)
		(end 131.75 127.2)
		(width 0.1)
		(layer "F.Cu")
		(net 23)
	)
	(segment
		(start 165.98 67.02)
		(end 166 67)
		(width 0.25)
		(layer "F.Cu")
		(net 23)
	)
	(segment
		(start 133.72 60.4)
		(end 133 60.4)
		(width 0.5)
		(layer "F.Cu")
		(net 23)
	)
	(segment
		(start 132.075 122.325)
		(end 131.75 122.65)
		(width 0.1)
		(layer "F.Cu")
		(net 23)
	)
	(segment
		(start 125.4 94.9)
		(end 125.2 95.1)
		(width 0.25)
		(layer "F.Cu")
		(net 23)
	)
	(segment
		(start 129.15 127.2)
		(end 129.475 126.875)
		(width 0.1)
		(layer "F.Cu")
		(net 23)
	)
	(segment
		(start 135.85 131.58)
		(end 135.88 131.58)
		(width 0.1)
		(layer "F.Cu")
		(net 23)
	)
	(segment
		(start 130.45 123.3)
		(end 130.775 123.625)
		(width 0.1)
		(layer "F.Cu")
		(net 23)
	)
	(segment
		(start 157.9 97.580499)
		(end 158.799499 97.580499)
		(width 0.1)
		(layer "F.Cu")
		(net 23)
	)
	(segment
		(start 125.74 129.01)
		(end 125.74 128.55)
		(width 0.1)
		(layer "F.Cu")
		(net 23)
	)
	(segment
		(start 133.645 55.445)
		(end 133.645 56.804561)
		(width 0.75)
		(layer "F.Cu")
		(net 23)
	)
	(segment
		(start 138.85 87.5)
		(end 138.304 86.954)
		(width 0.25)
		(layer "F.Cu")
		(net 23)
	)
	(segment
		(start 126.55 127.2)
		(end 126.875 127.525)
		(width 0.1)
		(layer "F.Cu")
		(net 23)
	)
	(segment
		(start 124.116 125.084)
		(end 124.6 124.6)
		(width 0.1)
		(layer "F.Cu")
		(net 23)
	)
	(segment
		(start 133.99 122.11)
		(end 133.1 122.11)
		(width 0.1)
		(layer "F.Cu")
		(net 23)
	)
	(segment
		(start 159 45.82)
		(end 160 45.82)
		(width 0.1)
		(layer "F.Cu")
		(net 23)
	)
	(segment
		(start 129.42 128.23)
		(end 129.475 128.175)
		(width 0.1)
		(layer "F.Cu")
		(net 23)
	)
	(segment
		(start 128.175 123.625)
		(end 128.5 123.3)
		(width 0.1)
		(layer "F.Cu")
		(net 23)
	)
	(segment
		(start 133 138.5)
		(end 133 138)
		(width 0.1)
		(layer "F.Cu")
		(net 23)
	)
	(segment
		(start 136.87 128.67)
		(end 136.9 128.7)
		(width 0.1)
		(layer "F.Cu")
		(net 23)
	)
	(segment
		(start 127.2 122)
		(end 126.875 121.675)
		(width 0.1)
		(layer "F.Cu")
		(net 23)
	)
	(segment
		(start 171.6 74.48)
		(end 171.6 75.2)
		(width 0.1)
		(layer "F.Cu")
		(net 23)
	)
	(segment
		(start 141.915 79.25)
		(end 141.915 80.25)
		(width 0.3)
		(layer "F.Cu")
		(net 23)
	)
	(segment
		(start 124.769669 128.55)
		(end 124.309669 128.09)
		(width 0.1)
		(layer "F.Cu")
		(net 23)
	)
	(segment
		(start 126.66 127.96)
		(end 126.55 127.85)
		(width 0.1)
		(layer "F.Cu")
		(net 23)
	)
	(segment
		(start 143.369999 109.150002)
		(end 142.750002 109.150002)
		(width 0.1)
		(layer "F.Cu")
		(net 23)
	)
	(segment
		(start 124.6 123.3)
		(end 124.925 123.625)
		(width 0.1)
		(layer "F.Cu")
		(net 23)
	)
	(segment
		(start 141.48284 119.5)
		(end 141.49142 119.49142)
		(width 0.1)
		(layer "F.Cu")
		(net 23)
	)
	(segment
		(start 135.5 137.5)
		(end 135.25 137.25)
		(width 0.1)
		(layer "F.Cu")
		(net 23)
	)
	(segment
		(start 142.82 55.3)
		(end 142.1 55.3)
		(width 0.5)
		(layer "F.Cu")
		(net 23)
	)
	(segment
		(start 167.9 67.1)
		(end 167.88 67.12)
		(width 0.1)
		(layer "F.Cu")
		(net 23)
	)
	(segment
		(start 132.84 86.725)
		(end 132.845 86.73)
		(width 0.1)
		(layer "F.Cu")
		(net 23)
	)
	(segment
		(start 124.999 149.1)
		(end 124.999 149.549)
		(width 0.25)
		(layer "F.Cu")
		(net 23)
	)
	(segment
		(start 149.704 125.801)
		(end 149.704 127.096)
		(width 0.25)
		(layer "F.Cu")
		(net 23)
	)
	(segment
		(start 125.9 122.65)
		(end 125.575 122.975)
		(width 0.1)
		(layer "F.Cu")
		(net 23)
	)
	(segment
		(start 141.915 76.25)
		(end 141.915 77.25)
		(width 0.3)
		(layer "F.Cu")
		(net 23)
	)
	(segment
		(start 131.1 121.35)
		(end 130.775 121.025)
		(width 0.1)
		(layer "F.Cu")
		(net 23)
	)
	(segment
		(start 159.94 50.725)
		(end 160.625 50.725)
		(width 0.25)
		(layer "F.Cu")
		(net 23)
	)
	(segment
		(start 133.654 80.601)
		(end 133.654 79.454)
		(width 0.25)
		(layer "F.Cu")
		(net 23)
	)
	(segment
		(start 135.88 138.04)
		(end 135.88 137.88)
		(width 0.1)
		(layer "F.Cu")
		(net 23)
	)
	(segment
		(start 127.58 128.23)
		(end 127.525 128.175)
		(width 0.1)
		(layer "F.Cu")
		(net 23)
	)
	(segment
		(start 127.2 121.35)
		(end 126.875 121.675)
		(width 0.1)
		(layer "F.Cu")
		(net 23)
	)
	(segment
		(start 124.6 125.9)
		(end 124.925 125.575)
		(width 0.1)
		(layer "F.Cu")
		(net 23)
	)
	(segment
		(start 127.2 127.85)
		(end 126.875 127.525)
		(width 0.1)
		(layer "F.Cu")
		(net 23)
	)
	(segment
		(start 144.6 61.27)
		(end 145.27 61.27)
		(width 0.25)
		(layer "F.Cu")
		(net 23)
	)
	(segment
		(start 134.5 136.5)
		(end 134.75 136.75)
		(width 0.1)
		(layer "F.Cu")
		(net 23)
	)
	(segment
		(start 127.85 125.25)
		(end 127.2 124.6)
		(width 0.1)
		(layer "F.Cu")
		(net 23)
	)
	(segment
		(start 125 57.2)
		(end 125 58.2)
		(width 0.1)
		(layer "F.Cu")
		(net 23)
	)
	(segment
		(start 117.399 129.301)
		(end 117.4 129.3)
		(width 0.25)
		(layer "F.Cu")
		(net 23)
	)
	(segment
		(start 151.070002 109.150002)
		(end 150.300002 109.150002)
		(width 0.1)
		(layer "F.Cu")
		(net 23)
	)
	(segment
		(start 125.25 123.95)
		(end 124.925 123.625)
		(width 0.1)
		(layer "F.Cu")
		(net 23)
	)
	(segment
		(start 128.901 99.951)
		(end 128.949 99.951)
		(width 0.1)
		(layer "F.Cu")
		(net 23)
	)
	(segment
		(start 143.369998 112.150002)
		(end 142.500002 112.150002)
		(width 0.1)
		(layer "F.Cu")
		(net 23)
	)
	(segment
		(start 129.475 127.525)
		(end 129.8 127.85)
		(width 0.1)
		(layer "F.Cu")
		(net 23)
	)
	(segment
		(start 131.75 122)
		(end 131.425 121.675)
		(width 0.1)
		(layer "F.Cu")
		(net 23)
	)
	(segment
		(start 134.75 137.25)
		(end 135 137)
		(width 0.1)
		(layer "F.Cu")
		(net 23)
	)
	(segment
		(start 136 137.5)
		(end 136.29 137.5)
		(width 0.1)
		(layer "F.Cu")
		(net 23)
	)
	(segment
		(start 137.5 134)
		(end 137.5 133.884)
		(width 0.1)
		(layer "F.Cu")
		(net 23)
	)
	(segment
		(start 138 85.3)
		(end 138.304 85.604)
		(width 0.25)
		(layer "F.Cu")
		(net 23)
	)
	(segment
		(start 124.116 125.33)
		(end 124.116 125.084)
		(width 0.1)
		(layer "F.Cu")
		(net 23)
	)
	(segment
		(start 172.6 74.48)
		(end 172.6 75.2)
		(width 0.1)
		(layer "F.Cu")
		(net 23)
	)
	(segment
		(start 151.255 94.005)
		(end 151.25 94)
		(width 0.25)
		(layer "F.Cu")
		(net 23)
	)
	(segment
		(start 158.565 49.375)
		(end 158.49 49.45)
		(width 0.25)
		(layer "F.Cu")
		(net 23)
	)
	(segment
		(start 124.14 123.49)
		(end 124.275 123.625)
		(width 0.1)
		(layer "F.Cu")
		(net 23)
	)
	(segment
		(start 131.1 121.35)
		(end 131.425 121.675)
		(width 0.1)
		(layer "F.Cu")
		(net 23)
	)
	(segment
		(start 144.2 102.5)
		(end 144.2 102.400002)
		(width 0.1)
		(layer "F.Cu")
		(net 23)
	)
	(segment
		(start 132.075 123.625)
		(end 131.75 123.3)
		(width 0.1)
		(layer "F.Cu")
		(net 23)
	)
	(segment
		(start 177 77.6)
		(end 175.942358 77.6)
		(width 0.25)
		(layer "F.Cu")
		(net 23)
	)
	(segment
		(start 124.07 127.17)
		(end 124.075 127.175)
		(width 0.1)
		(layer "F.Cu")
		(net 23)
	)
	(segment
		(start 138.304 86.954)
		(end 138.304 86.524999)
		(width 0.25)
		(layer "F.Cu")
		(net 23)
	)
	(segment
		(start 124.82 129.01)
		(end 124.82 128.55)
		(width 0.1)
		(layer "F.Cu")
		(net 23)
	)
	(segment
		(start 165.265 63.52)
		(end 165.22 63.52)
		(width 0.1)
		(layer "F.Cu")
		(net 23)
	)
	(segment
		(start 123.44 128.09)
		(end 123.9 128.09)
		(width 0.1)
		(layer "F.Cu")
		(net 23)
	)
	(segment
		(start 130.45 127.85)
		(end 131.1 127.2)
		(width 0.1)
		(layer "F.Cu")
		(net 23)
	)
	(segment
		(start 131.75 127.85)
		(end 132.075 127.525)
		(width 0.1)
		(layer "F.Cu")
		(net 23)
	)
	(segment
		(start 125.92 94.9)
		(end 125.4 94.9)
		(width 0.25)
		(layer "F.Cu")
		(net 23)
	)
	(segment
		(start 132.88 134.88)
		(end 132.88 134.74)
		(width 0.1)
		(layer "F.Cu")
		(net 23)
	)
	(segment
		(start 145.06 115.9)
		(end 145.08 115.92)
		(width 0.25)
		(layer "F.Cu")
		(net 23)
	)
	(segment
		(start 132.5 134.5)
		(end 132.5 134.12)
		(width 0.1)
		(layer "F.Cu")
		(net 23)
	)
	(segment
		(start 124.6 123.95)
		(end 124.925 123.625)
		(width 0.1)
		(layer "F.Cu")
		(net 23)
	)
	(segment
		(start 126.384 128.334)
		(end 126.66 128.334)
		(width 0.1)
		(layer "F.Cu")
		(net 23)
	)
	(segment
		(start 125.9 120.7)
		(end 126.55 121.35)
		(width 0.1)
		(layer "F.Cu")
		(net 23)
	)
	(segment
		(start 131.1 127.2)
		(end 131.75 126.55)
		(width 0.1)
		(layer "F.Cu")
		(net 23)
	)
	(segment
		(start 125.025 95.275)
		(end 125.2 95.1)
		(width 0.25)
		(layer "F.Cu")
		(net 23)
	)
	(segment
		(start 125.9 122)
		(end 126.225 121.675)
		(width 0.1)
		(layer "F.Cu")
		(net 23)
	)
	(segment
		(start 124.3 121.65)
		(end 124.116 121.65)
		(width 0.1)
		(layer "F.Cu")
		(net 23)
	)
	(segment
		(start 119.73 64.73)
		(end 119.7 64.7)
		(width 0.1)
		(layer "F.Cu")
		(net 23)
	)
	(segment
		(start 124.82 119.35)
		(end 124.82 119.83)
		(width 0.1)
		(layer "F.Cu")
		(net 23)
	)
	(segment
		(start 126.66 118.89)
		(end 126.66 119.14)
		(width 0.1)
		(layer "F.Cu")
		(net 23)
	)
	(segment
		(start 133.56 119.35)
		(end 133.56 118.89)
		(width 0.1)
		(layer "F.Cu")
		(net 23)
	)
	(segment
		(start 118.95 71.8)
		(end 119 71.75)
		(width 0.25)
		(layer "F.Cu")
		(net 23)
	)
	(segment
		(start 123.9 121.65)
		(end 124.116 121.65)
		(width 0.1)
		(layer "F.Cu")
		(net 23)
	)
	(segment
		(start 136.88 131.58)
		(end 136.9 131.6)
		(width 0.1)
		(layer "F.Cu")
		(net 23)
	)
	(segment
		(start 127.2 141)
		(end 126.6 141)
		(width 0.5)
		(layer "F.Cu")
		(net 23)
	)
	(segment
		(start 134.5 137)
		(end 134.75 136.75)
		(width 0.1)
		(layer "F.Cu")
		(net 23)
	)
	(segment
		(start 131.75 121.35)
		(end 131.425 121.675)
		(width 0.1)
		(layer "F.Cu")
		(net 23)
	)
	(segment
		(start 156.1 116.551)
		(end 157.251 116.551)
		(width 0.1)
		(layer "F.Cu")
		(net 23)
	)
	(segment
		(start 129.15 127.85)
		(end 129.475 128.175)
		(width 0.1)
		(layer "F.Cu")
		(net 23)
	)
	(segment
		(start 123.9 122.57)
		(end 124.116 122.57)
		(width 0.1)
		(layer "F.Cu")
		(net 23)
	)
	(segment
		(start 117.548 103.852)
		(end 117.5 103.9)
		(width 0.1)
		(layer "F.Cu")
		(net 23)
	)
	(segment
		(start 175.942358 77.6)
		(end 175.822358 77.48)
		(width 0.25)
		(layer "F.Cu")
		(net 23)
	)
	(segment
		(start 138.83 138.18)
		(end 138.83 137.599999)
		(width 0.1)
		(layer "F.Cu")
		(net 23)
	)
	(segment
		(start 133 135)
		(end 132.88 134.88)
		(width 0.1)
		(layer "F.Cu")
		(net 23)
	)
	(segment
		(start 129.15 123.95)
		(end 128.825 123.625)
		(width 0.1)
		(layer "F.Cu")
		(net 23)
	)
	(segment
		(start 131.1 121.35)
		(end 131.425 121.025)
		(width 0.1)
		(layer "F.Cu")
		(net 23)
	)
	(segment
		(start 124.48 73)
		(end 124.5 73.02)
		(width 0.1)
		(layer "F.Cu")
		(net 23)
	)
	(segment
		(start 127.85 120.7)
		(end 127.85 120.05)
		(width 0.1)
		(layer "F.Cu")
		(net 23)
	)
	(segment
		(start 127.564 90.309)
		(end 127.6 90.345)
		(width 0.1)
		(layer "F.Cu")
		(net 23)
	)
	(segment
		(start 124.196 125.25)
		(end 124.6 125.25)
		(width 0.1)
		(layer "F.Cu")
		(net 23)
	)
	(segment
		(start 129.8 119.89)
		(end 129.88 119.81)
		(width 0.1)
		(layer "F.Cu")
		(net 23)
	)
	(segment
		(start 118.601 131.799)
		(end 118.601 131.1)
		(width 0.1)
		(layer "F.Cu")
		(net 23)
	)
	(segment
		(start 119.75 147.498)
		(end 119.75 146.75)
		(width 0.25)
		(layer "F.Cu")
		(net 23)
	)
	(segment
		(start 135 136.5)
		(end 134.75 136.25)
		(width 0.1)
		(layer "F.Cu")
		(net 23)
	)
	(segment
		(start 141.49142 119.49142)
		(end 141.49142 119.45)
		(width 0.1)
		(layer "F.Cu")
		(net 23)
	)
	(segment
		(start 129.42 119.35)
		(end 129.88 119.81)
		(width 0.1)
		(layer "F.Cu")
		(net 23)
	)
	(segment
		(start 129.42 128.55)
		(end 129.42 128.23)
		(width 0.1)
		(layer "F.Cu")
		(net 23)
	)
	(segment
		(start 126.165 128.125)
		(end 126.175 128.125)
		(width 0.1)
		(layer "F.Cu")
		(net 23)
	)
	(segment
		(start 135 136.5)
		(end 135.25 136.75)
		(width 0.1)
		(layer "F.Cu")
		(net 23)
	)
	(segment
		(start 129.4 98.82)
		(end 129.52 98.7)
		(width 0.1)
		(layer "F.Cu")
		(net 23)
	)
	(segment
		(start 142.79 96.674999)
		(end 143.525001 96.674999)
		(width 0.1)
		(layer "F.Cu")
		(net 23)
	)
	(segment
		(start 135 137)
		(end 135.25 136.75)
		(width 0.1)
		(layer "F.Cu")
		(net 23)
	)
	(segment
		(start 116.52 146.38)
		(end 116.5 146.4)
		(width 0.25)
		(layer "F.Cu")
		(net 23)
	)
	(segment
		(start 129.475 126.875)
		(end 129.8 126.55)
		(width 0.1)
		(layer "F.Cu")
		(net 23)
	)
	(segment
		(start 116.52 68.9)
		(end 115.8 68.9)
		(width 0.1)
		(layer "F.Cu")
		(net 23)
	)
	(segment
		(start 131.1 120.7)
		(end 131.425 121.025)
		(width 0.1)
		(layer "F.Cu")
		(net 23)
	)
	(segment
		(start 125.74 128.01)
		(end 125.9 127.85)
		(width 0.1)
		(layer "F.Cu")
		(net 23)
	)
	(segment
		(start 128.5 123.95)
		(end 128.825 123.625)
		(width 0.1)
		(layer "F.Cu")
		(net 23)
	)
	(segment
		(start 127.8 129.55)
		(end 127.58 129.33)
		(width 0.1)
		(layer "F.Cu")
		(net 23)
	)
	(segment
		(start 136.850001 128.67)
		(end 136.87 128.67)
		(width 0.1)
		(layer "F.Cu")
		(net 23)
	)
	(segment
		(start 162 45.82)
		(end 162.78 45.82)
		(width 0.1)
		(layer "F.Cu")
		(net 23)
	)
	(segment
		(start 147.97 76.075)
		(end 147.97 75.75)
		(width 0.5)
		(layer "F.Cu")
		(net 23)
	)
	(segment
		(start 127.2 127.2)
		(end 126.875 127.525)
		(width 0.1)
		(layer "F.Cu")
		(net 23)
	)
	(segment
		(start 129.15 127.2)
		(end 129.475 127.525)
		(width 0.1)
		(layer "F.Cu")
		(net 23)
	)
	(segment
		(start 138.570001 92.600003)
		(end 138.600003 92.600003)
		(width 0.5)
		(layer "F.Cu")
		(net 23)
	)
	(segment
		(start 125.9 127.85)
		(end 126.175 128.125)
		(width 0.1)
		(layer "F.Cu")
		(net 23)
	)
	(segment
		(start 124.6 124.6)
		(end 124.925 124.925)
		(width 0.1)
		(layer "F.Cu")
		(net 23)
	)
	(segment
		(start 127.2 127.2)
		(end 126.875 126.875)
		(width 0.1)
		(layer "F.Cu")
		(net 23)
	)
	(segment
		(start 115.92 108.07)
		(end 115.75 107.9)
		(width 0.1)
		(layer "F.Cu")
		(net 23)
	)
	(segment
		(start 125.25 125.25)
		(end 125.575 125.575)
		(width 0.1)
		(layer "F.Cu")
		(net 23)
	)
	(segment
		(start 124.6 122)
		(end 124.116 122.484)
		(width 0.1)
		(layer "F.Cu")
		(net 23)
	)
	(segment
		(start 117.649 89)
		(end 121.2 89)
		(width 0.25)
		(layer "F.Cu")
		(net 23)
	)
	(segment
		(start 135.88 137.88)
		(end 135.5 137.5)
		(width 0.1)
		(layer "F.Cu")
		(net 23)
	)
	(segment
		(start 127.85 122)
		(end 128.175 122.325)
		(width 0.1)
		(layer "F.Cu")
		(net 23)
	)
	(segment
		(start 124.41 124.14)
		(end 124.6 123.95)
		(width 0.1)
		(layer "F.Cu")
		(net 23)
	)
	(segment
		(start 131.52 116.02)
		(end 131.5 116)
		(width 0.1)
		(layer "F.Cu")
		(net 23)
	)
	(segment
		(start 135.5 136.5)
		(end 135.25 136.75)
		(width 0.1)
		(layer "F.Cu")
		(net 23)
	)
	(segment
		(start 132.675 86.725)
		(end 132.84 86.725)
		(width 0.1)
		(layer "F.Cu")
		(net 23)
	)
	(segment
		(start 138.48 70.2)
		(end 139 70.2)
		(width 0.25)
		(layer "F.Cu")
		(net 23)
	)
	(segment
		(start 159.94 49.375)
		(end 160.675 49.375)
		(width 0.25)
		(layer "F.Cu")
		(net 23)
	)
	(segment
		(start 132.075 125.575)
		(end 131.75 125.25)
		(width 0.1)
		(layer "F.Cu")
		(net 23)
	)
	(segment
		(start 135 136)
		(end 134.75 136.25)
		(width 0.1)
		(layer "F.Cu")
		(net 23)
	)
	(segment
		(start 125.899999 125.25)
		(end 125.575 125.575)
		(width 0.1)
		(layer "F.Cu")
		(net 23)
	)
	(segment
		(start 127.85 125.25)
		(end 128.175 125.575)
		(width 0.1)
		(layer "F.Cu")
		(net 23)
	)
	(segment
		(start 159.25 102.650001)
		(end 159.55 102.350001)
		(width 0.25)
		(layer "F.Cu")
		(net 23)
	)
	(segment
		(start 126.55 122)
		(end 126.875 121.675)
		(width 0.1)
		(layer "F.Cu")
		(net 23)
	)
	(segment
		(start 128.175 122.975)
		(end 128.5 123.3)
		(width 0.1)
		(layer "F.Cu")
		(net 23)
	)
	(segment
		(start 136.5 102.300002)
		(end 136.5 102.3)
		(width 0.1)
		(layer "F.Cu")
		(net 23)
	)
	(segment
		(start 136.1 85.3)
		(end 138 85.3)
		(width 0.25)
		(layer "F.Cu")
		(net 23)
	)
	(segment
		(start 130.45 125.9)
		(end 130.125 125.575)
		(width 0.1)
		(layer "F.Cu")
		(net 23)
	)
	(segment
		(start 124.6 126.55)
		(end 124.3 126.25)
		(width 0.1)
		(layer "F.Cu")
		(net 23)
	)
	(segment
		(start 128.5 119.35)
		(end 128.04 119.81)
		(width 0.1)
		(layer "F.Cu")
		(net 23)
	)
	(segment
		(start 139.750001 128.67)
		(end 139.77 128.67)
		(width 0.1)
		(layer "F.Cu")
		(net 23)
	)
	(segment
		(start 132.075 124.925)
		(end 131.75 124.6)
		(width 0.1)
		(layer "F.Cu")
		(net 23)
	)
	(segment
		(start 159.9 102.700001)
		(end 159.55 102.350001)
		(width 0.25)
		(layer "F.Cu")
		(net 23)
	)
	(segment
		(start 130.125 128.175)
		(end 129.800001 127.85)
		(width 0.1)
		(layer "F.Cu")
		(net 23)
	)
	(segment
		(start 132.075 121.675)
		(end 131.75 121.35)
		(width 0.1)
		(layer "F.Cu")
		(net 23)
	)
	(segment
		(start 121.948107 89.034085)
		(end 121.234085 89.034085)
		(width 0.25)
		(layer "F.Cu")
		(net 23)
	)
	(segment
		(start 131.75 120.7)
		(end 131.425 121.025)
		(width 0.1)
		(layer "F.Cu")
		(net 23)
	)
	(segment
		(start 125.74 128.55)
		(end 125.74 128.01)
		(width 0.1)
		(layer "F.Cu")
		(net 23)
	)
	(segment
		(start 135.669999 112.150001)
		(end 135.150001 112.150001)
		(width 0.1)
		(layer "F.Cu")
		(net 23)
	)
	(segment
		(start 126.55 126.55)
		(end 126.875 126.875)
		(width 0.1)
		(layer "F.Cu")
		(net 23)
	)
	(segment
		(start 132.64 134.5)
		(end 132.88 134.74)
		(width 0.1)
		(layer "F.Cu")
		(net 23)
	)
	(segment
		(start 136 137.5)
		(end 136 137.92)
		(width 0.1)
		(layer "F.Cu")
		(net 23)
	)
	(segment
		(start 123.44 126.25)
		(end 123.9 126.25)
		(width 0.1)
		(layer "F.Cu")
		(net 23)
	)
	(segment
		(start 139.92 138.55)
		(end 139.2 138.55)
		(width 0.1)
		(layer "F.Cu")
		(net 23)
	)
	(segment
		(start 136.67 137.5)
		(end 136.48 137.69)
		(width 0.1)
		(layer "F.Cu")
		(net 23)
	)
	(segment
		(start 124.116 125.33)
		(end 124.196 125.25)
		(width 0.1)
		(layer "F.Cu")
		(net 23)
	)
	(segment
		(start 134 122.1)
		(end 133.99 122.11)
		(width 0.1)
		(layer "F.Cu")
		(net 23)
	)
	(segment
		(start 127.85 120.05)
		(end 127.85 120)
		(width 0.1)
		(layer "F.Cu")
		(net 23)
	)
	(segment
		(start 131.425 127.525)
		(end 131.75 127.85)
		(width 0.1)
		(layer "F.Cu")
		(net 23)
	)
	(segment
		(start 127.58 118.89)
		(end 127.58 119.35)
		(width 0.1)
		(layer "F.Cu")
		(net 23)
	)
	(segment
		(start 129.15 123.3)
		(end 128.825 123.625)
		(width 0.1)
		(layer "F.Cu")
		(net 23)
	)
	(segment
		(start 127.85 125.9)
		(end 128.175 125.575)
		(width 0.1)
		(layer "F.Cu")
		(net 23)
	)
	(segment
		(start 125.249 147.498)
		(end 125.249 146.751)
		(width 0.25)
		(layer "F.Cu")
		(net 23)
	)
	(segment
		(start 123.44 122.57)
		(end 123.9 122.57)
		(width 0.1)
		(layer "F.Cu")
		(net 23)
	)
	(segment
		(start 156.435 96.465499)
		(end 156.55 96.580499)
		(width 0.1)
		(layer "F.Cu")
		(net 23)
	)
	(segment
		(start 134 136)
		(end 134.5 136)
		(width 0.1)
		(layer "F.Cu")
		(net 23)
	)
	(segment
		(start 125.74 128.55)
		(end 126.165 128.125)
		(width 0.1)
		(layer "F.Cu")
		(net 23)
	)
	(segment
		(start 161.13 50.75)
		(end 161.4 51.02)
		(width 0.25)
		(layer "F.Cu")
		(net 23)
	)
	(segment
		(start 135.48 84.68)
		(end 136.1 85.3)
		(width 0.25)
		(layer "F.Cu")
		(net 23)
	)
	(segment
		(start 167.88 67.12)
		(end 167.88 67.8)
		(width 0.1)
		(layer "F.Cu")
		(net 23)
	)
	(segment
		(start 124.48 71)
		(end 124.48 70)
		(width 0.1)
		(layer "F.Cu")
		(net 23)
	)
	(segment
		(start 133.1 118.89)
		(end 133.56 118.89)
		(width 0.1)
		(layer "F.Cu")
		(net 23)
	)
	(segment
		(start 151.07 112.150002)
		(end 150.249998 112.150002)
		(width 0.1)
		(layer "F.Cu")
		(net 23)
	)
	(segment
		(start 134.5 136.5)
		(end 134.75 136.25)
		(width 0.1)
		(layer "F.Cu")
		(net 23)
	)
	(segment
		(start 117.52 140.2)
		(end 117.52 141.498)
		(width 0.25)
		(layer "F.Cu")
		(net 23)
	)
	(segment
		(start 133.1 123.95)
		(end 133.56 123.95)
		(width 0.1)
		(layer "F.Cu")
		(net 23)
	)
	(segment
		(start 124.309669 128.09)
		(end 124.116 128.09)
		(width 0.1)
		(layer "F.Cu")
		(net 23)
	)
	(segment
		(start 131.425 123.625)
		(end 131.75 123.95)
		(width 0.1)
		(layer "F.Cu")
		(net 23)
	)
	(segment
		(start 132.7 93.8)
		(end 133.47 93.8)
		(width 0.25)
		(layer "F.Cu")
		(net 23)
	)
	(segment
		(start 127.58 128.55)
		(end 127.58 128.23)
		(width 0.1)
		(layer "F.Cu")
		(net 23)
	)
	(segment
		(start 123.44 121.65)
		(end 123.9 121.65)
		(width 0.1)
		(layer "F.Cu")
		(net 23)
	)
	(segment
		(start 165.813 69.526999)
		(end 165.813 67.967)
		(width 0.25)
		(layer "F.Cu")
		(net 23)
	)
	(segment
		(start 130.4 142.9)
		(end 129.5 142.9)
		(width 0.25)
		(layer "F.Cu")
		(net 23)
	)
	(segment
		(start 139.2 138.55)
		(end 138.83 138.18)
		(width 0.1)
		(layer "F.Cu")
		(net 23)
	)
	(segment
		(start 131.75 122)
		(end 132.075 122.325)
		(width 0.1)
		(layer "F.Cu")
		(net 23)
	)
	(segment
		(start 123.44 123.49)
		(end 123.9 123.49)
		(width 0.1)
		(layer "F.Cu")
		(net 23)
	)
	(segment
		(start 128.825 127.525)
		(end 129.15 127.85)
		(width 0.1)
		(layer "F.Cu")
		(net 23)
	)
	(segment
		(start 133 134.5)
		(end 132.88 134.62)
		(width 0.1)
		(layer "F.Cu")
		(net 23)
	)
	(segment
		(start 132.075 126.225)
		(end 131.75 125.9)
		(width 0.1)
		(layer "F.Cu")
		(net 23)
	)
	(segment
		(start 127.58 119.35)
		(end 128.04 119.81)
		(width 0.1)
		(layer "F.Cu")
		(net 23)
	)
	(segment
		(start 124.146 120.7)
		(end 124.116 120.73)
		(width 0.1)
		(layer "F.Cu")
		(net 23)
	)
	(segment
		(start 129.8 121.35)
		(end 129.5 121.65)
		(width 0.1)
		(layer "F.Cu")
		(net 23)
	)
	(segment
		(start 130 94.2)
		(end 130 94.75)
		(width 0.1)
		(layer "F.Cu")
		(net 23)
	)
	(segment
		(start 126.225 127.525)
		(end 126.55 127.85)
		(width 0.1)
		(layer "F.Cu")
		(net 23)
	)
	(segment
		(start 124.6 125.9)
		(end 124.25 126.25)
		(width 0.1)
		(layer "F.Cu")
		(net 23)
	)
	(segment
		(start 124.5 73.02)
		(end 124.5 73.75)
		(width 0.1)
		(layer "F.Cu")
		(net 23)
	)
	(segment
		(start 135.5 137)
		(end 135.25 137.25)
		(width 0.1)
		(layer "F.Cu")
		(net 23)
	)
	(segment
		(start 116.301 129.301)
		(end 117.399 129.301)
		(width 0.25)
		(layer "F.Cu")
		(net 23)
	)
	(segment
		(start 116.8 114.4)
		(end 116.8 114.2)
		(width 0.1)
		(layer "F.Cu")
		(net 23)
	)
	(segment
		(start 130.45 120.7)
		(end 129.8 121.35)
		(width 0.1)
		(layer "F.Cu")
		(net 23)
	)
	(segment
		(start 132.62 135)
		(end 132.88 134.74)
		(width 0.1)
		(layer "F.Cu")
		(net 23)
	)
	(segment
		(start 159.25 102.85)
		(end 159.9 102.85)
		(width 0.25)
		(layer "F.Cu")
		(net 23)
	)
	(segment
		(start 149.702 124.914)
		(end 149.702 125.799)
		(width 0.25)
		(layer "F.Cu")
		(net 23)
	)
	(segment
		(start 136.450001 102.350001)
		(end 136.5 102.300002)
		(width 0.1)
		(layer "F.Cu")
		(net 23)
	)
	(segment
		(start 153.32 46.9)
		(end 152.6 46.9)
		(width 0.1)
		(layer "F.Cu")
		(net 23)
	)
	(segment
		(start 126.55 127.85)
		(end 126.225 128.175)
		(width 0.1)
		(layer "F.Cu")
		(net 23)
	)
	(segment
		(start 128.5 125.25)
		(end 128.175 125.575)
		(width 0.1)
		(layer "F.Cu")
		(net 23)
	)
	(segment
		(start 129.8 122)
		(end 129.8 121.95)
		(width 0.1)
		(layer "F.Cu")
		(net 23)
	)
	(via
		(at 141.05 87.75)
		(size 0.45)
		(drill 0.2)
		(layers "F.Cu" "B.Cu")
		(remove_unused_layers yes)
		(keep_end_layers yes)
		(zone_layer_connections "In1.Cu" "In4.Cu")
		(net 23)
	)
	(via
		(at 143.04 106.9)
		(size 0.45)
		(drill 0.2)
		(layers "F.Cu" "B.Cu")
		(remove_unused_layers yes)
		(keep_end_layers yes)
		(zone_layer_connections "In1.Cu" "In4.Cu" "In6.Cu")
		(net 23)
	)
	(via
		(at 162 133.25)
		(size 0.45)
		(drill 0.2)
		(layers "F.Cu" "B.Cu")
		(remove_unused_layers yes)
		(keep_end_layers yes)
		(zone_layer_connections "In1.Cu" "In4.Cu" "In6.Cu")
		(net 23)
	)
	(via
		(at 120 126.6)
		(size 0.45)
		(drill 0.2)
		(layers "F.Cu" "B.Cu")
		(remove_unused_layers yes)
		(keep_end_layers yes)
		(zone_layer_connections "In1.Cu" "In4.Cu" "In6.Cu")
		(net 23)
	)
	(via
		(at 119.95 114.95)
		(size 0.45)
		(drill 0.2)
		(layers "F.Cu" "B.Cu")
		(remove_unused_layers yes)
		(keep_end_layers yes)
		(free yes)
		(zone_layer_connections "In1.Cu" "In4.Cu" "In6.Cu")
		(net 23)
	)
	(via
		(at 142.78 90.75)
		(size 0.45)
		(drill 0.2)
		(layers "F.Cu" "B.Cu")
		(remove_unused_layers yes)
		(keep_end_layers yes)
		(zone_layer_connections "In1.Cu" "In4.Cu")
		(net 23)
	)
	(via
		(at 138.042859 99.3)
		(size 0.45)
		(drill 0.2)
		(layers "F.Cu" "B.Cu")
		(remove_unused_layers yes)
		(keep_end_layers yes)
		(zone_layer_connections "In1.Cu" "In4.Cu" "In6.Cu")
		(net 23)
	)
	(via
		(at 138.83 137.599999)
		(size 0.45)
		(drill 0.2)
		(layers "F.Cu" "B.Cu")
		(remove_unused_layers yes)
		(keep_end_layers yes)
		(zone_layer_connections "In1.Cu" "In4.Cu" "In6.Cu")
		(net 23)
	)
	(via
		(at 119.96 113.16)
		(size 0.45)
		(drill 0.2)
		(layers "F.Cu" "B.Cu")
		(remove_unused_layers yes)
		(keep_end_layers yes)
		(zone_layer_connections "In1.Cu" "In4.Cu" "In6.Cu")
		(net 23)
	)
	(via
		(at 131.26 119.134)
		(size 0.45)
		(drill 0.2)
		(layers "F.Cu" "B.Cu")
		(remove_unused_layers yes)
		(keep_end_layers yes)
		(zone_layer_connections "In1.Cu" "In4.Cu" "In6.Cu")
		(net 23)
	)
	(via
		(at 155.2 98.6)
		(size 0.45)
		(drill 0.2)
		(layers "F.Cu" "B.Cu")
		(remove_unused_layers yes)
		(keep_end_layers yes)
		(zone_layer_connections "In1.Cu" "In4.Cu" "In6.Cu")
		(net 23)
	)
	(via
		(at 149.2 55.6)
		(size 0.45)
		(drill 0.2)
		(layers "F.Cu" "B.Cu")
		(remove_unused_layers yes)
		(keep_end_layers yes)
		(zone_layer_connections "In1.Cu" "In4.Cu" "In6.Cu")
		(net 23)
	)
	(via
		(at 145.375 88.25)
		(size 0.45)
		(drill 0.2)
		(layers "F.Cu" "B.Cu")
		(remove_unused_layers yes)
		(keep_end_layers yes)
		(zone_layer_connections "In1.Cu" "In4.Cu")
		(net 23)
	)
	(via
		(at 136.48 137.69)
		(size 0.45)
		(drill 0.2)
		(layers "F.Cu" "B.Cu")
		(remove_unused_layers yes)
		(keep_end_layers yes)
		(zone_layer_connections "In1.Cu" "In4.Cu" "In6.Cu")
		(net 23)
	)
	(via
		(at 133 60.4)
		(size 0.45)
		(drill 0.2)
		(layers "F.Cu" "B.Cu")
		(remove_unused_layers yes)
		(keep_end_layers yes)
		(zone_layer_connections "In1.Cu" "In4.Cu" "In6.Cu")
		(net 23)
	)
	(via
		(at 123.2 94.9)
		(size 0.45)
		(drill 0.2)
		(layers "F.Cu" "B.Cu")
		(remove_unused_layers yes)
		(keep_end_layers yes)
		(zone_layer_connections "In1.Cu" "In4.Cu" "In6.Cu")
		(net 23)
	)
	(via
		(at 160.945 86.25)
		(size 0.45)
		(drill 0.2)
		(layers "F.Cu" "B.Cu")
		(remove_unused_layers yes)
		(keep_end_layers yes)
		(zone_layer_connections "In1.Cu" "In4.Cu" "In6.Cu")
		(net 23)
	)
	(via
		(at 139.6 69.6)
		(size 0.45)
		(drill 0.2)
		(layers "F.Cu" "B.Cu")
		(remove_unused_layers yes)
		(keep_end_layers yes)
		(zone_layer_connections "In1.Cu" "In4.Cu" "In6.Cu")
		(net 23)
	)
	(via
		(at 158.35 82.75)
		(size 0.45)
		(drill 0.2)
		(layers "F.Cu" "B.Cu")
		(remove_unused_layers yes)
		(keep_end_layers yes)
		(zone_layer_connections "In1.Cu" "In4.Cu" "In6.Cu")
		(net 23)
	)
	(via
		(at 115.8 68.9)
		(size 0.45)
		(drill 0.2)
		(layers "F.Cu" "B.Cu")
		(remove_unused_layers yes)
		(keep_end_layers yes)
		(zone_layer_connections "In1.Cu" "In4.Cu" "In6.Cu")
		(net 23)
	)
	(via
		(at 131.4 88)
		(size 0.45)
		(drill 0.2)
		(layers "F.Cu" "B.Cu")
		(remove_unused_layers yes)
		(keep_end_layers yes)
		(zone_layer_connections "In1.Cu" "In4.Cu" "In6.Cu")
		(net 23)
	)
	(via
		(at 123.5 144)
		(size 0.45)
		(drill 0.2)
		(layers "F.Cu" "B.Cu")
		(remove_unused_layers yes)
		(keep_end_layers yes)
		(zone_layer_connections "In1.Cu" "In4.Cu" "In6.Cu")
		(net 23)
	)
	(via
		(at 167.9 67)
		(size 0.45)
		(drill 0.2)
		(layers "F.Cu" "B.Cu")
		(remove_unused_layers yes)
		(keep_end_layers yes)
		(zone_layer_connections "In1.Cu" "In4.Cu" "In6.Cu")
		(net 23)
	)
	(via
		(at 126.65 89)
		(size 0.45)
		(drill 0.2)
		(layers "F.Cu" "B.Cu")
		(remove_unused_layers yes)
		(keep_end_layers yes)
		(zone_layer_connections "In1.Cu" "In4.Cu" "In6.Cu")
		(net 23)
	)
	(via
		(at 138.7 128.7)
		(size 0.45)
		(drill 0.2)
		(layers "F.Cu" "B.Cu")
		(remove_unused_layers yes)
		(keep_end_layers yes)
		(zone_layer_connections "In1.Cu" "In4.Cu" "In6.Cu")
		(net 23)
	)
	(via
		(at 126.875 126.875)
		(size 0.45)
		(drill 0.2)
		(layers "F.Cu" "B.Cu")
		(remove_unused_layers yes)
		(keep_end_layers yes)
		(zone_layer_connections "In1.Cu" "In4.Cu" "In6.Cu")
		(net 23)
	)
	(via
		(at 119.75 146.75)
		(size 0.45)
		(drill 0.2)
		(layers "F.Cu" "B.Cu")
		(remove_unused_layers yes)
		(keep_end_layers yes)
		(zone_layer_connections "In1.Cu" "In4.Cu" "In6.Cu")
		(net 23)
	)
	(via
		(at 116.6 122.1)
		(size 0.45)
		(drill 0.2)
		(layers "F.Cu" "B.Cu")
		(remove_unused_layers yes)
		(keep_end_layers yes)
		(zone_layer_connections "In1.Cu" "In4.Cu" "In6.Cu")
		(net 23)
	)
	(via
		(at 123 131.75)
		(size 0.45)
		(drill 0.2)
		(layers "F.Cu" "B.Cu")
		(remove_unused_layers yes)
		(keep_end_layers yes)
		(zone_layer_connections "In1.Cu" "In4.Cu" "In6.Cu")
		(net 23)
	)
	(via
		(at 126 133.5)
		(size 0.45)
		(drill 0.2)
		(layers "F.Cu" "B.Cu")
		(remove_unused_layers yes)
		(keep_end_layers yes)
		(zone_layer_connections "In1.Cu" "In4.Cu" "In6.Cu")
		(net 23)
	)
	(via
		(at 144.4 106.2)
		(size 0.45)
		(drill 0.2)
		(layers "F.Cu" "B.Cu")
		(remove_unused_layers yes)
		(keep_end_layers yes)
		(zone_layer_connections "In1.Cu" "In4.Cu" "In6.Cu")
		(net 23)
	)
	(via
		(at 162.9 97.4)
		(size 0.45)
		(drill 0.2)
		(layers "F.Cu" "B.Cu")
		(remove_unused_layers yes)
		(keep_end_layers yes)
		(zone_layer_connections "In1.Cu" "In4.Cu" "In6.Cu")
		(net 23)
	)
	(via
		(at 166.85 94.4)
		(size 0.45)
		(drill 0.2)
		(layers "F.Cu" "B.Cu")
		(remove_unused_layers yes)
		(keep_end_layers yes)
		(zone_layer_connections "In1.Cu" "In4.Cu" "In6.Cu")
		(net 23)
	)
	(via
		(at 120 119.4)
		(size 0.45)
		(drill 0.2)
		(layers "F.Cu" "B.Cu")
		(remove_unused_layers yes)
		(keep_end_layers yes)
		(zone_layer_connections "In1.Cu" "In4.Cu" "In6.Cu")
		(net 23)
	)
	(via
		(at 129.570694 94.923662)
		(size 0.45)
		(drill 0.2)
		(layers "F.Cu" "B.Cu")
		(remove_unused_layers yes)
		(keep_end_layers yes)
		(zone_layer_connections "In1.Cu" "In4.Cu" "In6.Cu")
		(net 23)
	)
	(via
		(at 136.9 55.9)
		(size 0.45)
		(drill 0.2)
		(layers "F.Cu" "B.Cu")
		(remove_unused_layers yes)
		(keep_end_layers yes)
		(zone_layer_connections "In1.Cu" "In4.Cu" "In6.Cu")
		(net 23)
	)
	(via
		(at 156.63 91.75)
		(size 0.45)
		(drill 0.2)
		(layers "F.Cu" "B.Cu")
		(remove_unused_layers yes)
		(keep_end_layers yes)
		(zone_layer_connections "In1.Cu" "In4.Cu")
		(net 23)
	)
	(via
		(at 164.7 63)
		(size 0.45)
		(drill 0.2)
		(layers "F.Cu" "B.Cu")
		(remove_unused_layers yes)
		(keep_end_layers yes)
		(zone_layer_connections "In1.Cu" "In4.Cu" "In6.Cu")
		(net 23)
	)
	(via
		(at 139.8 128.7)
		(size 0.45)
		(drill 0.2)
		(layers "F.Cu" "B.Cu")
		(remove_unused_layers yes)
		(keep_end_layers yes)
		(zone_layer_connections "In1.Cu" "In4.Cu" "In6.Cu")
		(net 23)
	)
	(via
		(at 139.2 112.9)
		(size 0.45)
		(drill 0.2)
		(layers "F.Cu" "B.Cu")
		(remove_unused_layers yes)
		(keep_end_layers yes)
		(zone_layer_connections "In1.Cu" "In4.Cu" "In6.Cu")
		(net 23)
	)
	(via
		(at 133.798281 92.096601)
		(size 0.45)
		(drill 0.2)
		(layers "F.Cu" "B.Cu")
		(remove_unused_layers yes)
		(keep_end_layers yes)
		(zone_layer_connections "In1.Cu" "In4.Cu" "In6.Cu")
		(net 23)
	)
	(via
		(at 143.545 76.25)
		(size 0.45)
		(drill 0.2)
		(layers "F.Cu" "B.Cu")
		(remove_unused_layers yes)
		(keep_end_layers yes)
		(zone_layer_connections "In1.Cu" "In4.Cu" "In6.Cu")
		(net 23)
	)
	(via
		(at 145.9 111.7)
		(size 0.45)
		(drill 0.2)
		(layers "F.Cu" "B.Cu")
		(remove_unused_layers yes)
		(keep_end_layers yes)
		(zone_layer_connections "In1.Cu" "In4.Cu" "In6.Cu")
		(net 23)
	)
	(via
		(at 129.475 126.875)
		(size 0.45)
		(drill 0.2)
		(layers "F.Cu" "B.Cu")
		(remove_unused_layers yes)
		(keep_end_layers yes)
		(zone_layer_connections "In1.Cu" "In4.Cu" "In6.Cu")
		(net 23)
	)
	(via
		(at 156.62 89.75)
		(size 0.45)
		(drill 0.2)
		(layers "F.Cu" "B.Cu")
		(remove_unused_layers yes)
		(keep_end_layers yes)
		(zone_layer_connections "In1.Cu" "In4.Cu")
		(net 23)
	)
	(via
		(at 128.6 144.9)
		(size 0.45)
		(drill 0.2)
		(layers "F.Cu" "B.Cu")
		(remove_unused_layers yes)
		(keep_end_layers yes)
		(zone_layer_connections "In1.Cu" "In4.Cu" "In6.Cu")
		(net 23)
	)
	(via
		(at 155.2 51.3)
		(size 0.45)
		(drill 0.2)
		(layers "F.Cu" "B.Cu")
		(remove_unused_layers yes)
		(keep_end_layers yes)
		(free yes)
		(zone_layer_connections "In1.Cu" "In4.Cu" "In6.Cu")
		(net 23)
	)
	(via
		(at 128.175 125.575)
		(size 0.45)
		(drill 0.2)
		(layers "F.Cu" "B.Cu")
		(remove_unused_layers yes)
		(keep_end_layers yes)
		(zone_layer_connections "In1.Cu" "In4.Cu" "In6.Cu")
		(net 23)
	)
	(via
		(at 133 78.8)
		(size 0.45)
		(drill 0.2)
		(layers "F.Cu" "B.Cu")
		(remove_unused_layers yes)
		(keep_end_layers yes)
		(zone_layer_connections "In1.Cu" "In4.Cu" "In6.Cu")
		(net 23)
	)
	(via
		(at 124.075 127.175)
		(size 0.45)
		(drill 0.2)
		(layers "F.Cu" "B.Cu")
		(remove_unused_layers yes)
		(keep_end_layers yes)
		(zone_layer_connections "In1.Cu" "In4.Cu" "In6.Cu")
		(net 23)
	)
	(via
		(at 128.175 122.975)
		(size 0.45)
		(drill 0.2)
		(layers "F.Cu" "B.Cu")
		(remove_unused_layers yes)
		(keep_end_layers yes)
		(zone_layer_connections "In1.Cu" "In4.Cu" "In6.Cu")
		(net 23)
	)
	(via
		(at 117.5 142.5)
		(size 0.45)
		(drill 0.2)
		(layers "F.Cu" "B.Cu")
		(remove_unused_layers yes)
		(keep_end_layers yes)
		(zone_layer_connections "In1.Cu" "In4.Cu" "In6.Cu")
		(net 23)
	)
	(via
		(at 154.89 88.75)
		(size 0.45)
		(drill 0.2)
		(layers "F.Cu" "B.Cu")
		(remove_unused_layers yes)
		(keep_end_layers yes)
		(zone_layer_connections "In1.Cu" "In4.Cu")
		(net 23)
	)
	(via
		(at 120 116.4)
		(size 0.45)
		(drill 0.2)
		(layers "F.Cu" "B.Cu")
		(remove_unused_layers yes)
		(keep_end_layers yes)
		(zone_layer_connections "In1.Cu" "In4.Cu" "In6.Cu")
		(net 23)
	)
	(via
		(at 151.43 76.75)
		(size 0.45)
		(drill 0.2)
		(layers "F.Cu" "B.Cu")
		(remove_unused_layers yes)
		(keep_end_layers yes)
		(zone_layer_connections "In1.Cu" "In4.Cu")
		(net 23)
	)
	(via
		(at 120 120.6)
		(size 0.45)
		(drill 0.2)
		(layers "F.Cu" "B.Cu")
		(remove_unused_layers yes)
		(keep_end_layers yes)
		(zone_layer_connections "In1.Cu" "In4.Cu" "In6.Cu")
		(net 23)
	)
	(via
		(at 120 125.4)
		(size 0.45)
		(drill 0.2)
		(layers "F.Cu" "B.Cu")
		(remove_unused_layers yes)
		(keep_end_layers yes)
		(zone_layer_connections "In1.Cu" "In4.Cu" "In6.Cu")
		(net 23)
	)
	(via
		(at 166 67)
		(size 0.45)
		(drill 0.2)
		(layers "F.Cu" "B.Cu")
		(remove_unused_layers yes)
		(keep_end_layers yes)
		(zone_layer_connections "In1.Cu" "In4.Cu" "In6.Cu")
		(net 23)
	)
	(via
		(at 139.4 93.4)
		(size 0.45)
		(drill 0.2)
		(layers "F.Cu" "B.Cu")
		(remove_unused_layers yes)
		(keep_end_layers yes)
		(zone_layer_connections "In1.Cu" "In4.Cu" "In6.Cu")
		(net 23)
	)
	(via
		(at 120.3 149.85)
		(size 0.45)
		(drill 0.2)
		(layers "F.Cu" "B.Cu")
		(remove_unused_layers yes)
		(keep_end_layers yes)
		(zone_layer_connections "In1.Cu" "In4.Cu" "In6.Cu")
		(net 23)
	)
	(via
		(at 143.645 78.25)
		(size 0.45)
		(drill 0.2)
		(layers "F.Cu" "B.Cu")
		(remove_unused_layers yes)
		(keep_end_layers yes)
		(zone_layer_connections "In1.Cu" "In4.Cu" "In6.Cu")
		(net 23)
	)
	(via
		(at 144.51 74.75)
		(size 0.45)
		(drill 0.2)
		(layers "F.Cu" "B.Cu")
		(remove_unused_layers yes)
		(keep_end_layers yes)
		(zone_layer_connections "In1.Cu" "In4.Cu" "In6.Cu")
		(net 23)
	)
	(via
		(at 144.51 72.75)
		(size 0.45)
		(drill 0.2)
		(layers "F.Cu" "B.Cu")
		(remove_unused_layers yes)
		(keep_end_layers yes)
		(zone_layer_connections "In1.Cu" "In4.Cu" "In6.Cu")
		(net 23)
	)
	(via
		(at 124.5 148.3)
		(size 0.45)
		(drill 0.2)
		(layers "F.Cu" "B.Cu")
		(remove_unused_layers yes)
		(keep_end_layers yes)
		(zone_layer_connections "In1.Cu" "In4.Cu" "In6.Cu")
		(net 23)
	)
	(via
		(at 134.8 111.8)
		(size 0.45)
		(drill 0.2)
		(layers "F.Cu" "B.Cu")
		(remove_unused_layers yes)
		(keep_end_layers yes)
		(zone_layer_connections "In1.Cu" "In4.Cu" "In6.Cu")
		(net 23)
	)
	(via
		(at 153.16 91.75)
		(size 0.45)
		(drill 0.2)
		(layers "F.Cu" "B.Cu")
		(remove_unused_layers yes)
		(keep_end_layers yes)
		(zone_layer_connections "In1.Cu" "In4.Cu")
		(net 23)
	)
	(via
		(at 179.8 67.3)
		(size 0.45)
		(drill 0.2)
		(layers "F.Cu" "B.Cu")
		(remove_unused_layers yes)
		(keep_end_layers yes)
		(zone_layer_connections "In1.Cu" "In4.Cu" "In6.Cu")
		(net 23)
	)
	(via
		(at 132.88 134.74)
		(size 0.45)
		(drill 0.2)
		(layers "F.Cu" "B.Cu")
		(remove_unused_layers yes)
		(keep_end_layers yes)
		(zone_layer_connections "In1.Cu" "In4.Cu" "In6.Cu")
		(net 23)
	)
	(via
		(at 159.215 86.25)
		(size 0.45)
		(drill 0.2)
		(layers "F.Cu" "B.Cu")
		(remove_unused_layers yes)
		(keep_end_layers yes)
		(zone_layer_connections "In1.Cu" "In4.Cu")
		(net 23)
	)
	(via
		(at 131.425 121.025)
		(size 0.45)
		(drill 0.2)
		(layers "F.Cu" "B.Cu")
		(remove_unused_layers yes)
		(keep_end_layers yes)
		(zone_layer_connections "In1.Cu" "In4.Cu" "In6.Cu")
		(net 23)
	)
	(via
		(at 142.78 86.75)
		(size 0.45)
		(drill 0.2)
		(layers "F.Cu" "B.Cu")
		(remove_unused_layers yes)
		(keep_end_layers yes)
		(zone_layer_connections "In1.Cu" "In4.Cu")
		(net 23)
	)
	(via
		(at 153.6 112.699999)
		(size 0.45)
		(drill 0.2)
		(layers "F.Cu" "B.Cu")
		(remove_unused_layers yes)
		(keep_end_layers yes)
		(zone_layer_connections "In1.Cu" "In4.Cu" "In6.Cu")
		(net 23)
	)
	(via
		(at 151.25 94)
		(size 0.45)
		(drill 0.2)
		(layers "F.Cu" "B.Cu")
		(remove_unused_layers yes)
		(keep_end_layers yes)
		(zone_layer_connections "In1.Cu" "In4.Cu")
		(net 23)
	)
	(via
		(at 119 125.4)
		(size 0.45)
		(drill 0.2)
		(layers "F.Cu" "B.Cu")
		(remove_unused_layers yes)
		(keep_end_layers yes)
		(zone_layer_connections "In1.Cu" "In4.Cu" "In6.Cu")
		(net 23)
	)
	(via
		(at 147.97 77.75)
		(size 0.45)
		(drill 0.2)
		(layers "F.Cu" "B.Cu")
		(remove_unused_layers yes)
		(keep_end_layers yes)
		(zone_layer_connections "In1.Cu" "In4.Cu")
		(net 23)
	)
	(via
		(at 133.798281 91.396601)
		(size 0.45)
		(drill 0.2)
		(layers "F.Cu" "B.Cu")
		(remove_unused_layers yes)
		(keep_end_layers yes)
		(zone_layer_connections "In1.Cu" "In4.Cu" "In6.Cu")
		(net 23)
	)
	(via
		(at 116.8 114.4)
		(size 0.45)
		(drill 0.2)
		(layers "F.Cu" "B.Cu")
		(remove_unused_layers yes)
		(keep_end_layers yes)
		(zone_layer_connections "In1.Cu" "In4.Cu" "In6.Cu")
		(net 23)
	)
	(via
		(at 134.75 137.25)
		(size 0.45)
		(drill 0.2)
		(layers "F.Cu" "B.Cu")
		(remove_unused_layers yes)
		(keep_end_layers yes)
		(zone_layer_connections "In1.Cu" "In4.Cu" "In6.Cu")
		(net 23)
	)
	(via
		(at 134.85 132.6)
		(size 0.45)
		(drill 0.2)
		(layers "F.Cu" "B.Cu")
		(remove_unused_layers yes)
		(keep_end_layers yes)
		(zone_layer_connections "In1.Cu" "In4.Cu" "In6.Cu")
		(net 23)
	)
	(via
		(at 165.85 94.4)
		(size 0.45)
		(drill 0.2)
		(layers "F.Cu" "B.Cu")
		(remove_unused_layers yes)
		(keep_end_layers yes)
		(zone_layer_connections "In1.Cu" "In4.Cu" "In6.Cu")
		(net 23)
	)
	(via
		(at 139.900002 99.3)
		(size 0.45)
		(drill 0.2)
		(layers "F.Cu" "B.Cu")
		(remove_unused_layers yes)
		(keep_end_layers yes)
		(zone_layer_connections "In1.Cu" "In4.Cu" "In6.Cu")
		(net 23)
	)
	(via
		(at 132.4 132.1)
		(size 0.45)
		(drill 0.2)
		(layers "F.Cu" "B.Cu")
		(remove_unused_layers yes)
		(keep_end_layers yes)
		(zone_layer_connections "In1.Cu" "In4.Cu" "In6.Cu")
		(net 23)
	)
	(via
		(at 121.9 144)
		(size 0.45)
		(drill 0.2)
		(layers "F.Cu" "B.Cu")
		(remove_unused_layers yes)
		(keep_end_layers yes)
		(zone_layer_connections "In1.Cu" "In4.Cu" "In6.Cu")
		(net 23)
	)
	(via
		(at 142.45 106.9)
		(size 0.45)
		(drill 0.2)
		(layers "F.Cu" "B.Cu")
		(remove_unused_layers yes)
		(keep_end_layers yes)
		(free yes)
		(zone_layer_connections "In1.Cu" "In4.Cu" "In6.Cu")
		(net 23)
	)
	(via
		(at 135.34 106.9)
		(size 0.45)
		(drill 0.2)
		(layers "F.Cu" "B.Cu")
		(remove_unused_layers yes)
		(keep_end_layers yes)
		(zone_layer_connections "In1.Cu" "In4.Cu" "In6.Cu")
		(net 23)
	)
	(via
		(at 145 53.5)
		(size 0.45)
		(drill 0.2)
		(layers "F.Cu" "B.Cu")
		(remove_unused_layers yes)
		(keep_end_layers yes)
		(zone_layer_connections "In1.Cu" "In4.Cu" "In6.Cu")
		(net 23)
	)
	(via
		(at 142.5 112.15)
		(size 0.45)
		(drill 0.2)
		(layers "F.Cu" "B.Cu")
		(remove_unused_layers yes)
		(keep_end_layers yes)
		(zone_layer_connections "In1.Cu" "In4.Cu" "In6.Cu")
		(net 23)
	)
	(via
		(at 135.75 72.15)
		(size 0.45)
		(drill 0.2)
		(layers "F.Cu" "B.Cu")
		(remove_unused_layers yes)
		(keep_end_layers yes)
		(zone_layer_connections "In1.Cu" "In4.Cu" "In6.Cu")
		(net 23)
	)
	(via
		(at 153.16 74.75)
		(size 0.45)
		(drill 0.2)
		(layers "F.Cu" "B.Cu")
		(remove_unused_layers yes)
		(keep_end_layers yes)
		(zone_layer_connections "In1.Cu" "In4.Cu")
		(net 23)
	)
	(via
		(at 154.89 81.75)
		(size 0.45)
		(drill 0.2)
		(layers "F.Cu" "B.Cu")
		(remove_unused_layers yes)
		(keep_end_layers yes)
		(zone_layer_connections "In1.Cu" "In4.Cu")
		(net 23)
	)
	(via
		(at 158.35 84.75)
		(size 0.45)
		(drill 0.2)
		(layers "F.Cu" "B.Cu")
		(remove_unused_layers yes)
		(keep_end_layers yes)
		(zone_layer_connections "In1.Cu" "In4.Cu")
		(net 23)
	)
	(via
		(at 136.5 102.3)
		(size 0.45)
		(drill 0.2)
		(layers "F.Cu" "B.Cu")
		(remove_unused_layers yes)
		(keep_end_layers yes)
		(zone_layer_connections "In1.Cu" "In4.Cu" "In6.Cu")
		(net 23)
	)
	(via
		(at 155.26 65.655)
		(size 0.45)
		(drill 0.2)
		(layers "F.Cu" "B.Cu")
		(remove_unused_layers yes)
		(keep_end_layers yes)
		(zone_layer_connections "In1.Cu" "In4.Cu" "In6.Cu")
		(net 23)
	)
	(via
		(at 166.85 95.4)
		(size 0.45)
		(drill 0.2)
		(layers "F.Cu" "B.Cu")
		(remove_unused_layers yes)
		(keep_end_layers yes)
		(zone_layer_connections "In1.Cu" "In4.Cu" "In6.Cu")
		(net 23)
	)
	(via
		(at 115.8 117.6)
		(size 0.45)
		(drill 0.2)
		(layers "F.Cu" "B.Cu")
		(remove_unused_layers yes)
		(keep_end_layers yes)
		(zone_layer_connections "In1.Cu" "In4.Cu" "In6.Cu")
		(net 23)
	)
	(via
		(at 166.85 93.4)
		(size 0.45)
		(drill 0.2)
		(layers "F.Cu" "B.Cu")
		(remove_unused_layers yes)
		(keep_end_layers yes)
		(zone_layer_connections "In1.Cu" "In4.Cu" "In6.Cu")
		(net 23)
	)
	(via
		(at 150 95.35)
		(size 0.45)
		(drill 0.2)
		(layers "F.Cu" "B.Cu")
		(remove_unused_layers yes)
		(keep_end_layers yes)
		(zone_layer_connections "In1.Cu" "In4.Cu")
		(net 23)
	)
	(via
		(at 149.7 76.75)
		(size 0.45)
		(drill 0.2)
		(layers "F.Cu" "B.Cu")
		(remove_unused_layers yes)
		(keep_end_layers yes)
		(zone_layer_connections "In1.Cu" "In4.Cu")
		(net 23)
	)
	(via
		(at 159.215 76.25)
		(size 0.45)
		(drill 0.2)
		(layers "F.Cu" "B.Cu")
		(remove_unused_layers yes)
		(keep_end_layers yes)
		(zone_layer_connections "In1.Cu" "In4.Cu" "In6.Cu")
		(net 23)
	)
	(via
		(at 156.145 91.25)
		(size 0.45)
		(drill 0.2)
		(layers "F.Cu" "B.Cu")
		(remove_unused_layers yes)
		(keep_end_layers yes)
		(zone_layer_connections "In1.Cu" "In4.Cu")
		(net 23)
	)
	(via
		(at 132.075 126.225)
		(size 0.45)
		(drill 0.2)
		(layers "F.Cu" "B.Cu")
		(remove_unused_layers yes)
		(keep_end_layers yes)
		(zone_layer_connections "In1.Cu" "In4.Cu" "In6.Cu")
		(net 23)
	)
	(via
		(at 129.475 128.175)
		(size 0.45)
		(drill 0.2)
		(layers "F.Cu" "B.Cu")
		(remove_unused_layers yes)
		(keep_end_layers yes)
		(zone_layer_connections "In1.Cu" "In4.Cu" "In6.Cu")
		(net 23)
	)
	(via
		(at 154.5 112.699999)
		(size 0.45)
		(drill 0.2)
		(layers "F.Cu" "B.Cu")
		(remove_unused_layers yes)
		(keep_end_layers yes)
		(zone_layer_connections "In1.Cu" "In4.Cu" "In6.Cu")
		(net 23)
	)
	(via
		(at 158.35 83.75)
		(size 0.45)
		(drill 0.2)
		(layers "F.Cu" "B.Cu")
		(remove_unused_layers yes)
		(keep_end_layers yes)
		(zone_layer_connections "In1.Cu" "In4.Cu" "In6.Cu")
		(net 23)
	)
	(via
		(at 119.95 114.36)
		(size 0.45)
		(drill 0.2)
		(layers "F.Cu" "B.Cu")
		(remove_unused_layers yes)
		(keep_end_layers yes)
		(zone_layer_connections "In1.Cu" "In4.Cu" "In6.Cu")
		(net 23)
	)
	(via
		(at 161.3 112.699999)
		(size 0.45)
		(drill 0.2)
		(layers "F.Cu" "B.Cu")
		(remove_unused_layers yes)
		(keep_end_layers yes)
		(zone_layer_connections "In1.Cu" "In4.Cu" "In6.Cu")
		(net 23)
	)
	(via
		(at 132.75 88)
		(size 0.45)
		(drill 0.2)
		(layers "F.Cu" "B.Cu")
		(remove_unused_layers yes)
		(keep_end_layers yes)
		(zone_layer_connections "In1.Cu" "In4.Cu" "In6.Cu")
		(net 23)
	)
	(via
		(at 115.797488 125.4)
		(size 0.45)
		(drill 0.2)
		(layers "F.Cu" "B.Cu")
		(remove_unused_layers yes)
		(keep_end_layers yes)
		(zone_layer_connections "In1.Cu" "In4.Cu" "In6.Cu")
		(net 23)
	)
	(via
		(at 120 122.4)
		(size 0.45)
		(drill 0.2)
		(layers "F.Cu" "B.Cu")
		(remove_unused_layers yes)
		(keep_end_layers yes)
		(zone_layer_connections "In1.Cu" "In4.Cu" "In6.Cu")
		(net 23)
	)
	(via
		(at 152.3 51.8)
		(size 0.45)
		(drill 0.2)
		(layers "F.Cu" "B.Cu")
		(remove_unused_layers yes)
		(keep_end_layers yes)
		(free yes)
		(zone_layer_connections "In1.Cu" "In4.Cu" "In6.Cu")
		(net 23)
	)
	(via
		(at 153.16 89.75)
		(size 0.45)
		(drill 0.2)
		(layers "F.Cu" "B.Cu")
		(remove_unused_layers yes)
		(keep_end_layers yes)
		(zone_layer_connections "In1.Cu" "In4.Cu")
		(net 23)
	)
	(via
		(at 166.85 97.4)
		(size 0.45)
		(drill 0.2)
		(layers "F.Cu" "B.Cu")
		(remove_unused_layers yes)
		(keep_end_layers yes)
		(zone_layer_connections "In1.Cu" "In4.Cu" "In6.Cu")
		(net 23)
	)
	(via
		(at 128.5 119.134)
		(size 0.45)
		(drill 0.2)
		(layers "F.Cu" "B.Cu")
		(remove_unused_layers yes)
		(keep_end_layers yes)
		(zone_layer_connections "In1.Cu" "In4.Cu" "In6.Cu")
		(net 23)
	)
	(via
		(at 116.6 89.3)
		(size 0.45)
		(drill 0.2)
		(layers "F.Cu" "B.Cu")
		(remove_unused_layers yes)
		(keep_end_layers yes)
		(zone_layer_connections "In1.Cu" "In4.Cu" "In6.Cu")
		(net 23)
	)
	(via
		(at 151.43 79.75)
		(size 0.45)
		(drill 0.2)
		(layers "F.Cu" "B.Cu")
		(remove_unused_layers yes)
		(keep_end_layers yes)
		(zone_layer_connections "In1.Cu" "In4.Cu")
		(net 23)
	)
	(via
		(at 135 66.4)
		(size 0.45)
		(drill 0.2)
		(layers "F.Cu" "B.Cu")
		(remove_unused_layers yes)
		(keep_end_layers yes)
		(zone_layer_connections "In1.Cu" "In4.Cu" "In6.Cu")
		(net 23)
	)
	(via
		(at 136.7 106.91)
		(size 0.45)
		(drill 0.2)
		(layers "F.Cu" "B.Cu")
		(remove_unused_layers yes)
		(keep_end_layers yes)
		(zone_layer_connections "In1.Cu" "In4.Cu" "In6.Cu")
		(net 23)
	)
	(via
		(at 129.943073 100.027302)
		(size 0.45)
		(drill 0.2)
		(layers "F.Cu" "B.Cu")
		(remove_unused_layers yes)
		(keep_end_layers yes)
		(zone_layer_connections "In1.Cu" "In4.Cu" "In6.Cu")
		(net 23)
	)
	(via
		(at 124.8 104)
		(size 0.45)
		(drill 0.2)
		(layers "F.Cu" "B.Cu")
		(remove_unused_layers yes)
		(keep_end_layers yes)
		(zone_layer_connections "In1.Cu" "In4.Cu" "In6.Cu")
		(net 23)
	)
	(via
		(at 159.21 106.2)
		(size 0.45)
		(drill 0.2)
		(layers "F.Cu" "B.Cu")
		(remove_unused_layers yes)
		(keep_end_layers yes)
		(zone_layer_connections "In1.Cu" "In4.Cu" "In6.Cu")
		(net 23)
	)
	(via
		(at 156.62 83.75)
		(size 0.45)
		(drill 0.2)
		(layers "F.Cu" "B.Cu")
		(remove_unused_layers yes)
		(keep_end_layers yes)
		(zone_layer_connections "In1.Cu" "In4.Cu")
		(net 23)
	)
	(via
		(at 124.116 122.57)
		(size 0.45)
		(drill 0.2)
		(layers "F.Cu" "B.Cu")
		(remove_unused_layers yes)
		(keep_end_layers yes)
		(zone_layer_connections "In1.Cu" "In4.Cu" "In6.Cu")
		(net 23)
	)
	(via
		(at 139.8 93.8)
		(size 0.45)
		(drill 0.2)
		(layers "F.Cu" "B.Cu")
		(remove_unused_layers yes)
		(keep_end_layers yes)
		(zone_layer_connections "In1.Cu" "In4.Cu" "In6.Cu")
		(net 23)
	)
	(via
		(at 158.109999 66.645001)
		(size 0.45)
		(drill 0.2)
		(layers "F.Cu" "B.Cu")
		(remove_unused_layers yes)
		(keep_end_layers yes)
		(zone_layer_connections "In1.Cu" "In4.Cu" "In6.Cu")
		(net 23)
	)
	(via
		(at 160.08 72.75)
		(size 0.45)
		(drill 0.2)
		(layers "F.Cu" "B.Cu")
		(remove_unused_layers yes)
		(keep_end_layers yes)
		(zone_layer_connections "In1.Cu" "In4.Cu" "In6.Cu")
		(net 23)
	)
	(via
		(at 154.6 50.7)
		(size 0.45)
		(drill 0.2)
		(layers "F.Cu" "B.Cu")
		(remove_unused_layers yes)
		(keep_end_layers yes)
		(free yes)
		(zone_layer_connections "In1.Cu" "In4.Cu" "In6.Cu")
		(net 23)
	)
	(via
		(at 134.75 136.75)
		(size 0.45)
		(drill 0.2)
		(layers "F.Cu" "B.Cu")
		(remove_unused_layers yes)
		(keep_end_layers yes)
		(zone_layer_connections "In1.Cu" "In4.Cu" "In6.Cu")
		(net 23)
	)
	(via
		(at 175.620002 145.42)
		(size 0.45)
		(drill 0.2)
		(layers "F.Cu" "B.Cu")
		(remove_unused_layers yes)
		(keep_end_layers yes)
		(zone_layer_connections "In1.Cu" "In4.Cu" "In6.Cu")
		(net 23)
	)
	(via
		(at 147.97 79.75)
		(size 0.45)
		(drill 0.2)
		(layers "F.Cu" "B.Cu")
		(remove_unused_layers yes)
		(keep_end_layers yes)
		(zone_layer_connections "In1.Cu" "In4.Cu")
		(net 23)
	)
	(via
		(at 133.9 137.6)
		(size 0.45)
		(drill 0.2)
		(layers "F.Cu" "B.Cu")
		(remove_unused_layers yes)
		(keep_end_layers yes)
		(zone_layer_connections "In1.Cu" "In4.Cu" "In6.Cu")
		(net 23)
	)
	(via
		(at 128.7 134.9)
		(size 0.45)
		(drill 0.2)
		(layers "F.Cu" "B.Cu")
		(remove_unused_layers yes)
		(keep_end_layers yes)
		(zone_layer_connections "In1.Cu" "In4.Cu" "In6.Cu")
		(net 23)
	)
	(via
		(at 160.25 136)
		(size 0.45)
		(drill 0.2)
		(layers "F.Cu" "B.Cu")
		(remove_unused_layers yes)
		(keep_end_layers yes)
		(zone_layer_connections "In1.Cu" "In4.Cu" "In6.Cu")
		(net 23)
	)
	(via
		(at 151.61 106.2)
		(size 0.45)
		(drill 0.2)
		(layers "F.Cu" "B.Cu")
		(remove_unused_layers yes)
		(keep_end_layers yes)
		(zone_layer_connections "In1.Cu" "In4.Cu" "In6.Cu")
		(net 23)
	)
	(via
		(at 157.485 86.25)
		(size 0.45)
		(drill 0.2)
		(layers "F.Cu" "B.Cu")
		(remove_unused_layers yes)
		(keep_end_layers yes)
		(zone_layer_connections "In1.Cu" "In4.Cu")
		(net 23)
	)
	(via
		(at 117.5 103.9)
		(size 0.45)
		(drill 0.2)
		(layers "F.Cu" "B.Cu")
		(remove_unused_layers yes)
		(keep_end_layers yes)
		(zone_layer_connections "In1.Cu" "In4.Cu" "In6.Cu")
		(net 23)
	)
	(via
		(at 150 94)
		(size 0.45)
		(drill 0.2)
		(layers "F.Cu" "B.Cu")
		(remove_unused_layers yes)
		(keep_end_layers yes)
		(zone_layer_connections "In1.Cu" "In4.Cu")
		(net 23)
	)
	(via
		(at 150.84 106.9)
		(size 0.45)
		(drill 0.2)
		(layers "F.Cu" "B.Cu")
		(remove_unused_layers yes)
		(keep_end_layers yes)
		(zone_layer_connections "In1.Cu" "In4.Cu" "In6.Cu")
		(net 23)
	)
	(via
		(at 145.9 112.699999)
		(size 0.45)
		(drill 0.2)
		(layers "F.Cu" "B.Cu")
		(remove_unused_layers yes)
		(keep_end_layers yes)
		(zone_layer_connections "In1.Cu" "In4.Cu" "In6.Cu")
		(net 23)
	)
	(via
		(at 142.399998 99.1)
		(size 0.45)
		(drill 0.2)
		(layers "F.Cu" "B.Cu")
		(remove_unused_layers yes)
		(keep_end_layers yes)
		(zone_layer_connections "In1.Cu" "In4.Cu" "In6.Cu")
		(net 23)
	)
	(via
		(at 164.5 139.25)
		(size 0.45)
		(drill 0.2)
		(layers "F.Cu" "B.Cu")
		(remove_unused_layers yes)
		(keep_end_layers yes)
		(zone_layer_connections "In1.Cu" "In4.Cu" "In6.Cu")
		(net 23)
	)
	(via
		(at 146.24 76.75)
		(size 0.45)
		(drill 0.2)
		(layers "F.Cu" "B.Cu")
		(remove_unused_layers yes)
		(keep_end_layers yes)
		(zone_layer_connections "In1.Cu" "In4.Cu")
		(net 23)
	)
	(via
		(at 134.75 136.25)
		(size 0.45)
		(drill 0.2)
		(layers "F.Cu" "B.Cu")
		(remove_unused_layers yes)
		(keep_end_layers yes)
		(zone_layer_connections "In1.Cu" "In4.Cu" "In6.Cu")
		(net 23)
	)
	(via
		(at 152.9 51.2)
		(size 0.45)
		(drill 0.2)
		(layers "F.Cu" "B.Cu")
		(remove_unused_layers yes)
		(keep_end_layers yes)
		(free yes)
		(zone_layer_connections "In1.Cu" "In4.Cu" "In6.Cu")
		(net 23)
	)
	(via
		(at 116.602512 119.1)
		(size 0.45)
		(drill 0.2)
		(layers "F.Cu" "B.Cu")
		(remove_unused_layers yes)
		(keep_end_layers yes)
		(zone_layer_connections "In1.Cu" "In4.Cu" "In6.Cu")
		(net 23)
	)
	(via
		(at 144.51 86.75)
		(size 0.45)
		(drill 0.2)
		(layers "F.Cu" "B.Cu")
		(remove_unused_layers yes)
		(keep_end_layers yes)
		(zone_layer_connections "In1.Cu" "In4.Cu")
		(net 23)
	)
	(via
		(at 139.4 105.5)
		(size 0.45)
		(drill 0.2)
		(layers "F.Cu" "B.Cu")
		(remove_unused_layers yes)
		(keep_end_layers yes)
		(zone_layer_connections "In1.Cu" "In4.Cu" "In6.Cu")
		(net 23)
	)
	(via
		(at 141.915 81.25)
		(size 0.45)
		(drill 0.2)
		(layers "F.Cu" "B.Cu")
		(remove_unused_layers yes)
		(keep_end_layers yes)
		(zone_layer_connections "In1.Cu" "In4.Cu" "In6.Cu")
		(net 23)
	)
	(via
		(at 125 58.2)
		(size 0.45)
		(drill 0.2)
		(layers "F.Cu" "B.Cu")
		(remove_unused_layers yes)
		(keep_end_layers yes)
		(zone_layer_connections "In1.Cu" "In4.Cu" "In6.Cu")
		(net 23)
	)
	(via
		(at 146.8 111.7)
		(size 0.45)
		(drill 0.2)
		(layers "F.Cu" "B.Cu")
		(remove_unused_layers yes)
		(keep_end_layers yes)
		(zone_layer_connections "In1.Cu" "In4.Cu" "In6.Cu")
		(net 23)
	)
	(via
		(at 126.65 77)
		(size 0.45)
		(drill 0.2)
		(layers "F.Cu" "B.Cu")
		(remove_unused_layers yes)
		(keep_end_layers yes)
		(zone_layer_connections "In1.Cu" "In4.Cu" "In6.Cu")
		(net 23)
	)
	(via
		(at 160.75 60.4)
		(size 0.45)
		(drill 0.2)
		(layers "F.Cu" "B.Cu")
		(remove_unused_layers yes)
		(keep_end_layers yes)
		(zone_layer_connections "In1.Cu" "In4.Cu" "In6.Cu")
		(net 23)
	)
	(via
		(at 161.25 133.25)
		(size 0.45)
		(drill 0.2)
		(layers "F.Cu" "B.Cu")
		(remove_unused_layers yes)
		(keep_end_layers yes)
		(zone_layer_connections "In1.Cu" "In4.Cu" "In6.Cu")
		(net 23)
	)
	(via
		(at 143.645 89.25)
		(size 0.45)
		(drill 0.2)
		(layers "F.Cu" "B.Cu")
		(remove_unused_layers yes)
		(keep_end_layers yes)
		(zone_layer_connections "In1.Cu" "In4.Cu")
		(net 23)
	)
	(via
		(at 161.3 113.7)
		(size 0.45)
		(drill 0.2)
		(layers "F.Cu" "B.Cu")
		(remove_unused_layers yes)
		(keep_end_layers yes)
		(zone_layer_connections "In1.Cu" "In4.Cu" "In6.Cu")
		(net 23)
	)
	(via
		(at 147.2 55.6)
		(size 0.45)
		(drill 0.2)
		(layers "F.Cu" "B.Cu")
		(remove_unused_layers yes)
		(keep_end_layers yes)
		(zone_layer_connections "In1.Cu" "In4.Cu" "In6.Cu")
		(net 23)
	)
	(via
		(at 141.915 71.25)
		(size 0.45)
		(drill 0.2)
		(layers "F.Cu" "B.Cu")
		(remove_unused_layers yes)
		(keep_end_layers yes)
		(zone_layer_connections "In1.Cu" "In4.Cu" "In6.Cu")
		(net 23)
	)
	(via
		(at 143.645 81.25)
		(size 0.45)
		(drill 0.2)
		(layers "F.Cu" "B.Cu")
		(remove_unused_layers yes)
		(keep_end_layers yes)
		(zone_layer_connections "In1.Cu" "In4.Cu" "In6.Cu")
		(net 23)
	)
	(via
		(at 122.25 80.25)
		(size 0.45)
		(drill 0.2)
		(layers "F.Cu" "B.Cu")
		(remove_unused_layers yes)
		(keep_end_layers yes)
		(zone_layer_connections "In1.Cu" "In4.Cu" "In6.Cu")
		(net 23)
	)
	(via
		(at 130.6 103.1)
		(size 0.45)
		(drill 0.2)
		(layers "F.Cu" "B.Cu")
		(remove_unused_layers yes)
		(keep_end_layers yes)
		(zone_layer_connections "In1.Cu" "In4.Cu" "In6.Cu")
		(net 23)
	)
	(via
		(at 115.797488 120.6)
		(size 0.45)
		(drill 0.2)
		(layers "F.Cu" "B.Cu")
		(remove_unused_layers yes)
		(keep_end_layers yes)
		(zone_layer_connections "In1.Cu" "In4.Cu" "In6.Cu")
		(net 23)
	)
	(via
		(at 128.175 123.625)
		(size 0.45)
		(drill 0.2)
		(layers "F.Cu" "B.Cu")
		(remove_unused_layers yes)
		(keep_end_layers yes)
		(zone_layer_connections "In1.Cu" "In4.Cu" "In6.Cu")
		(net 23)
	)
	(via
		(at 138.75 112.55)
		(size 0.45)
		(drill 0.2)
		(layers "F.Cu" "B.Cu")
		(remove_unused_layers yes)
		(keep_end_layers yes)
		(zone_layer_connections "In1.Cu" "In4.Cu" "In6.Cu")
		(net 23)
	)
	(via
		(at 124.925 123.625)
		(size 0.45)
		(drill 0.2)
		(layers "F.Cu" "B.Cu")
		(remove_unused_layers yes)
		(keep_end_layers yes)
		(zone_layer_connections "In1.Cu" "In4.Cu" "In6.Cu")
		(net 23)
	)
	(via
		(at 143.7 118.2)
		(size 0.45)
		(drill 0.2)
		(layers "F.Cu" "B.Cu")
		(remove_unused_layers yes)
		(keep_end_layers yes)
		(zone_layer_connections "In1.Cu" "In4.Cu" "In6.Cu")
		(net 23)
	)
	(via
		(at 158 109.15)
		(size 0.45)
		(drill 0.2)
		(layers "F.Cu" "B.Cu")
		(remove_unused_layers yes)
		(keep_end_layers yes)
		(zone_layer_connections "In1.Cu" "In4.Cu" "In6.Cu")
		(net 23)
	)
	(via
		(at 132.075 122.325)
		(size 0.45)
		(drill 0.2)
		(layers "F.Cu" "B.Cu")
		(remove_unused_layers yes)
		(keep_end_layers yes)
		(zone_layer_connections "In1.Cu" "In4.Cu" "In6.Cu")
		(net 23)
	)
	(via
		(at 130.125 125.575)
		(size 0.45)
		(drill 0.2)
		(layers "F.Cu" "B.Cu")
		(remove_unused_layers yes)
		(keep_end_layers yes)
		(zone_layer_connections "In1.Cu" "In4.Cu" "In6.Cu")
		(net 23)
	)
	(via
		(at 132.5 134.12)
		(size 0.45)
		(drill 0.2)
		(layers "F.Cu" "B.Cu")
		(remove_unused_layers yes)
		(keep_end_layers yes)
		(zone_layer_connections "In1.Cu" "In4.Cu" "In6.Cu")
		(net 23)
	)
	(via
		(at 153.18 77.76)
		(size 0.45)
		(drill 0.2)
		(layers "F.Cu" "B.Cu")
		(remove_unused_layers yes)
		(keep_end_layers yes)
		(zone_layer_connections "In1.Cu" "In4.Cu")
		(net 23)
	)
	(via
		(at 155.2 50.7)
		(size 0.45)
		(drill 0.2)
		(layers "F.Cu" "B.Cu")
		(remove_unused_layers yes)
		(keep_end_layers yes)
		(free yes)
		(zone_layer_connections "In1.Cu" "In4.Cu" "In6.Cu")
		(net 23)
	)
	(via
		(at 115.9 107.1)
		(size 0.45)
		(drill 0.2)
		(layers "F.Cu" "B.Cu")
		(remove_unused_layers yes)
		(keep_end_layers yes)
		(zone_layer_connections "In1.Cu" "In4.Cu" "In6.Cu")
		(net 23)
	)
	(via
		(at 147.97 76.75)
		(size 0.45)
		(drill 0.2)
		(layers "F.Cu" "B.Cu")
		(remove_unused_layers yes)
		(keep_end_layers yes)
		(zone_layer_connections "In1.Cu" "In4.Cu")
		(net 23)
	)
	(via
		(at 165.85 95.4)
		(size 0.45)
		(drill 0.2)
		(layers "F.Cu" "B.Cu")
		(remove_unused_layers yes)
		(keep_end_layers yes)
		(zone_layer_connections "In1.Cu" "In4.Cu" "In6.Cu")
		(net 23)
	)
	(via
		(at 152.2 106.2)
		(size 0.45)
		(drill 0.2)
		(layers "F.Cu" "B.Cu")
		(remove_unused_layers yes)
		(keep_end_layers yes)
		(zone_layer_connections "In1.Cu" "In4.Cu" "In6.Cu")
		(net 23)
	)
	(via
		(at 143.5 134)
		(size 0.45)
		(drill 0.2)
		(layers "F.Cu" "B.Cu")
		(remove_unused_layers yes)
		(keep_end_layers yes)
		(zone_layer_connections "In1.Cu" "In4.Cu" "In6.Cu")
		(net 23)
	)
	(via
		(at 141.05 82.75)
		(size 0.45)
		(drill 0.2)
		(layers "F.Cu" "B.Cu")
		(remove_unused_layers yes)
		(keep_end_layers yes)
		(zone_layer_connections "In1.Cu" "In4.Cu" "In6.Cu")
		(net 23)
	)
	(via
		(at 151.6 145.4)
		(size 0.45)
		(drill 0.2)
		(layers "F.Cu" "B.Cu")
		(remove_unused_layers yes)
		(keep_end_layers yes)
		(zone_layer_connections "In1.Cu" "In4.Cu" "In6.Cu")
		(net 23)
	)
	(via
		(at 162.6 70.8)
		(size 0.45)
		(drill 0.2)
		(layers "F.Cu" "B.Cu")
		(remove_unused_layers yes)
		(keep_end_layers yes)
		(zone_layer_connections "In1.Cu" "In4.Cu" "In6.Cu")
		(net 23)
	)
	(via
		(at 159.8 106.2)
		(size 0.45)
		(drill 0.2)
		(layers "F.Cu" "B.Cu")
		(remove_unused_layers yes)
		(keep_end_layers yes)
		(zone_layer_connections "In1.Cu" "In4.Cu" "In6.Cu")
		(net 23)
	)
	(via
		(at 159.215 74.25)
		(size 0.45)
		(drill 0.2)
		(layers "F.Cu" "B.Cu")
		(remove_unused_layers yes)
		(keep_end_layers yes)
		(zone_layer_connections "In1.Cu" "In4.Cu" "In6.Cu")
		(net 23)
	)
	(via
		(at 183.75 87.25)
		(size 0.45)
		(drill 0.2)
		(layers "F.Cu" "B.Cu")
		(remove_unused_layers yes)
		(keep_end_layers yes)
		(zone_layer_connections "In1.Cu" "In4.Cu" "In6.Cu")
		(net 23)
	)
	(via
		(at 164.5 129.25)
		(size 0.45)
		(drill 0.2)
		(layers "F.Cu" "B.Cu")
		(remove_unused_layers yes)
		(keep_end_layers yes)
		(zone_layer_connections "In1.Cu" "In4.Cu" "In6.Cu")
		(net 23)
	)
	(via
		(at 158.44 106.2)
		(size 0.45)
		(drill 0.2)
		(layers "F.Cu" "B.Cu")
		(remove_unused_layers yes)
		(keep_end_layers yes)
		(zone_layer_connections "In1.Cu" "In4.Cu" "In6.Cu")
		(net 23)
	)
	(via
		(at 159.25 102.85)
		(size 0.45)
		(drill 0.2)
		(layers "F.Cu" "B.Cu")
		(remove_unused_layers yes)
		(keep_end_layers yes)
		(zone_layer_connections "In1.Cu" "In4.Cu" "In6.Cu")
		(net 23)
	)
	(via
		(at 128.225 128.125)
		(size 0.45)
		(drill 0.2)
		(layers "F.Cu" "B.Cu")
		(remove_unused_layers yes)
		(keep_end_layers yes)
		(zone_layer_connections "In1.Cu" "In4.Cu" "In6.Cu")
		(net 23)
	)
	(via
		(at 124.925 125.575)
		(size 0.45)
		(drill 0.2)
		(layers "F.Cu" "B.Cu")
		(remove_unused_layers yes)
		(keep_end_layers yes)
		(zone_layer_connections "In1.Cu" "In4.Cu" "In6.Cu")
		(net 23)
	)
	(via
		(at 161.3 114.7)
		(size 0.45)
		(drill 0.2)
		(layers "F.Cu" "B.Cu")
		(remove_unused_layers yes)
		(keep_end_layers yes)
		(zone_layer_connections "In1.Cu" "In4.Cu" "In6.Cu")
		(net 23)
	)
	(via
		(at 152.6 46.9)
		(size 0.45)
		(drill 0.2)
		(layers "F.Cu" "B.Cu")
		(remove_unused_layers yes)
		(keep_end_layers yes)
		(zone_layer_connections "In1.Cu" "In4.Cu" "In6.Cu")
		(net 23)
	)
	(via
		(at 122.27 128.775)
		(size 0.45)
		(drill 0.2)
		(layers "F.Cu" "B.Cu")
		(remove_unused_layers yes)
		(keep_end_layers yes)
		(zone_layer_connections "In1.Cu" "In4.Cu" "In6.Cu")
		(net 23)
	)
	(via
		(at 159.215 78.25)
		(size 0.45)
		(drill 0.2)
		(layers "F.Cu" "B.Cu")
		(remove_unused_layers yes)
		(keep_end_layers yes)
		(zone_layer_connections "In1.Cu" "In4.Cu" "In6.Cu")
		(net 23)
	)
	(via
		(at 134.75 106.9)
		(size 0.45)
		(drill 0.2)
		(layers "F.Cu" "B.Cu")
		(remove_unused_layers yes)
		(keep_end_layers yes)
		(free yes)
		(zone_layer_connections "In1.Cu" "In4.Cu" "In6.Cu")
		(net 23)
	)
	(via
		(at 128.7 136.4)
		(size 0.45)
		(drill 0.2)
		(layers "F.Cu" "B.Cu")
		(remove_unused_layers yes)
		(keep_end_layers yes)
		(zone_layer_connections "In1.Cu" "In4.Cu" "In6.Cu")
		(net 23)
	)
	(via
		(at 141.05 73.75)
		(size 0.45)
		(drill 0.2)
		(layers "F.Cu" "B.Cu")
		(remove_unused_layers yes)
		(keep_end_layers yes)
		(zone_layer_connections "In1.Cu" "In4.Cu" "In6.Cu")
		(net 23)
	)
	(via
		(at 154.9 105.48)
		(size 0.45)
		(drill 0.2)
		(layers "F.Cu" "B.Cu")
		(remove_unused_layers yes)
		(keep_end_layers yes)
		(zone_layer_connections "In1.Cu" "In4.Cu" "In6.Cu")
		(net 23)
	)
	(via
		(at 124.116 126.25)
		(size 0.45)
		(drill 0.2)
		(layers "F.Cu" "B.Cu")
		(remove_unused_layers yes)
		(keep_end_layers yes)
		(zone_layer_connections "In1.Cu" "In4.Cu" "In6.Cu")
		(net 23)
	)
	(via
		(at 179 71.7)
		(size 0.45)
		(drill 0.2)
		(layers "F.Cu" "B.Cu")
		(remove_unused_layers yes)
		(keep_end_layers yes)
		(zone_layer_connections "In1.Cu" "In4.Cu" "In6.Cu")
		(net 23)
	)
	(via
		(at 115.797488 126.6)
		(size 0.45)
		(drill 0.2)
		(layers "F.Cu" "B.Cu")
		(remove_unused_layers yes)
		(keep_end_layers yes)
		(zone_layer_connections "In1.Cu" "In4.Cu" "In6.Cu")
		(net 23)
	)
	(via
		(at 130.775 121.675)
		(size 0.45)
		(drill 0.2)
		(layers "F.Cu" "B.Cu")
		(remove_unused_layers yes)
		(keep_end_layers yes)
		(zone_layer_connections "In1.Cu" "In4.Cu" "In6.Cu")
		(net 23)
	)
	(via
		(at 132.898281 92.796601)
		(size 0.45)
		(drill 0.2)
		(layers "F.Cu" "B.Cu")
		(remove_unused_layers yes)
		(keep_end_layers yes)
		(zone_layer_connections "In1.Cu" "In4.Cu" "In6.Cu")
		(net 23)
	)
	(via
		(at 142.78 83.75)
		(size 0.45)
		(drill 0.2)
		(layers "F.Cu" "B.Cu")
		(remove_unused_layers yes)
		(keep_end_layers yes)
		(zone_layer_connections "In1.Cu" "In4.Cu" "In6.Cu")
		(net 23)
	)
	(via
		(at 124.116 121.65)
		(size 0.45)
		(drill 0.2)
		(layers "F.Cu" "B.Cu")
		(remove_unused_layers yes)
		(keep_end_layers yes)
		(zone_layer_connections "In1.Cu" "In4.Cu" "In6.Cu")
		(net 23)
	)
	(via
		(at 130.9 131.6)
		(size 0.45)
		(drill 0.2)
		(layers "F.Cu" "B.Cu")
		(remove_unused_layers yes)
		(keep_end_layers yes)
		(zone_layer_connections "In1.Cu" "In4.Cu" "In6.Cu")
		(net 23)
	)
	(via
		(at 116.6 120.9)
		(size 0.45)
		(drill 0.2)
		(layers "F.Cu" "B.Cu")
		(remove_unused_layers yes)
		(keep_end_layers yes)
		(zone_layer_connections "In1.Cu" "In4.Cu" "In6.Cu")
		(net 23)
	)
	(via
		(at 130.2 101.8)
		(size 0.45)
		(drill 0.2)
		(layers "F.Cu" "B.Cu")
		(remove_unused_layers yes)
		(keep_end_layers yes)
		(zone_layer_connections "In1.Cu" "In4.Cu" "In6.Cu")
		(net 23)
	)
	(via
		(at 124.275 123.625)
		(size 0.45)
		(drill 0.2)
		(layers "F.Cu" "B.Cu")
		(remove_unused_layers yes)
		(keep_end_layers yes)
		(zone_layer_connections "In1.Cu" "In4.Cu" "In6.Cu")
		(net 23)
	)
	(via
		(at 136.98 124.15)
		(size 0.45)
		(drill 0.2)
		(layers "F.Cu" "B.Cu")
		(remove_unused_layers yes)
		(keep_end_layers yes)
		(zone_layer_connections "In1.Cu" "In4.Cu" "In6.Cu")
		(net 23)
	)
	(via
		(at 157.485 82.25)
		(size 0.45)
		(drill 0.2)
		(layers "F.Cu" "B.Cu")
		(remove_unused_layers yes)
		(keep_end_layers yes)
		(zone_layer_connections "In1.Cu" "In4.Cu" "In6.Cu")
		(net 23)
	)
	(via
		(at 154.5 113.700001)
		(size 0.45)
		(drill 0.2)
		(layers "F.Cu" "B.Cu")
		(remove_unused_layers yes)
		(keep_end_layers yes)
		(zone_layer_connections "In1.Cu" "In4.Cu" "In6.Cu")
		(net 23)
	)
	(via
		(at 150.25 106.9)
		(size 0.45)
		(drill 0.2)
		(layers "F.Cu" "B.Cu")
		(remove_unused_layers yes)
		(keep_end_layers yes)
		(free yes)
		(zone_layer_connections "In1.Cu" "In4.Cu" "In6.Cu")
		(net 23)
	)
	(via
		(at 119 126.6)
		(size 0.45)
		(drill 0.2)
		(layers "F.Cu" "B.Cu")
		(remove_unused_layers yes)
		(keep_end_layers yes)
		(zone_layer_connections "In1.Cu" "In4.Cu" "In6.Cu")
		(net 23)
	)
	(via
		(at 154.89 89.75)
		(size 0.45)
		(drill 0.2)
		(layers "F.Cu" "B.Cu")
		(remove_unused_layers yes)
		(keep_end_layers yes)
		(zone_layer_connections "In1.Cu" "In4.Cu")
		(net 23)
	)
	(via
		(at 142.5 108.9)
		(size 0.45)
		(drill 0.2)
		(layers "F.Cu" "B.Cu")
		(remove_unused_layers yes)
		(keep_end_layers yes)
		(zone_layer_connections "In1.Cu" "In4.Cu" "In6.Cu")
		(net 23)
	)
	(via
		(at 129.920694 95.373662)
		(size 0.45)
		(drill 0.2)
		(layers "F.Cu" "B.Cu")
		(remove_unused_layers yes)
		(keep_end_layers yes)
		(zone_layer_connections "In1.Cu" "In4.Cu" "In6.Cu")
		(net 23)
	)
	(via
		(at 142.78 80.75)
		(size 0.45)
		(drill 0.2)
		(layers "F.Cu" "B.Cu")
		(remove_unused_layers yes)
		(keep_end_layers yes)
		(zone_layer_connections "In1.Cu" "In4.Cu" "In6.Cu")
		(net 23)
	)
	(via
		(at 150.565 89.25)
		(size 0.45)
		(drill 0.2)
		(layers "F.Cu" "B.Cu")
		(remove_unused_layers yes)
		(keep_end_layers yes)
		(zone_layer_connections "In1.Cu" "In4.Cu")
		(net 23)
	)
	(via
		(at 149.7 77.75)
		(size 0.45)
		(drill 0.2)
		(layers "F.Cu" "B.Cu")
		(remove_unused_layers yes)
		(keep_end_layers yes)
		(zone_layer_connections "In1.Cu" "In4.Cu")
		(net 23)
	)
	(via
		(at 134.25 88)
		(size 0.45)
		(drill 0.2)
		(layers "F.Cu" "B.Cu")
		(remove_unused_layers yes)
		(keep_end_layers yes)
		(zone_layer_connections "In1.Cu" "In4.Cu" "In6.Cu")
		(net 23)
	)
	(via
		(at 135.75 73.35)
		(size 0.45)
		(drill 0.2)
		(layers "F.Cu" "B.Cu")
		(remove_unused_layers yes)
		(keep_end_layers yes)
		(zone_layer_connections "In1.Cu" "In4.Cu" "In6.Cu")
		(net 23)
	)
	(via
		(at 146.25 77.75)
		(size 0.45)
		(drill 0.2)
		(layers "F.Cu" "B.Cu")
		(remove_unused_layers yes)
		(keep_end_layers yes)
		(zone_layer_connections "In1.Cu" "In4.Cu")
		(net 23)
	)
	(via
		(at 147.6 96.9)
		(size 0.45)
		(drill 0.2)
		(layers "F.Cu" "B.Cu")
		(remove_unused_layers yes)
		(keep_end_layers yes)
		(zone_layer_connections "In1.Cu" "In4.Cu")
		(net 23)
	)
	(via
		(at 161.9 96.4)
		(size 0.45)
		(drill 0.2)
		(layers "F.Cu" "B.Cu")
		(remove_unused_layers yes)
		(keep_end_layers yes)
		(zone_layer_connections "In1.Cu" "In4.Cu" "In6.Cu")
		(net 23)
	)
	(via
		(at 121.6 128.6)
		(size 0.45)
		(drill 0.2)
		(layers "F.Cu" "B.Cu")
		(remove_unused_layers yes)
		(keep_end_layers yes)
		(zone_layer_connections "In1.Cu" "In4.Cu" "In6.Cu")
		(net 23)
	)
	(via
		(at 145.9 113.7)
		(size 0.45)
		(drill 0.2)
		(layers "F.Cu" "B.Cu")
		(remove_unused_layers yes)
		(keep_end_layers yes)
		(zone_layer_connections "In1.Cu" "In4.Cu" "In6.Cu")
		(net 23)
	)
	(via
		(at 156.62 85.75)
		(size 0.45)
		(drill 0.2)
		(layers "F.Cu" "B.Cu")
		(remove_unused_layers yes)
		(keep_end_layers yes)
		(zone_layer_connections "In1.Cu" "In4.Cu")
		(net 23)
	)
	(via
		(at 155.755 80.25)
		(size 0.45)
		(drill 0.2)
		(layers "F.Cu" "B.Cu")
		(remove_unused_layers yes)
		(keep_end_layers yes)
		(zone_layer_connections "In1.Cu" "In4.Cu" "In6.Cu")
		(net 23)
	)
	(via
		(at 157.3 116.6)
		(size 0.45)
		(drill 0.2)
		(layers "F.Cu" "B.Cu")
		(remove_unused_layers yes)
		(keep_end_layers yes)
		(zone_layer_connections "In1.Cu" "In4.Cu" "In6.Cu")
		(net 23)
	)
	(via
		(at 149.65 122.25)
		(size 0.45)
		(drill 0.2)
		(layers "F.Cu" "B.Cu")
		(remove_unused_layers yes)
		(keep_end_layers yes)
		(zone_layer_connections "In1.Cu" "In4.Cu" "In6.Cu")
		(net 23)
	)
	(via
		(at 136.75 73.35)
		(size 0.45)
		(drill 0.2)
		(layers "F.Cu" "B.Cu")
		(remove_unused_layers yes)
		(keep_end_layers yes)
		(zone_layer_connections "In1.Cu" "In4.Cu" "In6.Cu")
		(net 23)
	)
	(via
		(at 154.89 90.75)
		(size 0.45)
		(drill 0.2)
		(layers "F.Cu" "B.Cu")
		(remove_unused_layers yes)
		(keep_end_layers yes)
		(zone_layer_connections "In1.Cu" "In4.Cu")
		(net 23)
	)
	(via
		(at 141.05 89.75)
		(size 0.45)
		(drill 0.2)
		(layers "F.Cu" "B.Cu")
		(remove_unused_layers yes)
		(keep_end_layers yes)
		(zone_layer_connections "In1.Cu" "In4.Cu")
		(net 23)
	)
	(via
		(at 146.25 79.75)
		(size 0.45)
		(drill 0.2)
		(layers "F.Cu" "B.Cu")
		(remove_unused_layers yes)
		(keep_end_layers yes)
		(zone_layer_connections "In1.Cu" "In4.Cu")
		(net 23)
	)
	(via
		(at 130.34 129.01)
		(size 0.45)
		(drill 0.2)
		(layers "F.Cu" "B.Cu")
		(remove_unused_layers yes)
		(keep_end_layers yes)
		(zone_layer_connections "In1.Cu" "In4.Cu" "In6.Cu")
		(net 23)
	)
	(via
		(at 155.755 82.25)
		(size 0.45)
		(drill 0.2)
		(layers "F.Cu" "B.Cu")
		(remove_unused_layers yes)
		(keep_end_layers yes)
		(zone_layer_connections "In1.Cu" "In4.Cu" "In6.Cu")
		(net 23)
	)
	(via
		(at 163.25 138.75)
		(size 0.45)
		(drill 0.2)
		(layers "F.Cu" "B.Cu")
		(remove_unused_layers yes)
		(keep_end_layers yes)
		(zone_layer_connections "In1.Cu" "In4.Cu" "In6.Cu")
		(net 23)
	)
	(via
		(at 125 149.55)
		(size 0.45)
		(drill 0.2)
		(layers "F.Cu" "B.Cu")
		(remove_unused_layers yes)
		(keep_end_layers yes)
		(zone_layer_connections "In1.Cu" "In4.Cu" "In6.Cu")
		(net 23)
	)
	(via
		(at 136.75 75.85)
		(size 0.45)
		(drill 0.2)
		(layers "F.Cu" "B.Cu")
		(remove_unused_layers yes)
		(keep_end_layers yes)
		(zone_layer_connections "In1.Cu" "In4.Cu" "In6.Cu")
		(net 23)
	)
	(via
		(at 154.025 80.25)
		(size 0.45)
		(drill 0.2)
		(layers "F.Cu" "B.Cu")
		(remove_unused_layers yes)
		(keep_end_layers yes)
		(zone_layer_connections "In1.Cu" "In4.Cu")
		(net 23)
	)
	(via
		(at 136.75 78.85)
		(size 0.45)
		(drill 0.2)
		(layers "F.Cu" "B.Cu")
		(remove_unused_layers yes)
		(keep_end_layers yes)
		(zone_layer_connections "In1.Cu" "In4.Cu" "In6.Cu")
		(net 23)
	)
	(via
		(at 134.8 128.7)
		(size 0.45)
		(drill 0.2)
		(layers "F.Cu" "B.Cu")
		(remove_unused_layers yes)
		(keep_end_layers yes)
		(zone_layer_connections "In1.Cu" "In4.Cu" "In6.Cu")
		(net 23)
	)
	(via
		(at 133 138.5)
		(size 0.45)
		(drill 0.2)
		(layers "F.Cu" "B.Cu")
		(remove_unused_layers yes)
		(keep_end_layers yes)
		(zone_layer_connections "In1.Cu" "In4.Cu" "In6.Cu")
		(net 23)
	)
	(via
		(at 143.81 106.2)
		(size 0.45)
		(drill 0.2)
		(layers "F.Cu" "B.Cu")
		(remove_unused_layers yes)
		(keep_end_layers yes)
		(zone_layer_connections "In1.Cu" "In4.Cu" "In6.Cu")
		(net 23)
	)
	(via
		(at 126.66 128.334)
		(size 0.45)
		(drill 0.2)
		(layers "F.Cu" "B.Cu")
		(remove_unused_layers yes)
		(keep_end_layers yes)
		(zone_layer_connections "In1.Cu" "In4.Cu" "In6.Cu")
		(net 23)
	)
	(via
		(at 115.8 70.9)
		(size 0.45)
		(drill 0.2)
		(layers "F.Cu" "B.Cu")
		(remove_unused_layers yes)
		(keep_end_layers yes)
		(zone_layer_connections "In1.Cu" "In4.Cu" "In6.Cu")
		(net 23)
	)
	(via
		(at 136.75 72.15)
		(size 0.45)
		(drill 0.2)
		(layers "F.Cu" "B.Cu")
		(remove_unused_layers yes)
		(keep_end_layers yes)
		(zone_layer_connections "In1.Cu" "In4.Cu" "In6.Cu")
		(net 23)
	)
	(via
		(at 131.4 116)
		(size 0.45)
		(drill 0.2)
		(layers "F.Cu" "B.Cu")
		(remove_unused_layers yes)
		(keep_end_layers yes)
		(zone_layer_connections "In1.Cu" "In4.Cu" "In6.Cu")
		(net 23)
	)
	(via
		(at 130.270694 94.923662)
		(size 0.45)
		(drill 0.2)
		(layers "F.Cu" "B.Cu")
		(remove_unused_layers yes)
		(keep_end_layers yes)
		(zone_layer_connections "In1.Cu" "In4.Cu" "In6.Cu")
		(net 23)
	)
	(via
		(at 120.37 109.5)
		(size 0.45)
		(drill 0.2)
		(layers "F.Cu" "B.Cu")
		(remove_unused_layers yes)
		(keep_end_layers yes)
		(zone_layer_connections "In1.Cu" "In4.Cu" "In6.Cu")
		(net 23)
	)
	(via
		(at 153.6 113.7)
		(size 0.45)
		(drill 0.2)
		(layers "F.Cu" "B.Cu")
		(remove_unused_layers yes)
		(keep_end_layers yes)
		(zone_layer_connections "In1.Cu" "In4.Cu" "In6.Cu")
		(net 23)
	)
	(via
		(at 119.25 113.75)
		(size 0.45)
		(drill 0.2)
		(layers "F.Cu" "B.Cu")
		(remove_unused_layers yes)
		(keep_end_layers yes)
		(zone_layer_connections "In1.Cu" "In4.Cu" "In6.Cu")
		(net 23)
	)
	(via
		(at 144.51 84.75)
		(size 0.45)
		(drill 0.2)
		(layers "F.Cu" "B.Cu")
		(remove_unused_layers yes)
		(keep_end_layers yes)
		(zone_layer_connections "In1.Cu" "In4.Cu")
		(net 23)
	)
	(via
		(at 115.75 107.9)
		(size 0.45)
		(drill 0.2)
		(layers "F.Cu" "B.Cu")
		(remove_unused_layers yes)
		(keep_end_layers yes)
		(zone_layer_connections "In1.Cu" "In4.Cu" "In6.Cu")
		(net 23)
	)
	(via
		(at 136.75 88.75)
		(size 0.45)
		(drill 0.2)
		(layers "F.Cu" "B.Cu")
		(remove_unused_layers yes)
		(keep_end_layers yes)
		(zone_layer_connections "In1.Cu" "In4.Cu" "In6.Cu")
		(net 23)
	)
	(via
		(at 132.675 86.725)
		(size 0.45)
		(drill 0.2)
		(layers "F.Cu" "B.Cu")
		(remove_unused_layers yes)
		(keep_end_layers yes)
		(zone_layer_connections "In1.Cu" "In4.Cu" "In6.Cu")
		(net 23)
	)
	(via
		(at 157.85 106.9)
		(size 0.45)
		(drill 0.2)
		(layers "F.Cu" "B.Cu")
		(remove_unused_layers yes)
		(keep_end_layers yes)
		(free yes)
		(zone_layer_connections "In1.Cu" "In4.Cu" "In6.Cu")
		(net 23)
	)
	(via
		(at 159 45.82)
		(size 0.45)
		(drill 0.2)
		(layers "F.Cu" "B.Cu")
		(remove_unused_layers yes)
		(keep_end_layers yes)
		(zone_layer_connections "In1.Cu" "In4.Cu" "In6.Cu")
		(net 23)
	)
	(via
		(at 131.6 140.4)
		(size 0.45)
		(drill 0.2)
		(layers "F.Cu" "B.Cu")
		(remove_unused_layers yes)
		(keep_end_layers yes)
		(zone_layer_connections "In1.Cu" "In4.Cu" "In6.Cu")
		(net 23)
	)
	(via
		(at 116.6 128.1)
		(size 0.45)
		(drill 0.2)
		(layers "F.Cu" "B.Cu")
		(remove_unused_layers yes)
		(keep_end_layers yes)
		(zone_layer_connections "In1.Cu" "In4.Cu" "In6.Cu")
		(net 23)
	)
	(via
		(at 143.645 85.25)
		(size 0.45)
		(drill 0.2)
		(layers "F.Cu" "B.Cu")
		(remove_unused_layers yes)
		(keep_end_layers yes)
		(zone_layer_connections "In1.Cu" "In4.Cu")
		(net 23)
	)
	(via
		(at 130.270694 95.823662)
		(size 0.45)
		(drill 0.2)
		(layers "F.Cu" "B.Cu")
		(remove_unused_layers yes)
		(keep_end_layers yes)
		(zone_layer_connections "In1.Cu" "In4.Cu" "In6.Cu")
		(net 23)
	)
	(via
		(at 153.6 114.7)
		(size 0.45)
		(drill 0.2)
		(layers "F.Cu" "B.Cu")
		(remove_unused_layers yes)
		(keep_end_layers yes)
		(zone_layer_connections "In1.Cu" "In4.Cu" "In6.Cu")
		(net 23)
	)
	(via
		(at 126.875 121.675)
		(size 0.45)
		(drill 0.2)
		(layers "F.Cu" "B.Cu")
		(remove_unused_layers yes)
		(keep_end_layers yes)
		(zone_layer_connections "In1.Cu" "In4.Cu" "In6.Cu")
		(net 23)
	)
	(via
		(at 151.43 78.75)
		(size 0.45)
		(drill 0.2)
		(layers "F.Cu" "B.Cu")
		(remove_unused_layers yes)
		(keep_end_layers yes)
		(zone_layer_connections "In1.Cu" "In4.Cu")
		(net 23)
	)
	(via
		(at 119.5 149.55)
		(size 0.45)
		(drill 0.2)
		(layers "F.Cu" "B.Cu")
		(remove_unused_layers yes)
		(keep_end_layers yes)
		(zone_layer_connections "In1.Cu" "In4.Cu" "In6.Cu")
		(net 23)
	)
	(via
		(at 144.51 90.75)
		(size 0.45)
		(drill 0.2)
		(layers "F.Cu" "B.Cu")
		(remove_unused_layers yes)
		(keep_end_layers yes)
		(zone_layer_connections "In1.Cu" "In4.Cu")
		(net 23)
	)
	(via
		(at 152.9 50.6)
		(size 0.45)
		(drill 0.2)
		(layers "F.Cu" "B.Cu")
		(remove_unused_layers yes)
		(keep_end_layers yes)
		(free yes)
		(zone_layer_connections "In1.Cu" "In4.Cu" "In6.Cu")
		(net 23)
	)
	(via
		(at 124.5 73.75)
		(size 0.45)
		(drill 0.2)
		(layers "F.Cu" "B.Cu")
		(remove_unused_layers yes)
		(keep_end_layers yes)
		(zone_layer_connections "In1.Cu" "In4.Cu" "In6.Cu")
		(net 23)
	)
	(via
		(at 129.8 136.3)
		(size 0.45)
		(drill 0.2)
		(layers "F.Cu" "B.Cu")
		(remove_unused_layers yes)
		(keep_end_layers yes)
		(zone_layer_connections "In1.Cu" "In4.Cu" "In6.Cu")
		(net 23)
	)
	(via
		(at 135.85 132.6)
		(size 0.45)
		(drill 0.2)
		(layers "F.Cu" "B.Cu")
		(remove_unused_layers yes)
		(keep_end_layers yes)
		(zone_layer_connections "In1.Cu" "In4.Cu" "In6.Cu")
		(net 23)
	)
	(via
		(at 141.915 89.25)
		(size 0.45)
		(drill 0.2)
		(layers "F.Cu" "B.Cu")
		(remove_unused_layers yes)
		(keep_end_layers yes)
		(zone_layer_connections "In1.Cu" "In4.Cu")
		(net 23)
	)
	(via
		(at 160.945 74.25)
		(size 0.45)
		(drill 0.2)
		(layers "F.Cu" "B.Cu")
		(remove_unused_layers yes)
		(keep_end_layers yes)
		(zone_layer_connections "In1.Cu" "In4.Cu" "In6.Cu")
		(net 23)
	)
	(via
		(at 119 117.6)
		(size 0.45)
		(drill 0.2)
		(layers "F.Cu" "B.Cu")
		(remove_unused_layers yes)
		(keep_end_layers yes)
		(zone_layer_connections "In1.Cu" "In4.Cu" "In6.Cu")
		(net 23)
	)
	(via
		(at 160.945 81.25)
		(size 0.45)
		(drill 0.2)
		(layers "F.Cu" "B.Cu")
		(remove_unused_layers yes)
		(keep_end_layers yes)
		(zone_layer_connections "In1.Cu" "In4.Cu" "In6.Cu")
		(net 23)
	)
	(via
		(at 132 130.2)
		(size 0.45)
		(drill 0.2)
		(layers "F.Cu" "B.Cu")
		(remove_unused_layers yes)
		(keep_end_layers yes)
		(zone_layer_connections "In1.Cu" "In4.Cu" "In6.Cu")
		(net 23)
	)
	(via
		(at 126.875 126.225)
		(size 0.45)
		(drill 0.2)
		(layers "F.Cu" "B.Cu")
		(remove_unused_layers yes)
		(keep_end_layers yes)
		(zone_layer_connections "In1.Cu" "In4.Cu" "In6.Cu")
		(net 23)
	)
	(via
		(at 132.5 115.5)
		(size 0.45)
		(drill 0.2)
		(layers "F.Cu" "B.Cu")
		(remove_unused_layers yes)
		(keep_end_layers yes)
		(zone_layer_connections "In1.Cu" "In4.Cu" "In6.Cu")
		(net 23)
	)
	(via
		(at 120 117.6)
		(size 0.45)
		(drill 0.2)
		(layers "F.Cu" "B.Cu")
		(remove_unused_layers yes)
		(keep_end_layers yes)
		(zone_layer_connections "In1.Cu" "In4.Cu" "In6.Cu")
		(net 23)
	)
	(via
		(at 119.96 113.75)
		(size 0.45)
		(drill 0.2)
		(layers "F.Cu" "B.Cu")
		(remove_unused_layers yes)
		(keep_end_layers yes)
		(zone_layer_connections "In1.Cu" "In4.Cu" "In6.Cu")
		(net 23)
	)
	(via
		(at 142.45 106.2)
		(size 0.45)
		(drill 0.2)
		(layers "F.Cu" "B.Cu")
		(remove_unused_layers yes)
		(keep_end_layers yes)
		(zone_layer_connections "In1.Cu" "In4.Cu" "In6.Cu")
		(net 23)
	)
	(via
		(at 142.78 77.75)
		(size 0.45)
		(drill 0.2)
		(layers "F.Cu" "B.Cu")
		(remove_unused_layers yes)
		(keep_end_layers yes)
		(zone_layer_connections "In1.Cu" "In4.Cu" "In6.Cu")
		(net 23)
	)
	(via
		(at 134.328572 99.3)
		(size 0.45)
		(drill 0.2)
		(layers "F.Cu" "B.Cu")
		(remove_unused_layers yes)
		(keep_end_layers yes)
		(zone_layer_connections "In1.Cu" "In4.Cu" "In6.Cu")
		(net 23)
	)
	(via
		(at 179 69.2)
		(size 0.45)
		(drill 0.2)
		(layers "F.Cu" "B.Cu")
		(remove_unused_layers yes)
		(keep_end_layers yes)
		(zone_layer_connections "In1.Cu" "In4.Cu" "In6.Cu")
		(net 23)
	)
	(via
		(at 136.75 80.65)
		(size 0.45)
		(drill 0.2)
		(layers "F.Cu" "B.Cu")
		(remove_unused_layers yes)
		(keep_end_layers yes)
		(zone_layer_connections "In1.Cu" "In4.Cu" "In6.Cu")
		(net 23)
	)
	(via
		(at 125.2 95.1)
		(size 0.45)
		(drill 0.2)
		(layers "F.Cu" "B.Cu")
		(remove_unused_layers yes)
		(keep_end_layers yes)
		(zone_layer_connections "In1.Cu" "In4.Cu" "In6.Cu")
		(net 23)
	)
	(via
		(at 171.6 75.2)
		(size 0.45)
		(drill 0.2)
		(layers "F.Cu" "B.Cu")
		(remove_unused_layers yes)
		(keep_end_layers yes)
		(zone_layer_connections "In1.Cu" "In4.Cu" "In6.Cu")
		(net 23)
	)
	(via
		(at 150.2 112.2)
		(size 0.45)
		(drill 0.2)
		(layers "F.Cu" "B.Cu")
		(remove_unused_layers yes)
		(keep_end_layers yes)
		(zone_layer_connections "In1.Cu" "In4.Cu" "In6.Cu")
		(net 23)
	)
	(via
		(at 151.65 67.3)
		(size 0.45)
		(drill 0.2)
		(layers "F.Cu" "B.Cu")
		(remove_unused_layers yes)
		(keep_end_layers yes)
		(zone_layer_connections "In1.Cu" "In4.Cu" "In6.Cu")
		(net 23)
	)
	(via
		(at 146 105.5)
		(size 0.45)
		(drill 0.2)
		(layers "F.Cu" "B.Cu")
		(remove_unused_layers yes)
		(keep_end_layers yes)
		(zone_layer_connections "In1.Cu" "In4.Cu" "In6.Cu")
		(net 23)
	)
	(via
		(at 162.9 95.4)
		(size 0.45)
		(drill 0.2)
		(layers "F.Cu" "B.Cu")
		(remove_unused_layers yes)
		(keep_end_layers yes)
		(zone_layer_connections "In1.Cu" "In4.Cu" "In6.Cu")
		(net 23)
	)
	(via
		(at 149.7 79.75)
		(size 0.45)
		(drill 0.2)
		(layers "F.Cu" "B.Cu")
		(remove_unused_layers yes)
		(keep_end_layers yes)
		(zone_layer_connections "In1.Cu" "In4.Cu")
		(net 23)
	)
	(via
		(at 155.755 81.25)
		(size 0.45)
		(drill 0.2)
		(layers "F.Cu" "B.Cu")
		(remove_unused_layers yes)
		(keep_end_layers yes)
		(zone_layer_connections "In1.Cu" "In4.Cu" "In6.Cu")
		(net 23)
	)
	(via
		(at 136.75 88.25)
		(size 0.45)
		(drill 0.2)
		(layers "F.Cu" "B.Cu")
		(remove_unused_layers yes)
		(keep_end_layers yes)
		(zone_layer_connections "In1.Cu" "In4.Cu" "In6.Cu")
		(net 23)
	)
	(via
		(at 127.525 124.275)
		(size 0.45)
		(drill 0.2)
		(layers "F.Cu" "B.Cu")
		(remove_unused_layers yes)
		(keep_end_layers yes)
		(zone_layer_connections "In1.Cu" "In4.Cu" "In6.Cu")
		(net 23)
	)
	(via
		(at 135.25 136.25)
		(size 0.45)
		(drill 0.2)
		(layers "F.Cu" "B.Cu")
		(remove_unused_layers yes)
		(keep_end_layers yes)
		(zone_layer_connections "In1.Cu" "In4.Cu" "In6.Cu")
		(net 23)
	)
	(via
		(at 132.075 126.875)
		(size 0.45)
		(drill 0.2)
		(layers "F.Cu" "B.Cu")
		(remove_unused_layers yes)
		(keep_end_layers yes)
		(zone_layer_connections "In1.Cu" "In4.Cu" "In6.Cu")
		(net 23)
	)
	(via
		(at 165.75 136)
		(size 0.45)
		(drill 0.2)
		(layers "F.Cu" "B.Cu")
		(remove_unused_layers yes)
		(keep_end_layers yes)
		(zone_layer_connections "In1.Cu" "In4.Cu" "In6.Cu")
		(net 23)
	)
	(via
		(at 158.35 90.75)
		(size 0.45)
		(drill 0.2)
		(layers "F.Cu" "B.Cu")
		(remove_unused_layers yes)
		(keep_end_layers yes)
		(zone_layer_connections "In1.Cu" "In4.Cu")
		(net 23)
	)
	(via
		(at 158.35 77.75)
		(size 0.45)
		(drill 0.2)
		(layers "F.Cu" "B.Cu")
		(remove_unused_layers yes)
		(keep_end_layers yes)
		(zone_layer_connections "In1.Cu" "In4.Cu" "In6.Cu")
		(net 23)
	)
	(via
		(at 132.075 121.675)
		(size 0.45)
		(drill 0.2)
		(layers "F.Cu" "B.Cu")
		(remove_unused_layers yes)
		(keep_end_layers yes)
		(zone_layer_connections "In1.Cu" "In4.Cu" "In6.Cu")
		(net 23)
	)
	(via
		(at 138.5 119.5)
		(size 0.45)
		(drill 0.2)
		(layers "F.Cu" "B.Cu")
		(remove_unused_layers yes)
		(keep_end_layers yes)
		(zone_layer_connections "In1.Cu" "In4.Cu" "In6.Cu")
		(net 23)
	)
	(via
		(at 141.915 84.25)
		(size 0.45)
		(drill 0.2)
		(layers "F.Cu" "B.Cu")
		(remove_unused_layers yes)
		(keep_end_layers yes)
		(zone_layer_connections "In1.Cu" "In4.Cu" "In6.Cu")
		(net 23)
	)
	(via
		(at 157.485 87.25)
		(size 0.45)
		(drill 0.2)
		(layers "F.Cu" "B.Cu")
		(remove_unused_layers yes)
		(keep_end_layers yes)
		(zone_layer_connections "In1.Cu" "In4.Cu")
		(net 23)
	)
	(via
		(at 162.2 113.700001)
		(size 0.45)
		(drill 0.2)
		(layers "F.Cu" "B.Cu")
		(remove_unused_layers yes)
		(keep_end_layers yes)
		(zone_layer_connections "In1.Cu" "In4.Cu" "In6.Cu")
		(net 23)
	)
	(via
		(at 154.89 87.75)
		(size 0.45)
		(drill 0.2)
		(layers "F.Cu" "B.Cu")
		(remove_unused_layers yes)
		(keep_end_layers yes)
		(zone_layer_connections "In1.Cu" "In4.Cu")
		(net 23)
	)
	(via
		(at 141.915 77.25)
		(size 0.45)
		(drill 0.2)
		(layers "F.Cu" "B.Cu")
		(remove_unused_layers yes)
		(keep_end_layers yes)
		(zone_layer_connections "In1.Cu" "In4.Cu" "In6.Cu")
		(net 23)
	)
	(via
		(at 124.3 149.85)
		(size 0.45)
		(drill 0.2)
		(layers "F.Cu" "B.Cu")
		(remove_unused_layers yes)
		(keep_end_layers yes)
		(zone_layer_connections "In1.Cu" "In4.Cu" "In6.Cu")
		(net 23)
	)
	(via
		(at 156.21 67.605)
		(size 0.45)
		(drill 0.2)
		(layers "F.Cu" "B.Cu")
		(remove_unused_layers yes)
		(keep_end_layers yes)
		(zone_layer_connections "In1.Cu" "In4.Cu" "In6.Cu")
		(net 23)
	)
	(via
		(at 119 116.4)
		(size 0.45)
		(drill 0.2)
		(layers "F.Cu" "B.Cu")
		(remove_unused_layers yes)
		(keep_end_layers yes)
		(zone_layer_connections "In1.Cu" "In4.Cu" "In6.Cu")
		(net 23)
	)
	(via
		(at 153.6 111.7)
		(size 0.45)
		(drill 0.2)
		(layers "F.Cu" "B.Cu")
		(remove_unused_layers yes)
		(keep_end_layers yes)
		(zone_layer_connections "In1.Cu" "In4.Cu" "In6.Cu")
		(net 23)
	)
	(via
		(at 162.9 93.4)
		(size 0.45)
		(drill 0.2)
		(layers "F.Cu" "B.Cu")
		(remove_unused_layers yes)
		(keep_end_layers yes)
		(zone_layer_connections "In1.Cu" "In4.Cu" "In6.Cu")
		(net 23)
	)
	(via
		(at 129.570694 95.823662)
		(size 0.45)
		(drill 0.2)
		(layers "F.Cu" "B.Cu")
		(remove_unused_layers yes)
		(keep_end_layers yes)
		(zone_layer_connections "In1.Cu" "In4.Cu" "In6.Cu")
		(net 23)
	)
	(via
		(at 151.43 75.75)
		(size 0.45)
		(drill 0.2)
		(layers "F.Cu" "B.Cu")
		(remove_unused_layers yes)
		(keep_end_layers yes)
		(zone_layer_connections "In1.Cu" "In4.Cu")
		(net 23)
	)
	(via
		(at 132.75 87.5)
		(size 0.45)
		(drill 0.2)
		(layers "F.Cu" "B.Cu")
		(remove_unused_layers yes)
		(keep_end_layers yes)
		(zone_layer_connections "In1.Cu" "In4.Cu" "In6.Cu")
		(net 23)
	)
	(via
		(at 161.9 98.4)
		(size 0.45)
		(drill 0.2)
		(layers "F.Cu" "B.Cu")
		(remove_unused_layers yes)
		(keep_end_layers yes)
		(zone_layer_connections "In1.Cu" "In4.Cu" "In6.Cu")
		(net 23)
	)
	(via
		(at 139.75 88.5)
		(size 0.45)
		(drill 0.2)
		(layers "F.Cu" "B.Cu")
		(remove_unused_layers yes)
		(keep_end_layers yes)
		(zone_layer_connections "In1.Cu" "In4.Cu" "In6.Cu")
		(net 23)
	)
	(via
		(at 143.645 82.25)
		(size 0.45)
		(drill 0.2)
		(layers "F.Cu" "B.Cu")
		(remove_unused_layers yes)
		(keep_end_layers yes)
		(zone_layer_connections "In1.Cu" "In4.Cu" "In6.Cu")
		(net 23)
	)
	(via
		(at 162.2 111.7)
		(size 0.45)
		(drill 0.2)
		(layers "F.Cu" "B.Cu")
		(remove_unused_layers yes)
		(keep_end_layers yes)
		(zone_layer_connections "In1.Cu" "In4.Cu" "In6.Cu")
		(net 23)
	)
	(via
		(at 168.7 76.5)
		(size 0.45)
		(drill 0.2)
		(layers "F.Cu" "B.Cu")
		(remove_unused_layers yes)
		(keep_end_layers yes)
		(zone_layer_connections "In1.Cu" "In4.Cu" "In6.Cu")
		(net 23)
	)
	(via
		(at 156.62 86.75)
		(size 0.45)
		(drill 0.2)
		(layers "F.Cu" "B.Cu")
		(remove_unused_layers yes)
		(keep_end_layers yes)
		(zone_layer_connections "In1.Cu" "In4.Cu")
		(net 23)
	)
	(via
		(at 153.18 78.75)
		(size 0.45)
		(drill 0.2)
		(layers "F.Cu" "B.Cu")
		(remove_unused_layers yes)
		(keep_end_layers yes)
		(zone_layer_connections "In1.Cu" "In4.Cu")
		(net 23)
	)
	(via
		(at 140.1 118.15)
		(size 0.45)
		(drill 0.2)
		(layers "F.Cu" "B.Cu")
		(remove_unused_layers yes)
		(keep_end_layers yes)
		(zone_layer_connections "In1.Cu" "In4.Cu" "In6.Cu")
		(net 23)
	)
	(via
		(at 124.116 120.73)
		(size 0.45)
		(drill 0.2)
		(layers "F.Cu" "B.Cu")
		(remove_unused_layers yes)
		(keep_end_layers yes)
		(zone_layer_connections "In1.Cu" "In4.Cu" "In6.Cu")
		(net 23)
	)
	(via
		(at 129.42 119.134)
		(size 0.45)
		(drill 0.2)
		(layers "F.Cu" "B.Cu")
		(remove_unused_layers yes)
		(keep_end_layers yes)
		(zone_layer_connections "In1.Cu" "In4.Cu" "In6.Cu")
		(net 23)
	)
	(via
		(at 154.025 77.25)
		(size 0.45)
		(drill 0.2)
		(layers "F.Cu" "B.Cu")
		(remove_unused_layers yes)
		(keep_end_layers yes)
		(zone_layer_connections "In1.Cu" "In4.Cu")
		(net 23)
	)
	(via
		(at 148.835 88.25)
		(size 0.45)
		(drill 0.2)
		(layers "F.Cu" "B.Cu")
		(remove_unused_layers yes)
		(keep_end_layers yes)
		(zone_layer_connections "In1.Cu" "In4.Cu")
		(net 23)
	)
	(via
		(at 150.84 106.2)
		(size 0.45)
		(drill 0.2)
		(layers "F.Cu" "B.Cu")
		(remove_unused_layers yes)
		(keep_end_layers yes)
		(zone_layer_connections "In1.Cu" "In4.Cu" "In6.Cu")
		(net 23)
	)
	(via
		(at 172.6 75.2)
		(size 0.45)
		(drill 0.2)
		(layers "F.Cu" "B.Cu")
		(remove_unused_layers yes)
		(keep_end_layers yes)
		(zone_layer_connections "In1.Cu" "In4.Cu" "In6.Cu")
		(net 23)
	)
	(via
		(at 131.425 121.675)
		(size 0.45)
		(drill 0.2)
		(layers "F.Cu" "B.Cu")
		(remove_unused_layers yes)
		(keep_end_layers yes)
		(zone_layer_connections "In1.Cu" "In4.Cu" "In6.Cu")
		(net 23)
	)
	(via
		(at 165.4 78.4)
		(size 0.45)
		(drill 0.2)
		(layers "F.Cu" "B.Cu")
		(remove_unused_layers yes)
		(keep_end_layers yes)
		(zone_layer_connections "In1.Cu" "In4.Cu" "In6.Cu")
		(net 23)
	)
	(via
		(at 154.89 82.75)
		(size 0.45)
		(drill 0.2)
		(layers "F.Cu" "B.Cu")
		(remove_unused_layers yes)
		(keep_end_layers yes)
		(zone_layer_connections "In1.Cu" "In4.Cu")
		(net 23)
	)
	(via
		(at 126.65 91.55)
		(size 0.45)
		(drill 0.2)
		(layers "F.Cu" "B.Cu")
		(remove_unused_layers yes)
		(keep_end_layers yes)
		(zone_layer_connections "In1.Cu" "In4.Cu" "In6.Cu")
		(net 23)
	)
	(via
		(at 145.375 89.25)
		(size 0.45)
		(drill 0.2)
		(layers "F.Cu" "B.Cu")
		(remove_unused_layers yes)
		(keep_end_layers yes)
		(zone_layer_connections "In1.Cu" "In4.Cu")
		(net 23)
	)
	(via
		(at 116.602512 117.9)
		(size 0.45)
		(drill 0.2)
		(layers "F.Cu" "B.Cu")
		(remove_unused_layers yes)
		(keep_end_layers yes)
		(zone_layer_connections "In1.Cu" "In4.Cu" "In6.Cu")
		(net 23)
	)
	(via
		(at 153.6 145.4)
		(size 0.45)
		(drill 0.2)
		(layers "F.Cu" "B.Cu")
		(remove_unused_layers yes)
		(keep_end_layers yes)
		(zone_layer_connections "In1.Cu" "In4.Cu" "In6.Cu")
		(net 23)
	)
	(via
		(at 134.75 109.15)
		(size 0.45)
		(drill 0.2)
		(layers "F.Cu" "B.Cu")
		(remove_unused_layers yes)
		(keep_end_layers yes)
		(zone_layer_connections "In1.Cu" "In4.Cu" "In6.Cu")
		(net 23)
	)
	(via
		(at 132.05 134.35)
		(size 0.45)
		(drill 0.2)
		(layers "F.Cu" "B.Cu")
		(remove_unused_layers yes)
		(keep_end_layers yes)
		(zone_layer_connections "In1.Cu" "In4.Cu" "In6.Cu")
		(net 23)
	)
	(via
		(at 159.215 80.25)
		(size 0.45)
		(drill 0.2)
		(layers "F.Cu" "B.Cu")
		(remove_unused_layers yes)
		(keep_end_layers yes)
		(zone_layer_connections "In1.Cu" "In4.Cu" "In6.Cu")
		(net 23)
	)
	(via
		(at 135.75 74.65)
		(size 0.45)
		(drill 0.2)
		(layers "F.Cu" "B.Cu")
		(remove_unused_layers yes)
		(keep_end_layers yes)
		(zone_layer_connections "In1.Cu" "In4.Cu" "In6.Cu")
		(net 23)
	)
	(via
		(at 136.11 106.2)
		(size 0.45)
		(drill 0.2)
		(layers "F.Cu" "B.Cu")
		(remove_unused_layers yes)
		(keep_end_layers yes)
		(zone_layer_connections "In1.Cu" "In4.Cu" "In6.Cu")
		(net 23)
	)
	(via
		(at 141.399999 99.1)
		(size 0.45)
		(drill 0.2)
		(layers "F.Cu" "B.Cu")
		(remove_unused_layers yes)
		(keep_end_layers yes)
		(zone_layer_connections "In1.Cu" "In4.Cu" "In6.Cu")
		(net 23)
	)
	(via
		(at 143.595 77.25)
		(size 0.45)
		(drill 0.2)
		(layers "F.Cu" "B.Cu")
		(remove_unused_layers yes)
		(keep_end_layers yes)
		(zone_layer_connections "In1.Cu" "In4.Cu" "In6.Cu")
		(net 23)
	)
	(via
		(at 151 53.5)
		(size 0.45)
		(drill 0.2)
		(layers "F.Cu" "B.Cu")
		(remove_unused_layers yes)
		(keep_end_layers yes)
		(zone_layer_connections "In1.Cu" "In4.Cu" "In6.Cu")
		(net 23)
	)
	(via
		(at 137.864 133.52)
		(size 0.45)
		(drill 0.2)
		(layers "F.Cu" "B.Cu")
		(remove_unused_layers yes)
		(keep_end_layers yes)
		(zone_layer_connections "In1.Cu" "In4.Cu" "In6.Cu")
		(net 23)
	)
	(via
		(at 161.9 97.4)
		(size 0.45)
		(drill 0.2)
		(layers "F.Cu" "B.Cu")
		(remove_unused_layers yes)
		(keep_end_layers yes)
		(zone_layer_connections "In1.Cu" "In4.Cu" "In6.Cu")
		(net 23)
	)
	(via
		(at 160.945 80.25)
		(size 0.45)
		(drill 0.2)
		(layers "F.Cu" "B.Cu")
		(remove_unused_layers yes)
		(keep_end_layers yes)
		(zone_layer_connections "In1.Cu" "In4.Cu" "In6.Cu")
		(net 23)
	)
	(via
		(at 160.08 81.75)
		(size 0.45)
		(drill 0.2)
		(layers "F.Cu" "B.Cu")
		(remove_unused_layers yes)
		(keep_end_layers yes)
		(zone_layer_connections "In1.Cu" "In4.Cu" "In6.Cu")
		(net 23)
	)
	(via
		(at 143.645 72.25)
		(size 0.45)
		(drill 0.2)
		(layers "F.Cu" "B.Cu")
		(remove_unused_layers yes)
		(keep_end_layers yes)
		(zone_layer_connections "In1.Cu" "In4.Cu" "In6.Cu")
		(net 23)
	)
	(via
		(at 120.37 108.3)
		(size 0.45)
		(drill 0.2)
		(layers "F.Cu" "B.Cu")
		(remove_unused_layers yes)
		(keep_end_layers yes)
		(zone_layer_connections "In1.Cu" "In4.Cu" "In6.Cu")
		(net 23)
	)
	(via
		(at 132.7 93.8)
		(size 0.45)
		(drill 0.2)
		(layers "F.Cu" "B.Cu")
		(remove_unused_layers yes)
		(keep_end_layers yes)
		(zone_layer_connections "In1.Cu" "In4.Cu" "In6.Cu")
		(net 23)
	)
	(via
		(at 161.11 66.645001)
		(size 0.45)
		(drill 0.2)
		(layers "F.Cu" "B.Cu")
		(remove_unused_layers yes)
		(keep_end_layers yes)
		(zone_layer_connections "In1.Cu" "In4.Cu" "In6.Cu")
		(net 23)
	)
	(via
		(at 132.075 124.925)
		(size 0.45)
		(drill 0.2)
		(layers "F.Cu" "B.Cu")
		(remove_unused_layers yes)
		(keep_end_layers yes)
		(zone_layer_connections "In1.Cu" "In4.Cu" "In6.Cu")
		(net 23)
	)
	(via
		(at 135.75 75.85)
		(size 0.45)
		(drill 0.2)
		(layers "F.Cu" "B.Cu")
		(remove_unused_layers yes)
		(keep_end_layers yes)
		(zone_layer_connections "In1.Cu" "In4.Cu" "In6.Cu")
		(net 23)
	)
	(via
		(at 134.2 67.4)
		(size 0.45)
		(drill 0.2)
		(layers "F.Cu" "B.Cu")
		(remove_unused_layers yes)
		(keep_end_layers yes)
		(zone_layer_connections "In1.Cu" "In4.Cu" "In6.Cu")
		(net 23)
	)
	(via
		(at 135.75 81.85)
		(size 0.45)
		(drill 0.2)
		(layers "F.Cu" "B.Cu")
		(remove_unused_layers yes)
		(keep_end_layers yes)
		(zone_layer_connections "In1.Cu" "In4.Cu" "In6.Cu")
		(net 23)
	)
	(via
		(at 135.25 136.75)
		(size 0.45)
		(drill 0.2)
		(layers "F.Cu" "B.Cu")
		(remove_unused_layers yes)
		(keep_end_layers yes)
		(zone_layer_connections "In1.Cu" "In4.Cu" "In6.Cu")
		(net 23)
	)
	(via
		(at 119 119.4)
		(size 0.45)
		(drill 0.2)
		(layers "F.Cu" "B.Cu")
		(remove_unused_layers yes)
		(keep_end_layers yes)
		(zone_layer_connections "In1.Cu" "In4.Cu" "In6.Cu")
		(net 23)
	)
	(via
		(at 142.78 74.75)
		(size 0.45)
		(drill 0.2)
		(layers "F.Cu" "B.Cu")
		(remove_unused_layers yes)
		(keep_end_layers yes)
		(zone_layer_connections "In1.Cu" "In4.Cu" "In6.Cu")
		(net 23)
	)
	(via
		(at 159.9 102.85)
		(size 0.45)
		(drill 0.2)
		(layers "F.Cu" "B.Cu")
		(remove_unused_layers yes)
		(keep_end_layers yes)
		(zone_layer_connections "In1.Cu" "In4.Cu" "In6.Cu")
		(net 23)
	)
	(via
		(at 152.325 66.625)
		(size 0.45)
		(drill 0.2)
		(layers "F.Cu" "B.Cu")
		(remove_unused_layers yes)
		(keep_end_layers yes)
		(zone_layer_connections "In1.Cu" "In4.Cu" "In6.Cu")
		(net 23)
	)
	(via
		(at 157.485 81.25)
		(size 0.45)
		(drill 0.2)
		(layers "F.Cu" "B.Cu")
		(remove_unused_layers yes)
		(keep_end_layers yes)
		(zone_layer_connections "In1.Cu" "In4.Cu" "In6.Cu")
		(net 23)
	)
	(via
		(at 160.7 49.35)
		(size 0.45)
		(drill 0.2)
		(layers "F.Cu" "B.Cu")
		(remove_unused_layers yes)
		(keep_end_layers yes)
		(zone_layer_connections "In1.Cu" "In4.Cu" "In6.Cu")
		(net 23)
	)
	(via
		(at 141.915 83.25)
		(size 0.45)
		(drill 0.2)
		(layers "F.Cu" "B.Cu")
		(remove_unused_layers yes)
		(keep_end_layers yes)
		(zone_layer_connections "In1.Cu" "In4.Cu" "In6.Cu")
		(net 23)
	)
	(via
		(at 149.7 76.075)
		(size 0.45)
		(drill 0.2)
		(layers "F.Cu" "B.Cu")
		(remove_unused_layers yes)
		(keep_end_layers yes)
		(zone_layer_connections "In1.Cu" "In4.Cu")
		(net 23)
	)
	(via
		(at 160.08 80.75)
		(size 0.45)
		(drill 0.2)
		(layers "F.Cu" "B.Cu")
		(remove_unused_layers yes)
		(keep_end_layers yes)
		(zone_layer_connections "In1.Cu" "In4.Cu" "In6.Cu")
		(net 23)
	)
	(via
		(at 123 132.75)
		(size 0.45)
		(drill 0.2)
		(layers "F.Cu" "B.Cu")
		(remove_unused_layers yes)
		(keep_end_layers yes)
		(zone_layer_connections "In1.Cu" "In4.Cu" "In6.Cu")
		(net 23)
	)
	(via
		(at 161.9 95.4)
		(size 0.45)
		(drill 0.2)
		(layers "F.Cu" "B.Cu")
		(remove_unused_layers yes)
		(keep_end_layers yes)
		(zone_layer_connections "In1.Cu" "In4.Cu" "In6.Cu")
		(net 23)
	)
	(via
		(at 134 124.85)
		(size 0.45)
		(drill 0.2)
		(layers "F.Cu" "B.Cu")
		(remove_unused_layers yes)
		(keep_end_layers yes)
		(zone_layer_connections "In1.Cu" "In4.Cu" "In6.Cu")
		(net 23)
	)
	(via
		(at 132.075 124.275)
		(size 0.45)
		(drill 0.2)
		(layers "F.Cu" "B.Cu")
		(remove_unused_layers yes)
		(keep_end_layers yes)
		(zone_layer_connections "In1.Cu" "In4.Cu" "In6.Cu")
		(net 23)
	)
	(via
		(at 167.2 75.4)
		(size 0.45)
		(drill 0.2)
		(layers "F.Cu" "B.Cu")
		(remove_unused_layers yes)
		(keep_end_layers yes)
		(zone_layer_connections "In1.Cu" "In4.Cu" "In6.Cu")
		(net 23)
	)
	(via
		(at 132.075 123.625)
		(size 0.45)
		(drill 0.2)
		(layers "F.Cu" "B.Cu")
		(remove_unused_layers yes)
		(keep_end_layers yes)
		(zone_layer_connections "In1.Cu" "In4.Cu" "In6.Cu")
		(net 23)
	)
	(via
		(at 119.5 148.3)
		(size 0.45)
		(drill 0.2)
		(layers "F.Cu" "B.Cu")
		(remove_unused_layers yes)
		(keep_end_layers yes)
		(zone_layer_connections "In1.Cu" "In4.Cu" "In6.Cu")
		(net 23)
	)
	(via
		(at 116.6 126.9)
		(size 0.45)
		(drill 0.2)
		(layers "F.Cu" "B.Cu")
		(remove_unused_layers yes)
		(keep_end_layers yes)
		(zone_layer_connections "In1.Cu" "In4.Cu" "In6.Cu")
		(net 23)
	)
	(via
		(at 150.3 67.3)
		(size 0.45)
		(drill 0.2)
		(layers "F.Cu" "B.Cu")
		(remove_unused_layers yes)
		(keep_end_layers yes)
		(zone_layer_connections "In1.Cu" "In4.Cu" "In6.Cu")
		(net 23)
	)
	(via
		(at 131.25 132.4)
		(size 0.45)
		(drill 0.2)
		(layers "F.Cu" "B.Cu")
		(remove_unused_layers yes)
		(keep_end_layers yes)
		(zone_layer_connections "In1.Cu" "In4.Cu" "In6.Cu")
		(net 23)
	)
	(via
		(at 144.3 60.3)
		(size 0.45)
		(drill 0.2)
		(layers "F.Cu" "B.Cu")
		(remove_unused_layers yes)
		(keep_end_layers yes)
		(zone_layer_connections "In1.Cu" "In4.Cu" "In6.Cu")
		(net 23)
	)
	(via
		(at 153.16 75.75)
		(size 0.45)
		(drill 0.2)
		(layers "F.Cu" "B.Cu")
		(remove_unused_layers yes)
		(keep_end_layers yes)
		(zone_layer_connections "In1.Cu" "In4.Cu")
		(net 23)
	)
	(via
		(at 136.75 81.85)
		(size 0.45)
		(drill 0.2)
		(layers "F.Cu" "B.Cu")
		(remove_unused_layers yes)
		(keep_end_layers yes)
		(zone_layer_connections "In1.Cu" "In4.Cu" "In6.Cu")
		(net 23)
	)
	(via
		(at 115.8 73.9)
		(size 0.45)
		(drill 0.2)
		(layers "F.Cu" "B.Cu")
		(remove_unused_layers yes)
		(keep_end_layers yes)
		(zone_layer_connections "In1.Cu" "In4.Cu" "In6.Cu")
		(net 23)
	)
	(via
		(at 151.61 106.91)
		(size 0.45)
		(drill 0.2)
		(layers "F.Cu" "B.Cu")
		(remove_unused_layers yes)
		(keep_end_layers yes)
		(zone_layer_connections "In1.Cu" "In4.Cu" "In6.Cu")
		(net 23)
	)
	(via
		(at 136.75 77.65)
		(size 0.45)
		(drill 0.2)
		(layers "F.Cu" "B.Cu")
		(remove_unused_layers yes)
		(keep_end_layers yes)
		(zone_layer_connections "In1.Cu" "In4.Cu" "In6.Cu")
		(net 23)
	)
	(via
		(at 159.21 106.91)
		(size 0.45)
		(drill 0.2)
		(layers "F.Cu" "B.Cu")
		(remove_unused_layers yes)
		(keep_end_layers yes)
		(zone_layer_connections "In1.Cu" "In4.Cu" "In6.Cu")
		(net 23)
	)
	(via
		(at 144.51 71.75)
		(size 0.45)
		(drill 0.2)
		(layers "F.Cu" "B.Cu")
		(remove_unused_layers yes)
		(keep_end_layers yes)
		(zone_layer_connections "In1.Cu" "In4.Cu" "In6.Cu")
		(net 23)
	)
	(via
		(at 159.215 79.25)
		(size 0.45)
		(drill 0.2)
		(layers "F.Cu" "B.Cu")
		(remove_unused_layers yes)
		(keep_end_layers yes)
		(zone_layer_connections "In1.Cu" "In4.Cu" "In6.Cu")
		(net 23)
	)
	(via
		(at 151.43 80.75)
		(size 0.45)
		(drill 0.2)
		(layers "F.Cu" "B.Cu")
		(remove_unused_layers yes)
		(keep_end_layers yes)
		(zone_layer_connections "In1.Cu" "In4.Cu")
		(net 23)
	)
	(via
		(at 158.35 73.75)
		(size 0.45)
		(drill 0.2)
		(layers "F.Cu" "B.Cu")
		(remove_unused_layers yes)
		(keep_end_layers yes)
		(zone_layer_connections "In1.Cu" "In4.Cu" "In6.Cu")
		(net 23)
	)
	(via
		(at 130.85 137.45)
		(size 0.45)
		(drill 0.2)
		(layers "F.Cu" "B.Cu")
		(remove_unused_layers yes)
		(keep_end_layers yes)
		(zone_layer_connections "In1.Cu" "In4.Cu" "In6.Cu")
		(net 23)
	)
	(via
		(at 143.75 136)
		(size 0.45)
		(drill 0.2)
		(layers "F.Cu" "B.Cu")
		(remove_unused_layers yes)
		(keep_end_layers yes)
		(zone_layer_connections "In1.Cu" "In4.Cu" "In6.Cu")
		(net 23)
	)
	(via
		(at 152.295 89.25)
		(size 0.45)
		(drill 0.2)
		(layers "F.Cu" "B.Cu")
		(remove_unused_layers yes)
		(keep_end_layers yes)
		(zone_layer_connections "In1.Cu" "In4.Cu")
		(net 23)
	)
	(via
		(at 162.9 96.4)
		(size 0.45)
		(drill 0.2)
		(layers "F.Cu" "B.Cu")
		(remove_unused_layers yes)
		(keep_end_layers yes)
		(zone_layer_connections "In1.Cu" "In4.Cu" "In6.Cu")
		(net 23)
	)
	(via
		(at 120 123.6)
		(size 0.45)
		(drill 0.2)
		(layers "F.Cu" "B.Cu")
		(remove_unused_layers yes)
		(keep_end_layers yes)
		(zone_layer_connections "In1.Cu" "In4.Cu" "In6.Cu")
		(net 23)
	)
	(via
		(at 147.105 71.25)
		(size 0.45)
		(drill 0.2)
		(layers "F.Cu" "B.Cu")
		(remove_unused_layers yes)
		(keep_end_layers yes)
		(zone_layer_connections "In1.Cu" "In4.Cu" "In6.Cu")
		(net 23)
	)
	(via
		(at 156.62 80.75)
		(size 0.45)
		(drill 0.2)
		(layers "F.Cu" "B.Cu")
		(remove_unused_layers yes)
		(keep_end_layers yes)
		(zone_layer_connections "In1.Cu" "In4.Cu" "In6.Cu")
		(net 23)
	)
	(via
		(at 177 77.6)
		(size 0.45)
		(drill 0.2)
		(layers "F.Cu" "B.Cu")
		(remove_unused_layers yes)
		(keep_end_layers yes)
		(zone_layer_connections "In1.Cu" "In4.Cu" "In6.Cu")
		(net 23)
	)
	(via
		(at 132.898281 92.096601)
		(size 0.45)
		(drill 0.2)
		(layers "F.Cu" "B.Cu")
		(remove_unused_layers yes)
		(keep_end_layers yes)
		(zone_layer_connections "In1.Cu" "In4.Cu" "In6.Cu")
		(net 23)
	)
	(via
		(at 115.9 103.1)
		(size 0.45)
		(drill 0.2)
		(layers "F.Cu" "B.Cu")
		(remove_unused_layers yes)
		(keep_end_layers yes)
		(zone_layer_connections "In1.Cu" "In4.Cu" "In6.Cu")
		(net 23)
	)
	(via
		(at 154.6 51.3)
		(size 0.45)
		(drill 0.2)
		(layers "F.Cu" "B.Cu")
		(remove_unused_layers yes)
		(keep_end_layers yes)
		(free yes)
		(zone_layer_connections "In1.Cu" "In4.Cu" "In6.Cu")
		(net 23)
	)
	(via
		(at 158.05 112.15)
		(size 0.45)
		(drill 0.2)
		(layers "F.Cu" "B.Cu")
		(remove_unused_layers yes)
		(keep_end_layers yes)
		(zone_layer_connections "In1.Cu" "In4.Cu" "In6.Cu")
		(net 23)
	)
	(via
		(at 156.62 88.75)
		(size 0.45)
		(drill 0.2)
		(layers "F.Cu" "B.Cu")
		(remove_unused_layers yes)
		(keep_end_layers yes)
		(zone_layer_connections "In1.Cu" "In4.Cu")
		(net 23)
	)
	(via
		(at 120.37 110.1)
		(size 0.45)
		(drill 0.2)
		(layers "F.Cu" "B.Cu")
		(remove_unused_layers yes)
		(keep_end_layers yes)
		(zone_layer_connections "In1.Cu" "In4.Cu" "In6.Cu")
		(net 23)
	)
	(via
		(at 119 123.6)
		(size 0.45)
		(drill 0.2)
		(layers "F.Cu" "B.Cu")
		(remove_unused_layers yes)
		(keep_end_layers yes)
		(zone_layer_connections "In1.Cu" "In4.Cu" "In6.Cu")
		(net 23)
	)
	(via
		(at 146.25 78.75)
		(size 0.45)
		(drill 0.2)
		(layers "F.Cu" "B.Cu")
		(remove_unused_layers yes)
		(keep_end_layers yes)
		(zone_layer_connections "In1.Cu" "In4.Cu")
		(net 23)
	)
	(via
		(at 161.3 111.7)
		(size 0.45)
		(drill 0.2)
		(layers "F.Cu" "B.Cu")
		(remove_unused_layers yes)
		(keep_end_layers yes)
		(zone_layer_connections "In1.Cu" "In4.Cu" "In6.Cu")
		(net 23)
	)
	(via
		(at 138.75 111.85)
		(size 0.45)
		(drill 0.2)
		(layers "F.Cu" "B.Cu")
		(remove_unused_layers yes)
		(keep_end_layers yes)
		(zone_layer_connections "In1.Cu" "In4.Cu" "In6.Cu")
		(net 23)
	)
	(via
		(at 162.9 98.4)
		(size 0.45)
		(drill 0.2)
		(layers "F.Cu" "B.Cu")
		(remove_unused_layers yes)
		(keep_end_layers yes)
		(zone_layer_connections "In1.Cu" "In4.Cu" "In6.Cu")
		(net 23)
	)
	(via
		(at 130.970694 94.923662)
		(size 0.45)
		(drill 0.2)
		(layers "F.Cu" "B.Cu")
		(remove_unused_layers yes)
		(keep_end_layers yes)
		(zone_layer_connections "In1.Cu" "In4.Cu" "In6.Cu")
		(net 23)
	)
	(via
		(at 165.85 96.4)
		(size 0.45)
		(drill 0.2)
		(layers "F.Cu" "B.Cu")
		(remove_unused_layers yes)
		(keep_end_layers yes)
		(zone_layer_connections "In1.Cu" "In4.Cu" "In6.Cu")
		(net 23)
	)
	(via
		(at 122.25 76.75)
		(size 0.45)
		(drill 0.2)
		(layers "F.Cu" "B.Cu")
		(remove_unused_layers yes)
		(keep_end_layers yes)
		(zone_layer_connections "In1.Cu" "In4.Cu" "In6.Cu")
		(net 23)
	)
	(via
		(at 182.5 136)
		(size 0.45)
		(drill 0.2)
		(layers "F.Cu" "B.Cu")
		(remove_unused_layers yes)
		(keep_end_layers yes)
		(zone_layer_connections "In1.Cu" "In4.Cu" "In6.Cu")
		(net 23)
	)
	(via
		(at 154.31 65.655)
		(size 0.45)
		(drill 0.2)
		(layers "F.Cu" "B.Cu")
		(remove_unused_layers yes)
		(keep_end_layers yes)
		(zone_layer_connections "In1.Cu" "In4.Cu" "In6.Cu")
		(net 23)
	)
	(via
		(at 154.89 83.75)
		(size 0.45)
		(drill 0.2)
		(layers "F.Cu" "B.Cu")
		(remove_unused_layers yes)
		(keep_end_layers yes)
		(zone_layer_connections "In1.Cu" "In4.Cu")
		(net 23)
	)
	(via
		(at 142.78 89.75)
		(size 0.45)
		(drill 0.2)
		(layers "F.Cu" "B.Cu")
		(remove_unused_layers yes)
		(keep_end_layers yes)
		(zone_layer_connections "In1.Cu" "In4.Cu")
		(net 23)
	)
	(via
		(at 119 122.4)
		(size 0.45)
		(drill 0.2)
		(layers "F.Cu" "B.Cu")
		(remove_unused_layers yes)
		(keep_end_layers yes)
		(zone_layer_connections "In1.Cu" "In4.Cu" "In6.Cu")
		(net 23)
	)
	(via
		(at 146.8 113.700001)
		(size 0.45)
		(drill 0.2)
		(layers "F.Cu" "B.Cu")
		(remove_unused_layers yes)
		(keep_end_layers yes)
		(zone_layer_connections "In1.Cu" "In4.Cu" "In6.Cu")
		(net 23)
	)
	(via
		(at 133.88 135.504)
		(size 0.45)
		(drill 0.2)
		(layers "F.Cu" "B.Cu")
		(remove_unused_layers yes)
		(keep_end_layers yes)
		(zone_layer_connections "In1.Cu" "In4.Cu" "In6.Cu")
		(net 23)
	)
	(via
		(at 115.8 119.4)
		(size 0.45)
		(drill 0.2)
		(layers "F.Cu" "B.Cu")
		(remove_unused_layers yes)
		(keep_end_layers yes)
		(zone_layer_connections "In1.Cu" "In4.Cu" "In6.Cu")
		(net 23)
	)
	(via
		(at 116.6 125.1)
		(size 0.45)
		(drill 0.2)
		(layers "F.Cu" "B.Cu")
		(remove_unused_layers yes)
		(keep_end_layers yes)
		(zone_layer_connections "In1.Cu" "In4.Cu" "In6.Cu")
		(net 23)
	)
	(via
		(at 152.975 67.3)
		(size 0.45)
		(drill 0.2)
		(layers "F.Cu" "B.Cu")
		(remove_unused_layers yes)
		(keep_end_layers yes)
		(zone_layer_connections "In1.Cu" "In4.Cu" "In6.Cu")
		(net 23)
	)
	(via
		(at 132.15 132.6)
		(size 0.45)
		(drill 0.2)
		(layers "F.Cu" "B.Cu")
		(remove_unused_layers yes)
		(keep_end_layers yes)
		(zone_layer_connections "In1.Cu" "In4.Cu" "In6.Cu")
		(net 23)
	)
	(via
		(at 145 115.9)
		(size 0.45)
		(drill 0.2)
		(layers "F.Cu" "B.Cu")
		(remove_unused_layers yes)
		(keep_end_layers yes)
		(zone_layer_connections "In1.Cu" "In4.Cu" "In6.Cu")
		(net 23)
	)
	(via
		(at 135.25 137.25)
		(size 0.45)
		(drill 0.2)
		(layers "F.Cu" "B.Cu")
		(remove_unused_layers yes)
		(keep_end_layers yes)
		(zone_layer_connections "In1.Cu" "In4.Cu" "In6.Cu")
		(net 23)
	)
	(via
		(at 150.975 67.975)
		(size 0.45)
		(drill 0.2)
		(layers "F.Cu" "B.Cu")
		(remove_unused_layers yes)
		(keep_end_layers yes)
		(zone_layer_connections "In1.Cu" "In4.Cu" "In6.Cu")
		(net 23)
	)
	(via
		(at 152.2 106.91)
		(size 0.45)
		(drill 0.2)
		(layers "F.Cu" "B.Cu")
		(remove_unused_layers yes)
		(keep_end_layers yes)
		(zone_layer_connections "In1.Cu" "In4.Cu" "In6.Cu")
		(net 23)
	)
	(via
		(at 179 74.2)
		(size 0.45)
		(drill 0.2)
		(layers "F.Cu" "B.Cu")
		(remove_unused_layers yes)
		(keep_end_layers yes)
		(zone_layer_connections "In1.Cu" "In4.Cu" "In6.Cu")
		(net 23)
	)
	(via
		(at 116.5 146.4)
		(size 0.45)
		(drill 0.2)
		(layers "F.Cu" "B.Cu")
		(remove_unused_layers yes)
		(keep_end_layers yes)
		(zone_layer_connections "In1.Cu" "In4.Cu" "In6.Cu")
		(net 23)
	)
	(via
		(at 148.95 67.3)
		(size 0.45)
		(drill 0.2)
		(layers "F.Cu" "B.Cu")
		(remove_unused_layers yes)
		(keep_end_layers yes)
		(zone_layer_connections "In1.Cu" "In4.Cu" "In6.Cu")
		(net 23)
	)
	(via
		(at 142.78 88.75)
		(size 0.45)
		(drill 0.2)
		(layers "F.Cu" "B.Cu")
		(remove_unused_layers yes)
		(keep_end_layers yes)
		(zone_layer_connections "In1.Cu" "In4.Cu")
		(net 23)
	)
	(via
		(at 149.7 78.75)
		(size 0.45)
		(drill 0.2)
		(layers "F.Cu" "B.Cu")
		(remove_unused_layers yes)
		(keep_end_layers yes)
		(zone_layer_connections "In1.Cu" "In4.Cu")
		(net 23)
	)
	(via
		(at 142.78 87.75)
		(size 0.45)
		(drill 0.2)
		(layers "F.Cu" "B.Cu")
		(remove_unused_layers yes)
		(keep_end_layers yes)
		(zone_layer_connections "In1.Cu" "In4.Cu")
		(net 23)
	)
	(via
		(at 129.5 142.9)
		(size 0.45)
		(drill 0.2)
		(layers "F.Cu" "B.Cu")
		(remove_unused_layers yes)
		(keep_end_layers yes)
		(zone_layer_connections "In1.Cu" "In4.Cu" "In6.Cu")
		(net 23)
	)
	(via
		(at 156.63 90.75)
		(size 0.45)
		(drill 0.2)
		(layers "F.Cu" "B.Cu")
		(remove_unused_layers yes)
		(keep_end_layers yes)
		(zone_layer_connections "In1.Cu" "In4.Cu")
		(net 23)
	)
	(via
		(at 141.05 79.75)
		(size 0.45)
		(drill 0.2)
		(layers "F.Cu" "B.Cu")
		(remove_unused_layers yes)
		(keep_end_layers yes)
		(zone_layer_connections "In1.Cu" "In4.Cu" "In6.Cu")
		(net 23)
	)
	(via
		(at 127.4 132.5)
		(size 0.45)
		(drill 0.2)
		(layers "F.Cu" "B.Cu")
		(remove_unused_layers yes)
		(keep_end_layers yes)
		(zone_layer_connections "In1.Cu" "In4.Cu" "In6.Cu")
		(net 23)
	)
	(via
		(at 125.25 146.75)
		(size 0.45)
		(drill 0.2)
		(layers "F.Cu" "B.Cu")
		(remove_unused_layers yes)
		(keep_end_layers yes)
		(zone_layer_connections "In1.Cu" "In4.Cu" "In6.Cu")
		(net 23)
	)
	(via
		(at 162.2 112.699999)
		(size 0.45)
		(drill 0.2)
		(layers "F.Cu" "B.Cu")
		(remove_unused_layers yes)
		(keep_end_layers yes)
		(zone_layer_connections "In1.Cu" "In4.Cu" "In6.Cu")
		(net 23)
	)
	(via
		(at 149.95 96.87)
		(size 0.45)
		(drill 0.2)
		(layers "F.Cu" "B.Cu")
		(remove_unused_layers yes)
		(keep_end_layers yes)
		(zone_layer_connections "In1.Cu" "In4.Cu" "In6.Cu")
		(net 23)
	)
	(via
		(at 154.31 68.595)
		(size 0.45)
		(drill 0.2)
		(layers "F.Cu" "B.Cu")
		(remove_unused_layers yes)
		(keep_end_layers yes)
		(zone_layer_connections "In1.Cu" "In4.Cu" "In6.Cu")
		(net 23)
	)
	(via
		(at 129.9 131.6)
		(size 0.45)
		(drill 0.2)
		(layers "F.Cu" "B.Cu")
		(remove_unused_layers yes)
		(keep_end_layers yes)
		(zone_layer_connections "In1.Cu" "In4.Cu" "In6.Cu")
		(net 23)
	)
	(via
		(at 131.25 133.6)
		(size 0.45)
		(drill 0.2)
		(layers "F.Cu" "B.Cu")
		(remove_unused_layers yes)
		(keep_end_layers yes)
		(zone_layer_connections "In1.Cu" "In4.Cu" "In6.Cu")
		(net 23)
	)
	(via
		(at 152.295 86.25)
		(size 0.45)
		(drill 0.2)
		(layers "F.Cu" "B.Cu")
		(remove_unused_layers yes)
		(keep_end_layers yes)
		(zone_layer_connections "In1.Cu" "In4.Cu")
		(net 23)
	)
	(via
		(at 120.37 107.7)
		(size 0.45)
		(drill 0.2)
		(layers "F.Cu" "B.Cu")
		(remove_unused_layers yes)
		(keep_end_layers yes)
		(zone_layer_connections "In1.Cu" "In4.Cu" "In6.Cu")
		(net 23)
	)
	(via
		(at 141.05 85.75)
		(size 0.45)
		(drill 0.2)
		(layers "F.Cu" "B.Cu")
		(remove_unused_layers yes)
		(keep_end_layers yes)
		(zone_layer_connections "In1.Cu" "In4.Cu")
		(net 23)
	)
	(via
		(at 132.5 117.5)
		(size 0.45)
		(drill 0.2)
		(layers "F.Cu" "B.Cu")
		(remove_unused_layers yes)
		(keep_end_layers yes)
		(zone_layer_connections "In1.Cu" "In4.Cu" "In6.Cu")
		(net 23)
	)
	(via
		(at 140 119.5)
		(size 0.45)
		(drill 0.2)
		(layers "F.Cu" "B.Cu")
		(remove_unused_layers yes)
		(keep_end_layers yes)
		(zone_layer_connections "In1.Cu" "In4.Cu" "In6.Cu")
		(net 23)
	)
	(via
		(at 138.85 139.55)
		(size 0.45)
		(drill 0.2)
		(layers "F.Cu" "B.Cu")
		(remove_unused_layers yes)
		(keep_end_layers yes)
		(zone_layer_connections "In1.Cu" "In4.Cu" "In6.Cu")
		(net 23)
	)
	(via
		(at 143.645 80.25)
		(size 0.45)
		(drill 0.2)
		(layers "F.Cu" "B.Cu")
		(remove_unused_layers yes)
		(keep_end_layers yes)
		(zone_layer_connections "In1.Cu" "In4.Cu" "In6.Cu")
		(net 23)
	)
	(via
		(at 160.08 74.75)
		(size 0.45)
		(drill 0.2)
		(layers "F.Cu" "B.Cu")
		(remove_unused_layers yes)
		(keep_end_layers yes)
		(zone_layer_connections "In1.Cu" "In4.Cu" "In6.Cu")
		(net 23)
	)
	(via
		(at 131.425 127.525)
		(size 0.45)
		(drill 0.2)
		(layers "F.Cu" "B.Cu")
		(remove_unused_layers yes)
		(keep_end_layers yes)
		(zone_layer_connections "In1.Cu" "In4.Cu" "In6.Cu")
		(net 23)
	)
	(via
		(at 116.6 123.9)
		(size 0.45)
		(drill 0.2)
		(layers "F.Cu" "B.Cu")
		(remove_unused_layers yes)
		(keep_end_layers yes)
		(zone_layer_connections "In1.Cu" "In4.Cu" "In6.Cu")
		(net 23)
	)
	(via
		(at 129.25 117.3)
		(size 0.45)
		(drill 0.2)
		(layers "F.Cu" "B.Cu")
		(remove_unused_layers yes)
		(keep_end_layers yes)
		(zone_layer_connections "In1.Cu" "In4.Cu" "In6.Cu")
		(net 23)
	)
	(via
		(at 138.3 111.5)
		(size 0.45)
		(drill 0.2)
		(layers "F.Cu" "B.Cu")
		(remove_unused_layers yes)
		(keep_end_layers yes)
		(zone_layer_connections "In1.Cu" "In4.Cu" "In6.Cu")
		(net 23)
	)
	(via
		(at 133.95 113.5)
		(size 0.45)
		(drill 0.2)
		(layers "F.Cu" "B.Cu")
		(remove_unused_layers yes)
		(keep_end_layers yes)
		(zone_layer_connections "In1.Cu" "In4.Cu" "In6.Cu")
		(net 23)
	)
	(via
		(at 145.3 61.3)
		(size 0.45)
		(drill 0.2)
		(layers "F.Cu" "B.Cu")
		(remove_unused_layers yes)
		(keep_end_layers yes)
		(zone_layer_connections "In1.Cu" "In4.Cu" "In6.Cu")
		(net 23)
	)
	(via
		(at 159.215 73.25)
		(size 0.45)
		(drill 0.2)
		(layers "F.Cu" "B.Cu")
		(remove_unused_layers yes)
		(keep_end_layers yes)
		(zone_layer_connections "In1.Cu" "In4.Cu" "In6.Cu")
		(net 23)
	)
	(via
		(at 154.025 81.25)
		(size 0.45)
		(drill 0.2)
		(layers "F.Cu" "B.Cu")
		(remove_unused_layers yes)
		(keep_end_layers yes)
		(zone_layer_connections "In1.Cu" "In4.Cu")
		(net 23)
	)
	(via
		(at 142.78 72.75)
		(size 0.45)
		(drill 0.2)
		(layers "F.Cu" "B.Cu")
		(remove_unused_layers yes)
		(keep_end_layers yes)
		(zone_layer_connections "In1.Cu" "In4.Cu" "In6.Cu")
		(net 23)
	)
	(via
		(at 126.5 103.3)
		(size 0.45)
		(drill 0.2)
		(layers "F.Cu" "B.Cu")
		(remove_unused_layers yes)
		(keep_end_layers yes)
		(zone_layer_connections "In1.Cu" "In4.Cu" "In6.Cu")
		(net 23)
	)
	(via
		(at 118.4 71.8)
		(size 0.45)
		(drill 0.2)
		(layers "F.Cu" "B.Cu")
		(remove_unused_layers yes)
		(keep_end_layers yes)
		(zone_layer_connections "In1.Cu" "In4.Cu" "In6.Cu")
		(net 23)
	)
	(via
		(at 165 133.25)
		(size 0.45)
		(drill 0.2)
		(layers "F.Cu" "B.Cu")
		(remove_unused_layers yes)
		(keep_end_layers yes)
		(zone_layer_connections "In1.Cu" "In4.Cu" "In6.Cu")
		(net 23)
	)
	(via
		(at 154.5 111.7)
		(size 0.45)
		(drill 0.2)
		(layers "F.Cu" "B.Cu")
		(remove_unused_layers yes)
		(keep_end_layers yes)
		(zone_layer_connections "In1.Cu" "In4.Cu" "In6.Cu")
		(net 23)
	)
	(via
		(at 143.645 79.25)
		(size 0.45)
		(drill 0.2)
		(layers "F.Cu" "B.Cu")
		(remove_unused_layers yes)
		(keep_end_layers yes)
		(zone_layer_connections "In1.Cu" "In4.Cu" "In6.Cu")
		(net 23)
	)
	(via
		(at 119.25 114.36)
		(size 0.45)
		(drill 0.2)
		(layers "F.Cu" "B.Cu")
		(remove_unused_layers yes)
		(keep_end_layers yes)
		(zone_layer_connections "In1.Cu" "In4.Cu" "In6.Cu")
		(net 23)
	)
	(via
		(at 115.797488 128.4)
		(size 0.45)
		(drill 0.2)
		(layers "F.Cu" "B.Cu")
		(remove_unused_layers yes)
		(keep_end_layers yes)
		(zone_layer_connections "In1.Cu" "In4.Cu" "In6.Cu")
		(net 23)
	)
	(via
		(at 141.05 76.75)
		(size 0.45)
		(drill 0.2)
		(layers "F.Cu" "B.Cu")
		(remove_unused_layers yes)
		(keep_end_layers yes)
		(zone_layer_connections "In1.Cu" "In4.Cu" "In6.Cu")
		(net 23)
	)
	(via
		(at 133.56 118.89)
		(size 0.45)
		(drill 0.2)
		(layers "F.Cu" "B.Cu")
		(remove_unused_layers yes)
		(keep_end_layers yes)
		(zone_layer_connections "In1.Cu" "In4.Cu" "In6.Cu")
		(net 23)
	)
	(via
		(at 159.215 77.25)
		(size 0.45)
		(drill 0.2)
		(layers "F.Cu" "B.Cu")
		(remove_unused_layers yes)
		(keep_end_layers yes)
		(zone_layer_connections "In1.Cu" "In4.Cu" "In6.Cu")
		(net 23)
	)
	(via
		(at 141.915 75.25)
		(size 0.45)
		(drill 0.2)
		(layers "F.Cu" "B.Cu")
		(remove_unused_layers yes)
		(keep_end_layers yes)
		(zone_layer_connections "In1.Cu" "In4.Cu" "In6.Cu")
		(net 23)
	)
	(via
		(at 125.575 122.975)
		(size 0.45)
		(drill 0.2)
		(layers "F.Cu" "B.Cu")
		(remove_unused_layers yes)
		(keep_end_layers yes)
		(zone_layer_connections "In1.Cu" "In4.Cu" "In6.Cu")
		(net 23)
	)
	(via
		(at 159.215 75.25)
		(size 0.45)
		(drill 0.2)
		(layers "F.Cu" "B.Cu")
		(remove_unused_layers yes)
		(keep_end_layers yes)
		(zone_layer_connections "In1.Cu" "In4.Cu" "In6.Cu")
		(net 23)
	)
	(via
		(at 158.35 81.75)
		(size 0.45)
		(drill 0.2)
		(layers "F.Cu" "B.Cu")
		(remove_unused_layers yes)
		(keep_end_layers yes)
		(zone_layer_connections "In1.Cu" "In4.Cu" "In6.Cu")
		(net 23)
	)
	(via
		(at 139.2 112.2)
		(size 0.45)
		(drill 0.2)
		(layers "F.Cu" "B.Cu")
		(remove_unused_layers yes)
		(keep_end_layers yes)
		(zone_layer_connections "In1.Cu" "In4.Cu" "In6.Cu")
		(net 23)
	)
	(via
		(at 152.3 50.6)
		(size 0.45)
		(drill 0.2)
		(layers "F.Cu" "B.Cu")
		(remove_unused_layers yes)
		(keep_end_layers yes)
		(free yes)
		(zone_layer_connections "In1.Cu" "In4.Cu" "In6.Cu")
		(net 23)
	)
	(via
		(at 124.5 69.25)
		(size 0.45)
		(drill 0.2)
		(layers "F.Cu" "B.Cu")
		(remove_unused_layers yes)
		(keep_end_layers yes)
		(zone_layer_connections "In1.Cu" "In4.Cu" "In6.Cu")
		(net 23)
	)
	(via
		(at 131.6 113.9)
		(size 0.45)
		(drill 0.2)
		(layers "F.Cu" "B.Cu")
		(remove_unused_layers yes)
		(keep_end_layers yes)
		(zone_layer_connections "In1.Cu" "In4.Cu" "In6.Cu")
		(net 23)
	)
	(via
		(at 123.25 86.5)
		(size 0.45)
		(drill 0.2)
		(layers "F.Cu" "B.Cu")
		(remove_unused_layers yes)
		(keep_end_layers yes)
		(zone_layer_connections "In1.Cu" "In4.Cu" "In6.Cu")
		(net 23)
	)
	(via
		(at 154.5 114.7)
		(size 0.45)
		(drill 0.2)
		(layers "F.Cu" "B.Cu")
		(remove_unused_layers yes)
		(keep_end_layers yes)
		(zone_layer_connections "In1.Cu" "In4.Cu" "In6.Cu")
		(net 23)
	)
	(via
		(at 171.620002 145.42)
		(size 0.45)
		(drill 0.2)
		(layers "F.Cu" "B.Cu")
		(remove_unused_layers yes)
		(keep_end_layers yes)
		(zone_layer_connections "In1.Cu" "In4.Cu" "In6.Cu")
		(net 23)
	)
	(via
		(at 152.9 51.8)
		(size 0.45)
		(drill 0.2)
		(layers "F.Cu" "B.Cu")
		(remove_unused_layers yes)
		(keep_end_layers yes)
		(free yes)
		(zone_layer_connections "In1.Cu" "In4.Cu" "In6.Cu")
		(net 23)
	)
	(via
		(at 158.35 88.75)
		(size 0.45)
		(drill 0.2)
		(layers "F.Cu" "B.Cu")
		(remove_unused_layers yes)
		(keep_end_layers yes)
		(zone_layer_connections "In1.Cu" "In4.Cu")
		(net 23)
	)
	(via
		(at 132.075 121.025)
		(size 0.45)
		(drill 0.2)
		(layers "F.Cu" "B.Cu")
		(remove_unused_layers yes)
		(keep_end_layers yes)
		(zone_layer_connections "In1.Cu" "In4.Cu" "In6.Cu")
		(net 23)
	)
	(via
		(at 138.8 134.35)
		(size 0.45)
		(drill 0.2)
		(layers "F.Cu" "B.Cu")
		(remove_unused_layers yes)
		(keep_end_layers yes)
		(zone_layer_connections "In1.Cu" "In4.Cu" "In6.Cu")
		(net 23)
	)
	(via
		(at 117.4 129.3)
		(size 0.45)
		(drill 0.2)
		(layers "F.Cu" "B.Cu")
		(remove_unused_layers yes)
		(keep_end_layers yes)
		(zone_layer_connections "In1.Cu" "In4.Cu" "In6.Cu")
		(net 23)
	)
	(via
		(at 120.1 148.3)
		(size 0.45)
		(drill 0.2)
		(layers "F.Cu" "B.Cu")
		(remove_unused_layers yes)
		(keep_end_layers yes)
		(zone_layer_connections "In1.Cu" "In4.Cu" "In6.Cu")
		(net 23)
	)
	(via
		(at 136.185715 99.3)
		(size 0.45)
		(drill 0.2)
		(layers "F.Cu" "B.Cu")
		(remove_unused_layers yes)
		(keep_end_layers yes)
		(zone_layer_connections "In1.Cu" "In4.Cu" "In6.Cu")
		(net 23)
	)
	(via
		(at 126 132.5)
		(size 0.45)
		(drill 0.2)
		(layers "F.Cu" "B.Cu")
		(remove_unused_layers yes)
		(keep_end_layers yes)
		(zone_layer_connections "In1.Cu" "In4.Cu" "In6.Cu")
		(net 23)
	)
	(via
		(at 143.645 83.25)
		(size 0.45)
		(drill 0.2)
		(layers "F.Cu" "B.Cu")
		(remove_unused_layers yes)
		(keep_end_layers yes)
		(zone_layer_connections "In1.Cu" "In4.Cu" "In6.Cu")
		(net 23)
	)
	(via
		(at 124.116 125.33)
		(size 0.45)
		(drill 0.2)
		(layers "F.Cu" "B.Cu")
		(remove_unused_layers yes)
		(keep_end_layers yes)
		(zone_layer_connections "In1.Cu" "In4.Cu" "In6.Cu")
		(net 23)
	)
	(via
		(at 158.11 68.595)
		(size 0.45)
		(drill 0.2)
		(layers "F.Cu" "B.Cu")
		(remove_unused_layers yes)
		(keep_end_layers yes)
		(zone_layer_connections "In1.Cu" "In4.Cu" "In6.Cu")
		(net 23)
	)
	(via
		(at 162.9 94.4)
		(size 0.45)
		(drill 0.2)
		(layers "F.Cu" "B.Cu")
		(remove_unused_layers yes)
		(keep_end_layers yes)
		(zone_layer_connections "In1.Cu" "In4.Cu" "In6.Cu")
		(net 23)
	)
	(via
		(at 138.6 55.9)
		(size 0.45)
		(drill 0.2)
		(layers "F.Cu" "B.Cu")
		(remove_unused_layers yes)
		(keep_end_layers yes)
		(zone_layer_connections "In1.Cu" "In4.Cu" "In6.Cu")
		(net 23)
	)
	(via
		(at 152.3 51.2)
		(size 0.45)
		(drill 0.2)
		(layers "F.Cu" "B.Cu")
		(remove_unused_layers yes)
		(keep_end_layers yes)
		(free yes)
		(zone_layer_connections "In1.Cu" "In4.Cu" "In6.Cu")
		(net 23)
	)
	(via
		(at 162.2 114.7)
		(size 0.45)
		(drill 0.2)
		(layers "F.Cu" "B.Cu")
		(remove_unused_layers yes)
		(keep_end_layers yes)
		(zone_layer_connections "In1.Cu" "In4.Cu" "In6.Cu")
		(net 23)
	)
	(via
		(at 180.3 69.1)
		(size 0.45)
		(drill 0.2)
		(layers "F.Cu" "B.Cu")
		(remove_unused_layers yes)
		(keep_end_layers yes)
		(zone_layer_connections "In1.Cu" "In4.Cu" "In6.Cu")
		(net 23)
	)
	(via
		(at 134.8 117.4)
		(size 0.45)
		(drill 0.2)
		(layers "F.Cu" "B.Cu")
		(remove_unused_layers yes)
		(keep_end_layers yes)
		(zone_layer_connections "In1.Cu" "In4.Cu" "In6.Cu")
		(net 23)
	)
	(via
		(at 136.9 131.6)
		(size 0.45)
		(drill 0.2)
		(layers "F.Cu" "B.Cu")
		(remove_unused_layers yes)
		(keep_end_layers yes)
		(zone_layer_connections "In1.Cu" "In4.Cu" "In6.Cu")
		(net 23)
	)
	(via
		(at 149.7 80.75)
		(size 0.45)
		(drill 0.2)
		(layers "F.Cu" "B.Cu")
		(remove_unused_layers yes)
		(keep_end_layers yes)
		(zone_layer_connections "In1.Cu" "In4.Cu")
		(net 23)
	)
	(via
		(at 125.15 148.35)
		(size 0.45)
		(drill 0.2)
		(layers "F.Cu" "B.Cu")
		(remove_unused_layers yes)
		(keep_end_layers yes)
		(zone_layer_connections "In1.Cu" "In4.Cu" "In6.Cu")
		(net 23)
	)
	(via
		(at 159.8 106.91)
		(size 0.45)
		(drill 0.2)
		(layers "F.Cu" "B.Cu")
		(remove_unused_layers yes)
		(keep_end_layers yes)
		(zone_layer_connections "In1.Cu" "In4.Cu" "In6.Cu")
		(net 23)
	)
	(via
		(at 151.5 98.6)
		(size 0.45)
		(drill 0.2)
		(layers "F.Cu" "B.Cu")
		(remove_unused_layers yes)
		(keep_end_layers yes)
		(zone_layer_connections "In1.Cu" "In4.Cu" "In6.Cu")
		(net 23)
	)
	(via
		(at 126.66 119.14)
		(size 0.45)
		(drill 0.2)
		(layers "F.Cu" "B.Cu")
		(remove_unused_layers yes)
		(keep_end_layers yes)
		(zone_layer_connections "In1.Cu" "In4.Cu" "In6.Cu")
		(net 23)
	)
	(via
		(at 130.620694 95.373662)
		(size 0.45)
		(drill 0.2)
		(layers "F.Cu" "B.Cu")
		(remove_unused_layers yes)
		(keep_end_layers yes)
		(zone_layer_connections "In1.Cu" "In4.Cu" "In6.Cu")
		(net 23)
	)
	(via
		(at 131.425 123.625)
		(size 0.45)
		(drill 0.2)
		(layers "F.Cu" "B.Cu")
		(remove_unused_layers yes)
		(keep_end_layers yes)
		(zone_layer_connections "In1.Cu" "In4.Cu" "In6.Cu")
		(net 23)
	)
	(via
		(at 135.257143 99.3)
		(size 0.45)
		(drill 0.2)
		(layers "F.Cu" "B.Cu")
		(remove_unused_layers yes)
		(keep_end_layers yes)
		(zone_layer_connections "In1.Cu" "In4.Cu" "In6.Cu")
		(net 23)
	)
	(via
		(at 141.915 72.25)
		(size 0.45)
		(drill 0.2)
		(layers "F.Cu" "B.Cu")
		(remove_unused_layers yes)
		(keep_end_layers yes)
		(zone_layer_connections "In1.Cu" "In4.Cu" "In6.Cu")
		(net 23)
	)
	(via
		(at 129.475 123.625)
		(size 0.45)
		(drill 0.2)
		(layers "F.Cu" "B.Cu")
		(remove_unused_layers yes)
		(keep_end_layers yes)
		(zone_layer_connections "In1.Cu" "In4.Cu" "In6.Cu")
		(net 23)
	)
	(via
		(at 125.74 119.14)
		(size 0.45)
		(drill 0.2)
		(layers "F.Cu" "B.Cu")
		(remove_unused_layers yes)
		(keep_end_layers yes)
		(zone_layer_connections "In1.Cu" "In4.Cu" "In6.Cu")
		(net 23)
	)
	(via
		(at 143.4 99.1)
		(size 0.45)
		(drill 0.2)
		(layers "F.Cu" "B.Cu")
		(remove_unused_layers yes)
		(keep_end_layers yes)
		(zone_layer_connections "In1.Cu" "In4.Cu" "In6.Cu")
		(net 23)
	)
	(via
		(at 160.08 71.75)
		(size 0.45)
		(drill 0.2)
		(layers "F.Cu" "B.Cu")
		(remove_unused_layers yes)
		(keep_end_layers yes)
		(zone_layer_connections "In1.Cu" "In4.Cu" "In6.Cu")
		(net 23)
	)
	(via
		(at 142.6 63.4)
		(size 0.45)
		(drill 0.2)
		(layers "F.Cu" "B.Cu")
		(remove_unused_layers yes)
		(keep_end_layers yes)
		(zone_layer_connections "In1.Cu" "In4.Cu" "In6.Cu")
		(net 23)
	)
	(via
		(at 126.225 124.925)
		(size 0.45)
		(drill 0.2)
		(layers "F.Cu" "B.Cu")
		(remove_unused_layers yes)
		(keep_end_layers yes)
		(zone_layer_connections "In1.Cu" "In4.Cu" "In6.Cu")
		(net 23)
	)
	(via
		(at 132.075 127.525)
		(size 0.45)
		(drill 0.2)
		(layers "F.Cu" "B.Cu")
		(remove_unused_layers yes)
		(keep_end_layers yes)
		(zone_layer_connections "In1.Cu" "In4.Cu" "In6.Cu")
		(net 23)
	)
	(via
		(at 143.81 106.91)
		(size 0.45)
		(drill 0.2)
		(layers "F.Cu" "B.Cu")
		(remove_unused_layers yes)
		(keep_end_layers yes)
		(zone_layer_connections "In1.Cu" "In4.Cu" "In6.Cu")
		(net 23)
	)
	(via
		(at 141.915 74.25)
		(size 0.45)
		(drill 0.2)
		(layers "F.Cu" "B.Cu")
		(remove_unused_layers yes)
		(keep_end_layers yes)
		(zone_layer_connections "In1.Cu" "In4.Cu" "In6.Cu")
		(net 23)
	)
	(via
		(at 141.915 78.25)
		(size 0.45)
		(drill 0.2)
		(layers "F.Cu" "B.Cu")
		(remove_unused_layers yes)
		(keep_end_layers yes)
		(zone_layer_connections "In1.Cu" "In4.Cu" "In6.Cu")
		(net 23)
	)
	(via
		(at 129.88 119.81)
		(size 0.45)
		(drill 0.2)
		(layers "F.Cu" "B.Cu")
		(remove_unused_layers yes)
		(keep_end_layers yes)
		(zone_layer_connections "In1.Cu" "In4.Cu" "In6.Cu")
		(net 23)
	)
	(via
		(at 149.7 89.75)
		(size 0.45)
		(drill 0.2)
		(layers "F.Cu" "B.Cu")
		(remove_unused_layers yes)
		(keep_end_layers yes)
		(zone_layer_connections "In1.Cu" "In4.Cu")
		(net 23)
	)
	(via
		(at 154.025 79.25)
		(size 0.45)
		(drill 0.2)
		(layers "F.Cu" "B.Cu")
		(remove_unused_layers yes)
		(keep_end_layers yes)
		(zone_layer_connections "In1.Cu" "In4.Cu")
		(net 23)
	)
	(via
		(at 165.85 93.4)
		(size 0.45)
		(drill 0.2)
		(layers "F.Cu" "B.Cu")
		(remove_unused_layers yes)
		(keep_end_layers yes)
		(zone_layer_connections "In1.Cu" "In4.Cu" "In6.Cu")
		(net 23)
	)
	(via
		(at 154.89 86.75)
		(size 0.45)
		(drill 0.2)
		(layers "F.Cu" "B.Cu")
		(remove_unused_layers yes)
		(keep_end_layers yes)
		(zone_layer_connections "In1.Cu" "In4.Cu")
		(net 23)
	)
	(via
		(at 147.97 78.75)
		(size 0.45)
		(drill 0.2)
		(layers "F.Cu" "B.Cu")
		(remove_unused_layers yes)
		(keep_end_layers yes)
		(zone_layer_connections "In1.Cu" "In4.Cu")
		(net 23)
	)
	(via
		(at 156.62 82.75)
		(size 0.45)
		(drill 0.2)
		(layers "F.Cu" "B.Cu")
		(remove_unused_layers yes)
		(keep_end_layers yes)
		(zone_layer_connections "In1.Cu" "In4.Cu")
		(net 23)
	)
	(via
		(at 134.85 131.6)
		(size 0.45)
		(drill 0.2)
		(layers "F.Cu" "B.Cu")
		(remove_unused_layers yes)
		(keep_end_layers yes)
		(zone_layer_connections "In1.Cu" "In4.Cu" "In6.Cu")
		(net 23)
	)
	(via
		(at 135.88 138.04)
		(size 0.45)
		(drill 0.2)
		(layers "F.Cu" "B.Cu")
		(remove_unused_layers yes)
		(keep_end_layers yes)
		(zone_layer_connections "In1.Cu" "In4.Cu" "In6.Cu")
		(net 23)
	)
	(via
		(at 116 140.5)
		(size 0.45)
		(drill 0.2)
		(layers "F.Cu" "B.Cu")
		(remove_unused_layers yes)
		(keep_end_layers yes)
		(zone_layer_connections "In1.Cu" "In4.Cu" "In6.Cu")
		(net 23)
	)
	(via
		(at 166.85 96.4)
		(size 0.45)
		(drill 0.2)
		(layers "F.Cu" "B.Cu")
		(remove_unused_layers yes)
		(keep_end_layers yes)
		(zone_layer_connections "In1.Cu" "In4.Cu" "In6.Cu")
		(net 23)
	)
	(via
		(at 141.915 91.25)
		(size 0.45)
		(drill 0.2)
		(layers "F.Cu" "B.Cu")
		(remove_unused_layers yes)
		(keep_end_layers yes)
		(zone_layer_connections "In1.Cu" "In4.Cu")
		(net 23)
	)
	(via
		(at 137 114.4)
		(size 0.45)
		(drill 0.2)
		(layers "F.Cu" "B.Cu")
		(remove_unused_layers yes)
		(keep_end_layers yes)
		(zone_layer_connections "In1.Cu" "In4.Cu" "In6.Cu")
		(net 23)
	)
	(via
		(at 133.4 99.3)
		(size 0.45)
		(drill 0.2)
		(layers "F.Cu" "B.Cu")
		(remove_unused_layers yes)
		(keep_end_layers yes)
		(zone_layer_connections "In1.Cu" "In4.Cu" "In6.Cu")
		(net 23)
	)
	(via
		(at 127.4 133.5)
		(size 0.45)
		(drill 0.2)
		(layers "F.Cu" "B.Cu")
		(remove_unused_layers yes)
		(keep_end_layers yes)
		(zone_layer_connections "In1.Cu" "In4.Cu" "In6.Cu")
		(net 23)
	)
	(via
		(at 143.645 87.25)
		(size 0.45)
		(drill 0.2)
		(layers "F.Cu" "B.Cu")
		(remove_unused_layers yes)
		(keep_end_layers yes)
		(zone_layer_connections "In1.Cu" "In4.Cu")
		(net 23)
	)
	(via
		(at 125.4 75.75)
		(size 0.45)
		(drill 0.2)
		(layers "F.Cu" "B.Cu")
		(remove_unused_layers yes)
		(keep_end_layers yes)
		(zone_layer_connections "In1.Cu" "In4.Cu" "In6.Cu")
		(net 23)
	)
	(via
		(at 124.116 128.09)
		(size 0.45)
		(drill 0.2)
		(layers "F.Cu" "B.Cu")
		(remove_unused_layers yes)
		(keep_end_layers yes)
		(zone_layer_connections "In1.Cu" "In4.Cu" "In6.Cu")
		(net 23)
	)
	(via
		(at 141.915 80.25)
		(size 0.45)
		(drill 0.2)
		(layers "F.Cu" "B.Cu")
		(remove_unused_layers yes)
		(keep_end_layers yes)
		(zone_layer_connections "In1.Cu" "In4.Cu" "In6.Cu")
		(net 23)
	)
	(via
		(at 147 53.5)
		(size 0.45)
		(drill 0.2)
		(layers "F.Cu" "B.Cu")
		(remove_unused_layers yes)
		(keep_end_layers yes)
		(zone_layer_connections "In1.Cu" "In4.Cu" "In6.Cu")
		(net 23)
	)
	(via
		(at 123.9 118.89)
		(size 0.45)
		(drill 0.2)
		(layers "F.Cu" "B.Cu")
		(remove_unused_layers yes)
		(keep_end_layers yes)
		(zone_layer_connections "In1.Cu" "In4.Cu" "In6.Cu")
		(net 23)
	)
	(via
		(at 136.11 106.91)
		(size 0.45)
		(drill 0.2)
		(layers "F.Cu" "B.Cu")
		(remove_unused_layers yes)
		(keep_end_layers yes)
		(zone_layer_connections "In1.Cu" "In4.Cu" "In6.Cu")
		(net 23)
	)
	(via
		(at 138.929999 117.7)
		(size 0.45)
		(drill 0.2)
		(layers "F.Cu" "B.Cu")
		(remove_unused_layers yes)
		(keep_end_layers yes)
		(zone_layer_connections "In1.Cu" "In4.Cu" "In6.Cu")
		(net 23)
	)
	(via
		(at 124.5 132.75)
		(size 0.45)
		(drill 0.2)
		(layers "F.Cu" "B.Cu")
		(remove_unused_layers yes)
		(keep_end_layers yes)
		(zone_layer_connections "In1.Cu" "In4.Cu" "In6.Cu")
		(net 23)
	)
	(via
		(at 139.75 88)
		(size 0.45)
		(drill 0.2)
		(layers "F.Cu" "B.Cu")
		(remove_unused_layers yes)
		(keep_end_layers yes)
		(zone_layer_connections "In1.Cu" "In4.Cu" "In6.Cu")
		(net 23)
	)
	(via
		(at 133.798281 92.796601)
		(size 0.45)
		(drill 0.2)
		(layers "F.Cu" "B.Cu")
		(remove_unused_layers yes)
		(keep_end_layers yes)
		(zone_layer_connections "In1.Cu" "In4.Cu" "In6.Cu")
		(net 23)
	)
	(via
		(at 160.945 78.25)
		(size 0.45)
		(drill 0.2)
		(layers "F.Cu" "B.Cu")
		(remove_unused_layers yes)
		(keep_end_layers yes)
		(zone_layer_connections "In1.Cu" "In4.Cu" "In6.Cu")
		(net 23)
	)
	(via
		(at 116.4 109.8)
		(size 0.45)
		(drill 0.2)
		(layers "F.Cu" "B.Cu")
		(remove_unused_layers yes)
		(keep_end_layers yes)
		(zone_layer_connections "In1.Cu" "In4.Cu" "In6.Cu")
		(net 23)
	)
	(via
		(at 145.375 86.25)
		(size 0.45)
		(drill 0.2)
		(layers "F.Cu" "B.Cu")
		(remove_unused_layers yes)
		(keep_end_layers yes)
		(zone_layer_connections "In1.Cu" "In4.Cu")
		(net 23)
	)
	(via
		(at 131.26 129.01)
		(size 0.45)
		(drill 0.2)
		(layers "F.Cu" "B.Cu")
		(remove_unused_layers yes)
		(keep_end_layers yes)
		(zone_layer_connections "In1.Cu" "In4.Cu" "In6.Cu")
		(net 23)
	)
	(via
		(at 144.4 106.91)
		(size 0.45)
		(drill 0.2)
		(layers "F.Cu" "B.Cu")
		(remove_unused_layers yes)
		(keep_end_layers yes)
		(zone_layer_connections "In1.Cu" "In4.Cu" "In6.Cu")
		(net 23)
	)
	(via
		(at 135.75 77.65)
		(size 0.45)
		(drill 0.2)
		(layers "F.Cu" "B.Cu")
		(remove_unused_layers yes)
		(keep_end_layers yes)
		(zone_layer_connections "In1.Cu" "In4.Cu" "In6.Cu")
		(net 23)
	)
	(via
		(at 141.05 91.75)
		(size 0.45)
		(drill 0.2)
		(layers "F.Cu" "B.Cu")
		(remove_unused_layers yes)
		(keep_end_layers yes)
		(zone_layer_connections "In1.Cu" "In4.Cu")
		(net 23)
	)
	(via
		(at 165.85 97.4)
		(size 0.45)
		(drill 0.2)
		(layers "F.Cu" "B.Cu")
		(remove_unused_layers yes)
		(keep_end_layers yes)
		(zone_layer_connections "In1.Cu" "In4.Cu" "In6.Cu")
		(net 23)
	)
	(via
		(at 124.5 131.75)
		(size 0.45)
		(drill 0.2)
		(layers "F.Cu" "B.Cu")
		(remove_unused_layers yes)
		(keep_end_layers yes)
		(zone_layer_connections "In1.Cu" "In4.Cu" "In6.Cu")
		(net 23)
	)
	(via
		(at 134.6 113.4)
		(size 0.45)
		(drill 0.2)
		(layers "F.Cu" "B.Cu")
		(remove_unused_layers yes)
		(keep_end_layers yes)
		(zone_layer_connections "In1.Cu" "In4.Cu" "In6.Cu")
		(net 23)
	)
	(via
		(at 145.375 87.25)
		(size 0.45)
		(drill 0.2)
		(layers "F.Cu" "B.Cu")
		(remove_unused_layers yes)
		(keep_end_layers yes)
		(zone_layer_connections "In1.Cu" "In4.Cu")
		(net 23)
	)
	(via
		(at 142.78 85.75)
		(size 0.45)
		(drill 0.2)
		(layers "F.Cu" "B.Cu")
		(remove_unused_layers yes)
		(keep_end_layers yes)
		(zone_layer_connections "In1.Cu" "In4.Cu")
		(net 23)
	)
	(via
		(at 144.51 83.75)
		(size 0.45)
		(drill 0.2)
		(layers "F.Cu" "B.Cu")
		(remove_unused_layers yes)
		(keep_end_layers yes)
		(zone_layer_connections "In1.Cu" "In4.Cu")
		(net 23)
	)
	(via
		(at 135.75 80.65)
		(size 0.45)
		(drill 0.2)
		(layers "F.Cu" "B.Cu")
		(remove_unused_layers yes)
		(keep_end_layers yes)
		(zone_layer_connections "In1.Cu" "In4.Cu" "In6.Cu")
		(net 23)
	)
	(via
		(at 142.1 55.3)
		(size 0.45)
		(drill 0.2)
		(layers "F.Cu" "B.Cu")
		(remove_unused_layers yes)
		(keep_end_layers yes)
		(zone_layer_connections "In1.Cu" "In4.Cu" "In6.Cu")
		(net 23)
	)
	(via
		(at 161.9 94.4)
		(size 0.45)
		(drill 0.2)
		(layers "F.Cu" "B.Cu")
		(remove_unused_layers yes)
		(keep_end_layers yes)
		(zone_layer_connections "In1.Cu" "In4.Cu" "In6.Cu")
		(net 23)
	)
	(via
		(at 134.75 106.2)
		(size 0.45)
		(drill 0.2)
		(layers "F.Cu" "B.Cu")
		(remove_unused_layers yes)
		(keep_end_layers yes)
		(zone_layer_connections "In1.Cu" "In4.Cu" "In6.Cu")
		(net 23)
	)
	(via
		(at 165.85 98.4)
		(size 0.45)
		(drill 0.2)
		(layers "F.Cu" "B.Cu")
		(remove_unused_layers yes)
		(keep_end_layers yes)
		(zone_layer_connections "In1.Cu" "In4.Cu" "In6.Cu")
		(net 23)
	)
	(via
		(at 119.25 114.95)
		(size 0.45)
		(drill 0.2)
		(layers "F.Cu" "B.Cu")
		(remove_unused_layers yes)
		(keep_end_layers yes)
		(zone_layer_connections "In1.Cu" "In4.Cu" "In6.Cu")
		(net 23)
	)
	(via
		(at 160.08 78.75)
		(size 0.45)
		(drill 0.2)
		(layers "F.Cu" "B.Cu")
		(remove_unused_layers yes)
		(keep_end_layers yes)
		(zone_layer_connections "In1.Cu" "In4.Cu" "In6.Cu")
		(net 23)
	)
	(via
		(at 135.8 128.7)
		(size 0.45)
		(drill 0.2)
		(layers "F.Cu" "B.Cu")
		(remove_unused_layers yes)
		(keep_end_layers yes)
		(zone_layer_connections "In1.Cu" "In4.Cu" "In6.Cu")
		(net 23)
	)
	(via
		(at 146.25 80.75)
		(size 0.45)
		(drill 0.2)
		(layers "F.Cu" "B.Cu")
		(remove_unused_layers yes)
		(keep_end_layers yes)
		(zone_layer_connections "In1.Cu" "In4.Cu")
		(net 23)
	)
	(via
		(at 143.7 95.2)
		(size 0.45)
		(drill 0.2)
		(layers "F.Cu" "B.Cu")
		(remove_unused_layers yes)
		(keep_end_layers yes)
		(zone_layer_connections "In1.Cu" "In4.Cu" "In6.Cu")
		(net 23)
	)
	(via
		(at 145.375 85.25)
		(size 0.45)
		(drill 0.2)
		(layers "F.Cu" "B.Cu")
		(remove_unused_layers yes)
		(keep_end_layers yes)
		(zone_layer_connections "In1.Cu" "In4.Cu")
		(net 23)
	)
	(via
		(at 119 120.6)
		(size 0.45)
		(drill 0.2)
		(layers "F.Cu" "B.Cu")
		(remove_unused_layers yes)
		(keep_end_layers yes)
		(zone_layer_connections "In1.Cu" "In4.Cu" "In6.Cu")
		(net 23)
	)
	(via
		(at 149.6 145.4)
		(size 0.45)
		(drill 0.2)
		(layers "F.Cu" "B.Cu")
		(remove_unused_layers yes)
		(keep_end_layers yes)
		(zone_layer_connections "In1.Cu" "In4.Cu" "In6.Cu")
		(net 23)
	)
	(via
		(at 183.25 133.25)
		(size 0.45)
		(drill 0.2)
		(layers "F.Cu" "B.Cu")
		(remove_unused_layers yes)
		(keep_end_layers yes)
		(zone_layer_connections "In1.Cu" "In4.Cu" "In6.Cu")
		(net 23)
	)
	(via
		(at 139.2 111.5)
		(size 0.45)
		(drill 0.2)
		(layers "F.Cu" "B.Cu")
		(remove_unused_layers yes)
		(keep_end_layers yes)
		(zone_layer_connections "In1.Cu" "In4.Cu" "In6.Cu")
		(net 23)
	)
	(via
		(at 138.3 112.9)
		(size 0.45)
		(drill 0.2)
		(layers "F.Cu" "B.Cu")
		(remove_unused_layers yes)
		(keep_end_layers yes)
		(zone_layer_connections "In1.Cu" "In4.Cu" "In6.Cu")
		(net 23)
	)
	(via
		(at 130.775 123.625)
		(size 0.45)
		(drill 0.2)
		(layers "F.Cu" "B.Cu")
		(remove_unused_layers yes)
		(keep_end_layers yes)
		(zone_layer_connections "In1.Cu" "In4.Cu" "In6.Cu")
		(net 23)
	)
	(via
		(at 159.22 91.34)
		(size 0.45)
		(drill 0.2)
		(layers "F.Cu" "B.Cu")
		(remove_unused_layers yes)
		(keep_end_layers yes)
		(zone_layer_connections "In1.Cu" "In4.Cu")
		(net 23)
	)
	(via
		(at 147.97 76.075)
		(size 0.45)
		(drill 0.2)
		(layers "F.Cu" "B.Cu")
		(remove_unused_layers yes)
		(keep_end_layers yes)
		(zone_layer_connections "In1.Cu" "In4.Cu")
		(net 23)
	)
	(via
		(at 153.16 80.75)
		(size 0.45)
		(drill 0.2)
		(layers "F.Cu" "B.Cu")
		(remove_unused_layers yes)
		(keep_end_layers yes)
		(zone_layer_connections "In1.Cu" "In4.Cu")
		(net 23)
	)
	(via
		(at 115.797488 122.4)
		(size 0.45)
		(drill 0.2)
		(layers "F.Cu" "B.Cu")
		(remove_unused_layers yes)
		(keep_end_layers yes)
		(zone_layer_connections "In1.Cu" "In4.Cu" "In6.Cu")
		(net 23)
	)
	(via
		(at 125.4 87.75)
		(size 0.45)
		(drill 0.2)
		(layers "F.Cu" "B.Cu")
		(remove_unused_layers yes)
		(keep_end_layers yes)
		(zone_layer_connections "In1.Cu" "In4.Cu" "In6.Cu")
		(net 23)
	)
	(via
		(at 119.7 64.7)
		(size 0.45)
		(drill 0.2)
		(layers "F.Cu" "B.Cu")
		(remove_unused_layers yes)
		(keep_end_layers yes)
		(zone_layer_connections "In1.Cu" "In4.Cu" "In6.Cu")
		(net 23)
	)
	(via
		(at 124.116 119.81)
		(size 0.45)
		(drill 0.2)
		(layers "F.Cu" "B.Cu")
		(remove_unused_layers yes)
		(keep_end_layers yes)
		(zone_layer_connections "In1.Cu" "In4.Cu" "In6.Cu")
		(net 23)
	)
	(via
		(at 141 53.5)
		(size 0.45)
		(drill 0.2)
		(layers "F.Cu" "B.Cu")
		(remove_unused_layers yes)
		(keep_end_layers yes)
		(zone_layer_connections "In1.Cu" "In4.Cu" "In6.Cu")
		(net 23)
	)
	(via
		(at 136.7 106.2)
		(size 0.45)
		(drill 0.2)
		(layers "F.Cu" "B.Cu")
		(remove_unused_layers yes)
		(keep_end_layers yes)
		(zone_layer_connections "In1.Cu" "In4.Cu" "In6.Cu")
		(net 23)
	)
	(via
		(at 157.85 106.2)
		(size 0.45)
		(drill 0.2)
		(layers "F.Cu" "B.Cu")
		(remove_unused_layers yes)
		(keep_end_layers yes)
		(zone_layer_connections "In1.Cu" "In4.Cu" "In6.Cu")
		(net 23)
	)
	(via
		(at 150.975 66.625)
		(size 0.45)
		(drill 0.2)
		(layers "F.Cu" "B.Cu")
		(remove_unused_layers yes)
		(keep_end_layers yes)
		(zone_layer_connections "In1.Cu" "In4.Cu" "In6.Cu")
		(net 23)
	)
	(via
		(at 155.5 94.024999)
		(size 0.45)
		(drill 0.2)
		(layers "F.Cu" "B.Cu")
		(remove_unused_layers yes)
		(keep_end_layers yes)
		(zone_layer_connections "In1.Cu" "In4.Cu")
		(net 23)
	)
	(via
		(at 130.338 118.493)
		(size 0.45)
		(drill 0.2)
		(layers "F.Cu" "B.Cu")
		(remove_unused_layers yes)
		(keep_end_layers yes)
		(zone_layer_connections "In1.Cu" "In4.Cu" "In6.Cu")
		(net 23)
	)
	(via
		(at 137.114287 99.3)
		(size 0.45)
		(drill 0.2)
		(layers "F.Cu" "B.Cu")
		(remove_unused_layers yes)
		(keep_end_layers yes)
		(zone_layer_connections "In1.Cu" "In4.Cu" "In6.Cu")
		(net 23)
	)
	(via
		(at 151.9 102.4)
		(size 0.45)
		(drill 0.2)
		(layers "F.Cu" "B.Cu")
		(remove_unused_layers yes)
		(keep_end_layers yes)
		(zone_layer_connections "In1.Cu" "In4.Cu" "In6.Cu")
		(net 23)
	)
	(via
		(at 132.075 125.575)
		(size 0.45)
		(drill 0.2)
		(layers "F.Cu" "B.Cu")
		(remove_unused_layers yes)
		(keep_end_layers yes)
		(zone_layer_connections "In1.Cu" "In4.Cu" "In6.Cu")
		(net 23)
	)
	(via
		(at 133.56 129.01)
		(size 0.45)
		(drill 0.2)
		(layers "F.Cu" "B.Cu")
		(remove_unused_layers yes)
		(keep_end_layers yes)
		(zone_layer_connections "In1.Cu" "In4.Cu" "In6.Cu")
		(net 23)
	)
	(via
		(at 136.75 74.65)
		(size 0.45)
		(drill 0.2)
		(layers "F.Cu" "B.Cu")
		(remove_unused_layers yes)
		(keep_end_layers yes)
		(zone_layer_connections "In1.Cu" "In4.Cu" "In6.Cu")
		(net 23)
	)
	(via
		(at 156.62 81.75)
		(size 0.45)
		(drill 0.2)
		(layers "F.Cu" "B.Cu")
		(remove_unused_layers yes)
		(keep_end_layers yes)
		(zone_layer_connections "In1.Cu" "In4.Cu" "In6.Cu")
		(net 23)
	)
	(via
		(at 126.65 79.55)
		(size 0.45)
		(drill 0.2)
		(layers "F.Cu" "B.Cu")
		(remove_unused_layers yes)
		(keep_end_layers yes)
		(zone_layer_connections "In1.Cu" "In4.Cu" "In6.Cu")
		(net 23)
	)
	(via
		(at 149.625 67.975)
		(size 0.45)
		(drill 0.2)
		(layers "F.Cu" "B.Cu")
		(remove_unused_layers yes)
		(keep_end_layers yes)
		(zone_layer_connections "In1.Cu" "In4.Cu" "In6.Cu")
		(net 23)
	)
	(via
		(at 131.4 71.4)
		(size 0.45)
		(drill 0.2)
		(layers "F.Cu" "B.Cu")
		(remove_unused_layers yes)
		(keep_end_layers yes)
		(zone_layer_connections "In1.Cu" "In4.Cu" "In6.Cu")
		(net 23)
	)
	(via
		(at 145.9 114.7)
		(size 0.45)
		(drill 0.2)
		(layers "F.Cu" "B.Cu")
		(remove_unused_layers yes)
		(keep_end_layers yes)
		(zone_layer_connections "In1.Cu" "In4.Cu" "In6.Cu")
		(net 23)
	)
	(via
		(at 146.8 114.7)
		(size 0.45)
		(drill 0.2)
		(layers "F.Cu" "B.Cu")
		(remove_unused_layers yes)
		(keep_end_layers yes)
		(zone_layer_connections "In1.Cu" "In4.Cu" "In6.Cu")
		(net 23)
	)
	(via
		(at 146.8 112.699999)
		(size 0.45)
		(drill 0.2)
		(layers "F.Cu" "B.Cu")
		(remove_unused_layers yes)
		(keep_end_layers yes)
		(zone_layer_connections "In1.Cu" "In4.Cu" "In6.Cu")
		(net 23)
	)
	(via
		(at 144.51 73.75)
		(size 0.45)
		(drill 0.2)
		(layers "F.Cu" "B.Cu")
		(remove_unused_layers yes)
		(keep_end_layers yes)
		(zone_layer_connections "In1.Cu" "In4.Cu" "In6.Cu")
		(net 23)
	)
	(via
		(at 143.04 106.2)
		(size 0.45)
		(drill 0.2)
		(layers "F.Cu" "B.Cu")
		(remove_unused_layers yes)
		(keep_end_layers yes)
		(zone_layer_connections "In1.Cu" "In4.Cu" "In6.Cu")
		(net 23)
	)
	(via
		(at 158.44 106.9)
		(size 0.45)
		(drill 0.2)
		(layers "F.Cu" "B.Cu")
		(remove_unused_layers yes)
		(keep_end_layers yes)
		(zone_layer_connections "In1.Cu" "In4.Cu" "In6.Cu")
		(net 23)
	)
	(via
		(at 131.4 87.5)
		(size 0.45)
		(drill 0.2)
		(layers "F.Cu" "B.Cu")
		(remove_unused_layers yes)
		(keep_end_layers yes)
		(zone_layer_connections "In1.Cu" "In4.Cu" "In6.Cu")
		(net 23)
	)
	(via
		(at 152.325 67.975)
		(size 0.45)
		(drill 0.2)
		(layers "F.Cu" "B.Cu")
		(remove_unused_layers yes)
		(keep_end_layers yes)
		(zone_layer_connections "In1.Cu" "In4.Cu" "In6.Cu")
		(net 23)
	)
	(via
		(at 156.62 84.75)
		(size 0.45)
		(drill 0.2)
		(layers "F.Cu" "B.Cu")
		(remove_unused_layers yes)
		(keep_end_layers yes)
		(zone_layer_connections "In1.Cu" "In4.Cu")
		(net 23)
	)
	(via
		(at 133.56 123.95)
		(size 0.45)
		(drill 0.2)
		(layers "F.Cu" "B.Cu")
		(remove_unused_layers yes)
		(keep_end_layers yes)
		(zone_layer_connections "In1.Cu" "In4.Cu" "In6.Cu")
		(net 23)
	)
	(via
		(at 149.625 66.625)
		(size 0.45)
		(drill 0.2)
		(layers "F.Cu" "B.Cu")
		(remove_unused_layers yes)
		(keep_end_layers yes)
		(zone_layer_connections "In1.Cu" "In4.Cu" "In6.Cu")
		(net 23)
	)
	(via
		(at 119.8 131.2)
		(size 0.45)
		(drill 0.2)
		(layers "F.Cu" "B.Cu")
		(remove_unused_layers yes)
		(keep_end_layers yes)
		(zone_layer_connections "In1.Cu" "In4.Cu" "In6.Cu")
		(net 23)
	)
	(via
		(at 156.21 65.655)
		(size 0.45)
		(drill 0.2)
		(layers "F.Cu" "B.Cu")
		(remove_unused_layers yes)
		(keep_end_layers yes)
		(zone_layer_connections "In1.Cu" "In4.Cu" "In6.Cu")
		(net 23)
	)
	(via
		(at 132 131.2)
		(size 0.45)
		(drill 0.2)
		(layers "F.Cu" "B.Cu")
		(remove_unused_layers yes)
		(keep_end_layers yes)
		(zone_layer_connections "In1.Cu" "In4.Cu" "In6.Cu")
		(net 23)
	)
	(via
		(at 166.85 98.4)
		(size 0.45)
		(drill 0.2)
		(layers "F.Cu" "B.Cu")
		(remove_unused_layers yes)
		(keep_end_layers yes)
		(zone_layer_connections "In1.Cu" "In4.Cu" "In6.Cu")
		(net 23)
	)
	(via
		(at 133.56 123.03)
		(size 0.45)
		(drill 0.2)
		(layers "F.Cu" "B.Cu")
		(remove_unused_layers yes)
		(keep_end_layers yes)
		(zone_layer_connections "In1.Cu" "In4.Cu" "In6.Cu")
		(net 23)
	)
	(via
		(at 158.35 89.75)
		(size 0.45)
		(drill 0.2)
		(layers "F.Cu" "B.Cu")
		(remove_unused_layers yes)
		(keep_end_layers yes)
		(zone_layer_connections "In1.Cu" "In4.Cu")
		(net 23)
	)
	(via
		(at 141.915 87.25)
		(size 0.45)
		(drill 0.2)
		(layers "F.Cu" "B.Cu")
		(remove_unused_layers yes)
		(keep_end_layers yes)
		(zone_layer_connections "In1.Cu" "In4.Cu")
		(net 23)
	)
	(via
		(at 141.4 119.5)
		(size 0.45)
		(drill 0.2)
		(layers "F.Cu" "B.Cu")
		(remove_unused_layers yes)
		(keep_end_layers yes)
		(zone_layer_connections "In1.Cu" "In4.Cu" "In6.Cu")
		(net 23)
	)
	(via
		(at 141.5 123.75)
		(size 0.45)
		(drill 0.2)
		(layers "F.Cu" "B.Cu")
		(remove_unused_layers yes)
		(keep_end_layers yes)
		(zone_layer_connections "In1.Cu" "In4.Cu" "In6.Cu")
		(net 23)
	)
	(via
		(at 153 55.6)
		(size 0.45)
		(drill 0.2)
		(layers "F.Cu" "B.Cu")
		(remove_unused_layers yes)
		(keep_end_layers yes)
		(zone_layer_connections "In1.Cu" "In4.Cu" "In6.Cu")
		(net 23)
	)
	(via
		(at 154 51.3)
		(size 0.45)
		(drill 0.2)
		(layers "F.Cu" "B.Cu")
		(remove_unused_layers yes)
		(keep_end_layers yes)
		(free yes)
		(zone_layer_connections "In1.Cu" "In4.Cu" "In6.Cu")
		(net 23)
	)
	(via
		(at 118.9 93.7)
		(size 0.45)
		(drill 0.2)
		(layers "F.Cu" "B.Cu")
		(remove_unused_layers yes)
		(keep_end_layers yes)
		(zone_layer_connections "In1.Cu" "In4.Cu" "In6.Cu")
		(net 23)
	)
	(via
		(at 143.645 91.25)
		(size 0.45)
		(drill 0.2)
		(layers "F.Cu" "B.Cu")
		(remove_unused_layers yes)
		(keep_end_layers yes)
		(zone_layer_connections "In1.Cu" "In4.Cu")
		(net 23)
	)
	(via
		(at 156.62 79.75)
		(size 0.45)
		(drill 0.2)
		(layers "F.Cu" "B.Cu")
		(remove_unused_layers yes)
		(keep_end_layers yes)
		(zone_layer_connections "In1.Cu" "In4.Cu" "In6.Cu")
		(net 23)
	)
	(via
		(at 161.75 139.25)
		(size 0.45)
		(drill 0.2)
		(layers "F.Cu" "B.Cu")
		(remove_unused_layers yes)
		(keep_end_layers yes)
		(zone_layer_connections "In1.Cu" "In4.Cu" "In6.Cu")
		(net 23)
	)
	(via
		(at 135.9 131.6)
		(size 0.45)
		(drill 0.2)
		(layers "F.Cu" "B.Cu")
		(remove_unused_layers yes)
		(keep_end_layers yes)
		(zone_layer_connections "In1.Cu" "In4.Cu" "In6.Cu")
		(net 23)
	)
	(via
		(at 134 122.1)
		(size 0.45)
		(drill 0.2)
		(layers "F.Cu" "B.Cu")
		(remove_unused_layers yes)
		(keep_end_layers yes)
		(zone_layer_connections "In1.Cu" "In4.Cu" "In6.Cu")
		(net 23)
	)
	(via
		(at 154.89 79.75)
		(size 0.45)
		(drill 0.2)
		(layers "F.Cu" "B.Cu")
		(remove_unused_layers yes)
		(keep_end_layers yes)
		(zone_layer_connections "In1.Cu" "In4.Cu")
		(net 23)
	)
	(via
		(at 139.3 87.5)
		(size 0.45)
		(drill 0.2)
		(layers "F.Cu" "B.Cu")
		(remove_unused_layers yes)
		(keep_end_layers yes)
		(zone_layer_connections "In1.Cu" "In4.Cu" "In6.Cu")
		(net 23)
	)
	(via
		(at 143.595 75.25)
		(size 0.45)
		(drill 0.2)
		(layers "F.Cu" "B.Cu")
		(remove_unused_layers yes)
		(keep_end_layers yes)
		(zone_layer_connections "In1.Cu" "In4.Cu" "In6.Cu")
		(net 23)
	)
	(via
		(at 151.43 77.75)
		(size 0.45)
		(drill 0.2)
		(layers "F.Cu" "B.Cu")
		(remove_unused_layers yes)
		(keep_end_layers yes)
		(zone_layer_connections "In1.Cu" "In4.Cu")
		(net 23)
	)
	(via
		(at 144.4 99.1)
		(size 0.45)
		(drill 0.2)
		(layers "F.Cu" "B.Cu")
		(remove_unused_layers yes)
		(keep_end_layers yes)
		(zone_layer_connections "In1.Cu" "In4.Cu" "In6.Cu")
		(net 23)
	)
	(via
		(at 154.89 84.75)
		(size 0.45)
		(drill 0.2)
		(layers "F.Cu" "B.Cu")
		(remove_unused_layers yes)
		(keep_end_layers yes)
		(zone_layer_connections "In1.Cu" "In4.Cu")
		(net 23)
	)
	(via
		(at 120.5 94)
		(size 0.45)
		(drill 0.2)
		(layers "F.Cu" "B.Cu")
		(remove_unused_layers yes)
		(keep_end_layers yes)
		(zone_layer_connections "In1.Cu" "In4.Cu" "In6.Cu")
		(net 23)
	)
	(via
		(at 118.25 142.5)
		(size 0.45)
		(drill 0.2)
		(layers "F.Cu" "B.Cu")
		(remove_unused_layers yes)
		(keep_end_layers yes)
		(zone_layer_connections "In1.Cu" "In4.Cu" "In6.Cu")
		(net 23)
	)
	(via
		(at 141.05 71.75)
		(size 0.45)
		(drill 0.2)
		(layers "F.Cu" "B.Cu")
		(remove_unused_layers yes)
		(keep_end_layers yes)
		(zone_layer_connections "In1.Cu" "In4.Cu" "In6.Cu")
		(net 23)
	)
	(via
		(at 134.25 87.5)
		(size 0.45)
		(drill 0.2)
		(layers "F.Cu" "B.Cu")
		(remove_unused_layers yes)
		(keep_end_layers yes)
		(zone_layer_connections "In1.Cu" "In4.Cu" "In6.Cu")
		(net 23)
	)
	(via
		(at 119.25 113.16)
		(size 0.45)
		(drill 0.2)
		(layers "F.Cu" "B.Cu")
		(remove_unused_layers yes)
		(keep_end_layers yes)
		(zone_layer_connections "In1.Cu" "In4.Cu" "In6.Cu")
		(net 23)
	)
	(via
		(at 143.55 125.25)
		(size 0.45)
		(drill 0.2)
		(layers "F.Cu" "B.Cu")
		(remove_unused_layers yes)
		(keep_end_layers yes)
		(zone_layer_connections "In1.Cu" "In4.Cu" "In6.Cu")
		(net 23)
	)
	(via
		(at 144.51 88.75)
		(size 0.45)
		(drill 0.2)
		(layers "F.Cu" "B.Cu")
		(remove_unused_layers yes)
		(keep_end_layers yes)
		(zone_layer_connections "In1.Cu" "In4.Cu")
		(net 23)
	)
	(via
		(at 132.898281 91.396601)
		(size 0.45)
		(drill 0.2)
		(layers "F.Cu" "B.Cu")
		(remove_unused_layers yes)
		(keep_end_layers yes)
		(zone_layer_connections "In1.Cu" "In4.Cu" "In6.Cu")
		(net 23)
	)
	(via
		(at 126.6 141)
		(size 0.45)
		(drill 0.2)
		(layers "F.Cu" "B.Cu")
		(remove_unused_layers yes)
		(keep_end_layers yes)
		(zone_layer_connections "In1.Cu" "In4.Cu" "In6.Cu")
		(net 23)
	)
	(via
		(at 150.3 109.15)
		(size 0.45)
		(drill 0.2)
		(layers "F.Cu" "B.Cu")
		(remove_unused_layers yes)
		(keep_end_layers yes)
		(zone_layer_connections "In1.Cu" "In4.Cu" "In6.Cu")
		(net 23)
	)
	(via
		(at 141.915 85.25)
		(size 0.45)
		(drill 0.2)
		(layers "F.Cu" "B.Cu")
		(remove_unused_layers yes)
		(keep_end_layers yes)
		(zone_layer_connections "In1.Cu" "In4.Cu" "In6.Cu")
		(net 23)
	)
	(via
		(at 160.65 50.75)
		(size 0.45)
		(drill 0.2)
		(layers "F.Cu" "B.Cu")
		(remove_unused_layers yes)
		(keep_end_layers yes)
		(zone_layer_connections "In1.Cu" "In4.Cu" "In6.Cu")
		(net 23)
	)
	(via
		(at 121.2 89)
		(size 0.45)
		(drill 0.2)
		(layers "F.Cu" "B.Cu")
		(remove_unused_layers yes)
		(keep_end_layers yes)
		(zone_layer_connections "In1.Cu" "In4.Cu" "In6.Cu")
		(net 23)
	)
	(via
		(at 135.75 78.85)
		(size 0.45)
		(drill 0.2)
		(layers "F.Cu" "B.Cu")
		(remove_unused_layers yes)
		(keep_end_layers yes)
		(zone_layer_connections "In1.Cu" "In4.Cu" "In6.Cu")
		(net 23)
	)
	(via
		(at 124.7 94.6)
		(size 0.45)
		(drill 0.2)
		(layers "F.Cu" "B.Cu")
		(remove_unused_layers yes)
		(keep_end_layers yes)
		(zone_layer_connections "In1.Cu" "In4.Cu" "In6.Cu")
		(net 23)
	)
	(via
		(at 162.8 45.8)
		(size 0.45)
		(drill 0.2)
		(layers "F.Cu" "B.Cu")
		(remove_unused_layers yes)
		(keep_end_layers yes)
		(zone_layer_connections "In1.Cu" "In4.Cu" "In6.Cu")
		(net 23)
	)
	(via
		(at 144.2 102.5)
		(size 0.45)
		(drill 0.2)
		(layers "F.Cu" "B.Cu")
		(remove_unused_layers yes)
		(keep_end_layers yes)
		(zone_layer_connections "In1.Cu" "In4.Cu" "In6.Cu")
		(net 23)
	)
	(via
		(at 153.18 76.75)
		(size 0.45)
		(drill 0.2)
		(layers "F.Cu" "B.Cu")
		(remove_unused_layers yes)
		(keep_end_layers yes)
		(zone_layer_connections "In1.Cu" "In4.Cu")
		(net 23)
	)
	(via
		(at 162.5 105.5)
		(size 0.45)
		(drill 0.2)
		(layers "F.Cu" "B.Cu")
		(remove_unused_layers yes)
		(keep_end_layers yes)
		(zone_layer_connections "In1.Cu" "In4.Cu" "In6.Cu")
		(net 23)
	)
	(via
		(at 158.9 98.2)
		(size 0.45)
		(drill 0.2)
		(layers "F.Cu" "B.Cu")
		(remove_unused_layers yes)
		(keep_end_layers yes)
		(zone_layer_connections "In1.Cu" "In4.Cu" "In6.Cu")
		(net 23)
	)
	(via
		(at 115.797488 123.6)
		(size 0.45)
		(drill 0.2)
		(layers "F.Cu" "B.Cu")
		(remove_unused_layers yes)
		(keep_end_layers yes)
		(zone_layer_connections "In1.Cu" "In4.Cu" "In6.Cu")
		(net 23)
	)
	(via
		(at 137 122.15)
		(size 0.45)
		(drill 0.2)
		(layers "F.Cu" "B.Cu")
		(remove_unused_layers yes)
		(keep_end_layers yes)
		(zone_layer_connections "In1.Cu" "In4.Cu" "In6.Cu")
		(net 23)
	)
	(via
		(at 164.75 130.5)
		(size 0.45)
		(drill 0.2)
		(layers "F.Cu" "B.Cu")
		(remove_unused_layers yes)
		(keep_end_layers yes)
		(zone_layer_connections "In1.Cu" "In4.Cu" "In6.Cu")
		(net 23)
	)
	(via
		(at 150.25 106.2)
		(size 0.45)
		(drill 0.2)
		(layers "F.Cu" "B.Cu")
		(remove_unused_layers yes)
		(keep_end_layers yes)
		(zone_layer_connections "In1.Cu" "In4.Cu" "In6.Cu")
		(net 23)
	)
	(via
		(at 160.945 76.25)
		(size 0.45)
		(drill 0.2)
		(layers "F.Cu" "B.Cu")
		(remove_unused_layers yes)
		(keep_end_layers yes)
		(zone_layer_connections "In1.Cu" "In4.Cu" "In6.Cu")
		(net 23)
	)
	(via
		(at 132.6 59.2)
		(size 0.45)
		(drill 0.2)
		(layers "F.Cu" "B.Cu")
		(remove_unused_layers yes)
		(keep_end_layers yes)
		(zone_layer_connections "In1.Cu" "In4.Cu" "In6.Cu")
		(net 23)
	)
	(via
		(at 126.1 141.8)
		(size 0.45)
		(drill 0.2)
		(layers "F.Cu" "B.Cu")
		(remove_unused_layers yes)
		(keep_end_layers yes)
		(zone_layer_connections "In1.Cu" "In4.Cu" "In6.Cu")
		(net 23)
	)
	(via
		(at 156.4 94.9)
		(size 0.45)
		(drill 0.2)
		(layers "F.Cu" "B.Cu")
		(remove_unused_layers yes)
		(keep_end_layers yes)
		(zone_layer_connections "In1.Cu" "In4.Cu")
		(net 23)
	)
	(via
		(at 154.89 85.75)
		(size 0.45)
		(drill 0.2)
		(layers "F.Cu" "B.Cu")
		(remove_unused_layers yes)
		(keep_end_layers yes)
		(zone_layer_connections "In1.Cu" "In4.Cu")
		(net 23)
	)
	(via
		(at 144.51 77.75)
		(size 0.45)
		(drill 0.2)
		(layers "F.Cu" "B.Cu")
		(remove_unused_layers yes)
		(keep_end_layers yes)
		(zone_layer_connections "In1.Cu" "In4.Cu" "In6.Cu")
		(net 23)
	)
	(via
		(at 160.945 72.25)
		(size 0.45)
		(drill 0.2)
		(layers "F.Cu" "B.Cu")
		(remove_unused_layers yes)
		(keep_end_layers yes)
		(zone_layer_connections "In1.Cu" "In4.Cu" "In6.Cu")
		(net 23)
	)
	(via
		(at 120.37 108.9)
		(size 0.45)
		(drill 0.2)
		(layers "F.Cu" "B.Cu")
		(remove_unused_layers yes)
		(keep_end_layers yes)
		(zone_layer_connections "In1.Cu" "In4.Cu" "In6.Cu")
		(net 23)
	)
	(via
		(at 160.08 86.75)
		(size 0.45)
		(drill 0.2)
		(layers "F.Cu" "B.Cu")
		(remove_unused_layers yes)
		(keep_end_layers yes)
		(zone_layer_connections "In1.Cu" "In4.Cu" "In6.Cu")
		(net 23)
	)
	(via
		(at 138.3 112.2)
		(size 0.45)
		(drill 0.2)
		(layers "F.Cu" "B.Cu")
		(remove_unused_layers yes)
		(keep_end_layers yes)
		(zone_layer_connections "In1.Cu" "In4.Cu" "In6.Cu")
		(net 23)
	)
	(via
		(at 128.175 122.325)
		(size 0.45)
		(drill 0.2)
		(layers "F.Cu" "B.Cu")
		(remove_unused_layers yes)
		(keep_end_layers yes)
		(zone_layer_connections "In1.Cu" "In4.Cu" "In6.Cu")
		(net 23)
	)
	(via
		(at 147.97 80.75)
		(size 0.45)
		(drill 0.2)
		(layers "F.Cu" "B.Cu")
		(remove_unused_layers yes)
		(keep_end_layers yes)
		(zone_layer_connections "In1.Cu" "In4.Cu")
		(net 23)
	)
	(via
		(at 153.16 79.75)
		(size 0.45)
		(drill 0.2)
		(layers "F.Cu" "B.Cu")
		(remove_unused_layers yes)
		(keep_end_layers yes)
		(zone_layer_connections "In1.Cu" "In4.Cu")
		(net 23)
	)
	(via
		(at 145.375 72.25)
		(size 0.45)
		(drill 0.2)
		(layers "F.Cu" "B.Cu")
		(remove_unused_layers yes)
		(keep_end_layers yes)
		(zone_layer_connections "In1.Cu" "In4.Cu" "In6.Cu")
		(net 23)
	)
	(via
		(at 135 115.5)
		(size 0.45)
		(drill 0.2)
		(layers "F.Cu" "B.Cu")
		(remove_unused_layers yes)
		(keep_end_layers yes)
		(zone_layer_connections "In1.Cu" "In4.Cu" "In6.Cu")
		(net 23)
	)
	(via
		(at 143.6 96.6)
		(size 0.45)
		(drill 0.2)
		(layers "F.Cu" "B.Cu")
		(remove_unused_layers yes)
		(keep_end_layers yes)
		(zone_layer_connections "In1.Cu" "In4.Cu" "In6.Cu")
		(net 23)
	)
	(via
		(at 127.6 91.8)
		(size 0.45)
		(drill 0.2)
		(layers "F.Cu" "B.Cu")
		(remove_unused_layers yes)
		(keep_end_layers yes)
		(zone_layer_connections "In1.Cu" "In4.Cu" "In6.Cu")
		(net 23)
	)
	(via
		(at 127.8 129.55)
		(size 0.45)
		(drill 0.2)
		(layers "F.Cu" "B.Cu")
		(remove_unused_layers yes)
		(keep_end_layers yes)
		(zone_layer_connections "In1.Cu" "In4.Cu" "In6.Cu")
		(net 23)
	)
	(via
		(at 129.5 121.65)
		(size 0.45)
		(drill 0.2)
		(layers "F.Cu" "B.Cu")
		(remove_unused_layers yes)
		(keep_end_layers yes)
		(zone_layer_connections "In1.Cu" "In4.Cu" "In6.Cu")
		(net 23)
	)
	(via
		(at 149.7 127.1)
		(size 0.45)
		(drill 0.2)
		(layers "F.Cu" "B.Cu")
		(remove_unused_layers yes)
		(keep_end_layers yes)
		(zone_layer_connections "In1.Cu" "In4.Cu" "In6.Cu")
		(net 23)
	)
	(via
		(at 151.2 55.6)
		(size 0.45)
		(drill 0.2)
		(layers "F.Cu" "B.Cu")
		(remove_unused_layers yes)
		(keep_end_layers yes)
		(zone_layer_connections "In1.Cu" "In4.Cu" "In6.Cu")
		(net 23)
	)
	(via
		(at 136.9 128.7)
		(size 0.45)
		(drill 0.2)
		(layers "F.Cu" "B.Cu")
		(remove_unused_layers yes)
		(keep_end_layers yes)
		(zone_layer_connections "In1.Cu" "In4.Cu" "In6.Cu")
		(net 23)
	)
	(via
		(at 156.62 87.75)
		(size 0.45)
		(drill 0.2)
		(layers "F.Cu" "B.Cu")
		(remove_unused_layers yes)
		(keep_end_layers yes)
		(zone_layer_connections "In1.Cu" "In4.Cu")
		(net 23)
	)
	(via
		(at 160.08 76.75)
		(size 0.45)
		(drill 0.2)
		(layers "F.Cu" "B.Cu")
		(remove_unused_layers yes)
		(keep_end_layers yes)
		(zone_layer_connections "In1.Cu" "In4.Cu" "In6.Cu")
		(net 23)
	)
	(via
		(at 145.375 90.25)
		(size 0.45)
		(drill 0.2)
		(layers "F.Cu" "B.Cu")
		(remove_unused_layers yes)
		(keep_end_layers yes)
		(zone_layer_connections "In1.Cu" "In4.Cu")
		(net 23)
	)
	(via
		(at 130.970694 95.823662)
		(size 0.45)
		(drill 0.2)
		(layers "F.Cu" "B.Cu")
		(remove_unused_layers yes)
		(keep_end_layers yes)
		(zone_layer_connections "In1.Cu" "In4.Cu" "In6.Cu")
		(net 23)
	)
	(via
		(at 138.97143 99.3)
		(size 0.45)
		(drill 0.2)
		(layers "F.Cu" "B.Cu")
		(remove_unused_layers yes)
		(keep_end_layers yes)
		(zone_layer_connections "In1.Cu" "In4.Cu" "In6.Cu")
		(net 23)
	)
	(via
		(at 128.489999 116.655001)
		(size 0.45)
		(drill 0.2)
		(layers "F.Cu" "B.Cu")
		(remove_unused_layers yes)
		(keep_end_layers yes)
		(zone_layer_connections "In1.Cu" "In4.Cu" "In6.Cu")
		(net 23)
	)
	(via
		(at 144.9 127.5)
		(size 0.45)
		(drill 0.2)
		(layers "F.Cu" "B.Cu")
		(remove_unused_layers yes)
		(keep_end_layers yes)
		(zone_layer_connections "In1.Cu" "In4.Cu" "In6.Cu")
		(net 23)
	)
	(via
		(at 161.9 93.4)
		(size 0.45)
		(drill 0.2)
		(layers "F.Cu" "B.Cu")
		(remove_unused_layers yes)
		(keep_end_layers yes)
		(zone_layer_connections "In1.Cu" "In4.Cu" "In6.Cu")
		(net 23)
	)
	(via
		(at 173.620002 145.42)
		(size 0.45)
		(drill 0.2)
		(layers "F.Cu" "B.Cu")
		(remove_unused_layers yes)
		(keep_end_layers yes)
		(zone_layer_connections "In1.Cu" "In4.Cu" "In6.Cu")
		(net 23)
	)
	(via
		(at 127.2 141)
		(size 0.45)
		(drill 0.2)
		(layers "F.Cu" "B.Cu")
		(remove_unused_layers yes)
		(keep_end_layers yes)
		(zone_layer_connections "In1.Cu" "In4.Cu" "In6.Cu")
		(net 23)
	)
	(via
		(at 157.485 83.25)
		(size 0.45)
		(drill 0.2)
		(layers "F.Cu" "B.Cu")
		(remove_unused_layers yes)
		(keep_end_layers yes)
		(zone_layer_connections "In1.Cu" "In4.Cu" "In6.Cu")
		(net 23)
	)
	(via
		(at 135.34 106.2)
		(size 0.45)
		(drill 0.2)
		(layers "F.Cu" "B.Cu")
		(remove_unused_layers yes)
		(keep_end_layers yes)
		(zone_layer_connections "In1.Cu" "In4.Cu" "In6.Cu")
		(net 23)
	)
	(segment
		(start 128.175 122.325)
		(end 128.345 122.325)
		(width 0.25)
		(layer "B.Cu")
		(net 23)
	)
	(segment
		(start 127.8 144.88)
		(end 128.58 144.88)
		(width 0.25)
		(layer "B.Cu")
		(net 23)
	)
	(segment
		(start 128.499999 127.355)
		(end 128.499999 127.850001)
		(width 0.25)
		(layer "B.Cu")
		(net 23)
	)
	(segment
		(start 128.489997 117.629999)
		(end 128.489997 118.609998)
		(width 0.25)
		(layer "B.Cu")
		(net 23)
	)
	(segment
		(start 178.998 67.348)
		(end 179.752 67.348)
		(width 0.1)
		(layer "B.Cu")
		(net 23)
	)
	(segment
		(start 166.52 136)
		(end 165.75 136)
		(width 0.25)
		(layer "B.Cu")
		(net 23)
	)
	(segment
		(start 137.98 127.98)
		(end 138.7 128.7)
		(width 0.1)
		(layer "B.Cu")
		(net 23)
	)
	(segment
		(start 121.7 144.2)
		(end 121.9 144)
		(width 0.25)
		(layer "B.Cu")
		(net 23)
	)
	(segment
		(start 163.249 138.749)
		(end 163.25 138.75)
		(width 0.25)
		(layer "B.Cu")
		(net 23)
	)
	(segment
		(start 117.95 143.55)
		(end 118.25 143.25)
		(width 0.25)
		(layer "B.Cu")
		(net 23)
	)
	(segment
		(start 131.425 121.52)
		(end 131.424998 121.520002)
		(width 0.25)
		(layer "B.Cu")
		(net 23)
	)
	(segment
		(start 150.681866 92.965116)
		(end 150.681866 93.431866)
		(width 0.1)
		(layer "B.Cu")
		(net 23)
	)
	(segment
		(start 138.830001 136.599999)
		(end 138.830001 137.599998)
		(width 0.25)
		(layer "B.Cu")
		(net 23)
	)
	(segment
		(start 148.88 88.21)
		(end 148.84 88.25)
		(width 0.3)
		(layer "B.Cu")
		(net 23)
	)
	(segment
		(start 144.52 73.745)
		(end 144.515 73.75)
		(width 0.5)
		(layer "B.Cu")
		(net 23)
	)
	(segment
		(start 139.4 105.48)
		(end 139.4 105.5)
		(width 0.1)
		(layer "B.Cu")
		(net 23)
	)
	(segment
		(start 144.52 136)
		(end 143.75 136)
		(width 0.25)
		(layer "B.Cu")
		(net 23)
	)
	(segment
		(start 129.474999 126.38)
		(end 129.475 126.875)
		(width 0.25)
		(layer "B.Cu")
		(net 23)
	)
	(segment
		(start 140.119998 115.100002)
		(end 140.12 115.1)
		(width 0.25)
		(layer "B.Cu")
		(net 23)
	)
	(segment
		(start 135.25 136.25)
		(end 135.25 136.159998)
		(width 0.25)
		(layer "B.Cu")
		(net 23)
	)
	(segment
		(start 143.52 133.25)
		(end 143.52 133.98)
		(width 0.25)
		(layer "B.Cu")
		(net 23)
	)
	(segment
		(start 126.8 141.82)
		(end 126.12 141.82)
		(width 0.25)
		(layer "B.Cu")
		(net 23)
	)
	(segment
		(start 159.28 75.75)
		(end 159.22 75.69)
		(width 0.5)
		(layer "B.Cu")
		(net 23)
	)
	(segment
		(start 135.850001 132.62)
		(end 135.850001 132.600001)
		(width 0.25)
		(layer "B.Cu")
		(net 23)
	)
	(segment
		(start 116.629999 89.270001)
		(end 116.6 89.3)
		(width 0.1)
		(layer "B.Cu")
		(net 23)
	)
	(segment
		(start 135.25 136.159998)
		(end 135.840001 135.569997)
		(width 0.25)
		(layer "B.Cu")
		(net 23)
	)
	(segment
		(start 178.998 71.702)
		(end 179 71.7)
		(width 0.1)
		(layer "B.Cu")
		(net 23)
	)
	(segment
		(start 152.52 83.175)
		(end 152.52 86.03)
		(width 0.1)
		(layer "B.Cu")
		(net 23)
	)
	(segment
		(start 153.8 90.155)
		(end 153.57 90.155)
		(width 0.3)
		(layer "B.Cu")
		(net 23)
	)
	(segment
		(start 118.85 93.65)
		(end 118.9 93.7)
		(width 0.1)
		(layer "B.Cu")
		(net 23)
	)
	(segment
		(start 134.850002 131.599998)
		(end 134.85 131.6)
		(width 0.25)
		(layer "B.Cu")
		(net 23)
	)
	(segment
		(start 162.991867 69.98)
		(end 162.991867 70.408133)
		(width 0.1)
		(layer "B.Cu")
		(net 23)
	)
	(segment
		(start 126.875 126.875)
		(end 126.875 126.68)
		(width 0.25)
		(layer "B.Cu")
		(net 23)
	)
	(segment
		(start 149.7 76.025)
		(end 149.7 75.925)
		(width 0.2)
		(layer "B.Cu")
		(net 23)
	)
	(segment
		(start 138.929999 117.7)
		(end 138.929999 117.15)
		(width 0.25)
		(layer "B.Cu")
		(net 23)
	)
	(segment
		(start 122.199 76.699)
		(end 122.25 76.75)
		(width 0.5)
		(layer "B.Cu")
		(net 23)
	)
	(segment
		(start 121.1 151.2)
		(end 120.42 151.2)
		(width 0.25)
		(layer "B.Cu")
		(net 23)
	)
	(segment
		(start 134.591421 131.158579)
		(end 134.052842 130.62)
		(width 0.1)
		(layer "B.Cu")
		(net 23)
	)
	(segment
		(start 138.930001 115.100002)
		(end 138.930001 117.149998)
		(width 0.25)
		(layer "B.Cu")
		(net 23)
	)
	(segment
		(start 138.830001 137.599998)
		(end 138.83 137.599999)
		(width 0.25)
		(layer "B.Cu")
		(net 23)
	)
	(segment
		(start 147.93 81.83)
		(end 147.93 81.25)
		(width 0.15)
		(layer "B.Cu")
		(net 23)
	)
	(segment
		(start 123.779998 123.625)
		(end 123.624999 123.470001)
		(width 0.25)
		(layer "B.Cu")
		(net 23)
	)
	(segment
		(start 153.57 90.155)
		(end 153.165 89.75)
		(width 0.3)
		(layer "B.Cu")
		(net 23)
	)
	(segment
		(start 162.991867 70.408133)
		(end 162.6 70.8)
		(width 0.1)
		(layer "B.Cu")
		(net 23)
	)
	(segment
		(start 175.6 146.2)
		(end 175.620002 146.179998)
		(width 0.1)
		(layer "B.Cu")
		(net 23)
	)
	(segment
		(start 137.98 126.6)
		(end 137.98 127.98)
		(width 0.1)
		(layer "B.Cu")
		(net 23)
	)
	(segment
		(start 151.6 146.159998)
		(end 151.6 145.4)
		(width 0.1)
		(layer "B.Cu")
		(net 23)
	)
	(segment
		(start 128.489999 119.123999)
		(end 128.5 119.134)
		(width 0.25)
		(layer "B.Cu")
		(net 23)
	)
	(segment
		(start 122.199 80.301)
		(end 122.25 80.25)
		(width 0.5)
		(layer "B.Cu")
		(net 23)
	)
	(segment
		(start 131.26 119.134)
		(end 130.885999 119.134)
		(width 0.25)
		(layer "B.Cu")
		(net 23)
	)
	(segment
		(start 125.409 119.471)
		(end 125.74 119.14)
		(width 0.25)
		(layer "B.Cu")
		(net 23)
	)
	(segment
		(start 120.5 94)
		(end 120.5 94.73)
		(width 0.1)
		(layer "B.Cu")
		(net 23)
	)
	(segment
		(start 129.88 119.81)
		(end 130.209999 119.81)
		(width 0.25)
		(layer "B.Cu")
		(net 23)
	)
	(segment
		(start 182.53 133.25)
		(end 183.25 133.25)
		(width 0.25)
		(layer "B.Cu")
		(net 23)
	)
	(segment
		(start 125.385 75.735)
		(end 125.4 75.75)
		(width 0.25)
		(layer "B.Cu")
		(net 23)
	)
	(segment
		(start 126.654 77)
		(end 126.65 77)
		(width 0.25)
		(layer "B.Cu")
		(net 23)
	)
	(segment
		(start 150.181866 97.101866)
		(end 149.95 96.87)
		(width 0.25)
		(layer "B.Cu")
		(net 23)
	)
	(segment
		(start 142.98 119.2)
		(end 142.98 118.174998)
		(width 0.25)
		(layer "B.Cu")
		(net 23)
	)
	(segment
		(start 148.82 82.25)
		(end 148.35 82.25)
		(width 0.15)
		(layer "B.Cu")
		(net 23)
	)
	(segment
		(start 148.011866 68.238134)
		(end 148.95 67.3)
		(width 0.1)
		(layer "B.Cu")
		(net 23)
	)
	(segment
		(start 126.875 127.045)
		(end 126.569999 127.350001)
		(width 0.25)
		(layer "B.Cu")
		(net 23)
	)
	(segment
		(start 163.73 129.25)
		(end 164.5 129.25)
		(width 0.25)
		(layer "B.Cu")
		(net 23)
	)
	(segment
		(start 159.22 75.81)
		(end 159.28 75.75)
		(width 0.5)
		(layer "B.Cu")
		(net 23)
	)
	(segment
		(start 180.32 69.12)
		(end 180.3 69.1)
		(width 0.1)
		(layer "B.Cu")
		(net 23)
	)
	(segment
		(start 128.920001 117.629999)
		(end 129.25 117.3)
		(width 0.25)
		(layer "B.Cu")
		(net 23)
	)
	(segment
		(start 135.88 138.04)
		(end 135.88 138.209109)
		(width 0.25)
		(layer "B.Cu")
		(net 23)
	)
	(segment
		(start 128.489997 116.655003)
		(end 128.489999 116.655001)
		(width 0.25)
		(layer "B.Cu")
		(net 23)
	)
	(segment
		(start 117.500002 89.270001)
		(end 116.629999 89.270001)
		(width 0.1)
		(layer "B.Cu")
		(net 23)
	)
	(segment
		(start 135.850001 132.600001)
		(end 135.85 132.6)
		(width 0.25)
		(layer "B.Cu")
		(net 23)
	)
	(segment
		(start 117.8 143.55)
		(end 117.95 143.55)
		(width 0.25)
		(layer "B.Cu")
		(net 23)
	)
	(segment
		(start 126.875 121.675)
		(end 127.369998 121.675)
		(width 0.25)
		(layer "B.Cu")
		(net 23)
	)
	(segment
		(start 124.78 149.77)
		(end 125 149.55)
		(width 0.25)
		(layer "B.Cu")
		(net 23)
	)
	(segment
		(start 148.011866 69.535117)
		(end 148.011866 68.238134)
		(width 0.1)
		(layer "B.Cu")
		(net 23)
	)
	(segment
		(start 128.489997 117.629999)
		(end 128.920001 117.629999)
		(width 0.25)
		(layer "B.Cu")
		(net 23)
	)
	(segment
		(start 178.998 74.202)
		(end 179 74.2)
		(width 0.1)
		(layer "B.Cu")
		(net 23)
	)
	(segment
		(start 121.601 150.6)
		(end 121.601 150.699)
		(width 0.25)
		(layer "B.Cu")
		(net 23)
	)
	(segment
		(start 124.116 125.33)
		(end 124.499997 125.33)
		(width 0.25)
		(layer "B.Cu")
		(net 23)
	)
	(segment
		(start 160.6 139.25)
		(end 161.75 139.25)
		(width 0.25)
		(layer "B.Cu")
		(net 23)
	)
	(segment
		(start 135.25 137.25)
		(end 134.75 137.25)
		(width 0.25)
		(layer "B.Cu")
		(net 23)
	)
	(segment
		(start 122.199 76)
		(end 122.199 76.699)
		(width 0.5)
		(layer "B.Cu")
		(net 23)
	)
	(segment
		(start 118.85 93.127)
		(end 118.85 93.65)
		(width 0.1)
		(layer "B.Cu")
		(net 23)
	)
	(segment
		(start 132.075 121.675)
		(end 131.425 121.675)
		(width 0.25)
		(layer "B.Cu")
		(net 23)
	)
	(segment
		(start 125.385 75.73)
		(end 125.385 75.735)
		(width 0.25)
		(layer "B.Cu")
		(net 23)
	)
	(segment
		(start 126.219998 119.461002)
		(end 126.061002 119.461002)
		(width 0.25)
		(layer "B.Cu")
		(net 23)
	)
	(segment
		(start 149.681866 92.965117)
		(end 149.681866 93.681866)
		(width 0.1)
		(layer "B.Cu")
		(net 23)
	)
	(segment
		(start 134.850002 132.62)
		(end 134.850002 132.600002)
		(width 0.25)
		(layer "B.Cu")
		(net 23)
	)
	(segment
		(start 149.7 75.925)
		(end 149.65 75.875)
		(width 0.2)
		(layer "B.Cu")
		(net 23)
	)
	(segment
		(start 171.600002 145.64)
		(end 171.600002 146.2)
		(width 0.1)
		(layer "B.Cu")
		(net 23)
	)
	(segment
		(start 116.4 110.451)
		(end 116.4 109.8)
		(width 0.1)
		(layer "B.Cu")
		(net 23)
	)
	(segment
		(start 162.77 133.25)
		(end 162 133.25)
		(width 0.25)
		(layer "B.Cu")
		(net 23)
	)
	(segment
		(start 136.13 138.04)
		(end 136.48 137.69)
		(width 0.25)
		(layer "B.Cu")
		(net 23)
	)
	(segment
		(start 132.760002 132.619999)
		(end 132.169999 132.619999)
		(width 0.25)
		(layer "B.Cu")
		(net 23)
	)
	(segment
		(start 130.604998 121.675)
		(end 130.449999 121.520001)
		(width 0.25)
		(layer "B.Cu")
		(net 23)
	)
	(segment
		(start 135.25 136.25)
		(end 134.75 136.25)
		(width 0.25)
		(layer "B.Cu")
		(net 23)
	)
	(segment
		(start 135.774004 135.504)
		(end 135.840001 135.569997)
		(width 0.25)
		(layer "B.Cu")
		(net 23)
	)
	(segment
		(start 140.12 116.124998)
		(end 140.120001 116.124999)
		(width 0.25)
		(layer "B.Cu")
		(net 23)
	)
	(segment
		(start 148.35 82.25)
		(end 147.93 81.83)
		(width 0.15)
		(layer "B.Cu")
		(net 23)
	)
	(segment
		(start 149.58 145.62)
		(end 149.58 146.18)
		(width 0.1)
		(layer "B.Cu")
		(net 23)
	)
	(segment
		(start 140.12 115.1)
		(end 140.12 116.124998)
		(width 0.25)
		(layer "B.Cu")
		(net 23)
	)
	(segment
		(start 179.752 67.348)
		(end 179.8 67.3)
		(width 0.1)
		(layer "B.Cu")
		(net 23)
	)
	(segment
		(start 127.090001 119.570001)
		(end 126.66 119.14)
		(width 0.25)
		(layer "B.Cu")
		(net 23)
	)
	(segment
		(start 134.75 136.75)
		(end 135.25 136.75)
		(width 0.25)
		(layer "B.Cu")
		(net 23)
	)
	(segment
		(start 140.120002 118.174998)
		(end 140.120002 118.170002)
		(width 0.25)
		(layer "B.Cu")
		(net 23)
	)
	(segment
		(start 148.82 75.31)
		(end 148.82 75.275)
		(width 0.2)
		(layer "B.Cu")
		(net 23)
	)
	(segment
		(start 130.449999 128.33)
		(end 130.449999 128.900001)
		(width 0.25)
		(layer "B.Cu")
		(net 23)
	)
	(segment
		(start 129.42 119.515002)
		(end 129.474998 119.57)
		(width 0.25)
		(layer "B.Cu")
		(net 23)
	)
	(segment
		(start 150.181866 97.5)
		(end 150.181866 97.101866)
		(width 0.25)
		(layer "B.Cu")
		(net 23)
	)
	(segment
		(start 126.8 144.88)
		(end 127.8 144.88)
		(width 0.25)
		(layer "B.Cu")
		(net 23)
	)
	(segment
		(start 122.199 81.1)
		(end 122.199 80.301)
		(width 0.5)
		(layer "B.Cu")
		(net 23)
	)
	(segment
		(start 144.52 73.25)
		(end 144.52 73.745)
		(width 0.5)
		(layer "B.Cu")
		(net 23)
	)
	(segment
		(start 134.850002 131.579998)
		(end 134.850002 131.599998)
		(width 0.25)
		(layer "B.Cu")
		(net 23)
	)
	(segment
		(start 125.625 127.38)
		(end 126.54 127.38)
		(width 0.25)
		(layer "B.Cu")
		(net 23)
	)
	(segment
		(start 126.061002 119.461002)
		(end 125.74 119.14)
		(width 0.25)
		(layer "B.Cu")
		(net 23)
	)
	(segment
		(start 134.75 137.25)
		(end 134.75 136.25)
		(width 0.25)
		(layer "B.Cu")
		(net 23)
	)
	(segment
		(start 159.22 75.69)
		(end 159.22 75.25)
		(width 0.5)
		(layer "B.Cu")
		(net 23)
	)
	(segment
		(start 126.654 89)
		(end 126.65 89)
		(width 0.1)
		(layer "B.Cu")
		(net 23)
	)
	(segment
		(start 123.5 144.62)
		(end 123.5 144)
		(width 0.25)
		(layer "B.Cu")
		(net 23)
	)
	(segment
		(start 124.744997 125.575)
		(end 124.594998 125.425001)
		(width 0.25)
		(layer "B.Cu")
		(net 23)
	)
	(segment
		(start 178.998 69.202)
		(end 179 69.2)
		(width 0.1)
		(layer "B.Cu")
		(net 23)
	)
	(segment
		(start 126.875 126.68)
		(end 126.57 126.375)
		(width 0.25)
		(layer "B.Cu")
		(net 23)
	)
	(segment
		(start 130.338 119.457999)
		(end 130.45 119.569999)
		(width 0.25)
		(layer "B.Cu")
		(net 23)
	)
	(segment
		(start 134.75 136.25)
		(end 134.75 135.659998)
		(width 0.25)
		(layer "B.Cu")
		(net 23)
	)
	(segment
		(start 130.338 118.493)
		(end 130.338 119.457999)
		(width 0.25)
		(layer "B.Cu")
		(net 23)
	)
	(segment
		(start 162.58 105.5)
		(end 162.5 105.5)
		(width 0.1)
		(layer "B.Cu")
		(net 23)
	)
	(segment
		(start 148.88 87.925)
		(end 148.88 88.21)
		(width 0.3)
		(layer "B.Cu")
		(net 23)
	)
	(segment
		(start 134.6 114.5726)
		(end 134.23 114.9426)
		(width 0.1)
		(layer "B.Cu")
		(net 23)
	)
	(segment
		(start 126.654 79.546)
		(end 126.65 79.55)
		(width 0.25)
		(layer "B.Cu")
		(net 23)
	)
	(segment
		(start 144.52 71.25)
		(end 144.52 71.745)
		(width 0.5)
		(layer "B.Cu")
		(net 23)
	)
	(segment
		(start 144.52 73.25)
		(end 144.52 72.755)
		(width 0.5)
		(layer "B.Cu")
		(net 23)
	)
	(segment
		(start 136.080001 126.604998)
		(end 136.080001 128.419999)
		(width 0.1)
		(layer "B.Cu")
		(net 23)
	)
	(segment
		(start 160.53 133.25)
		(end 161.25 133.25)
		(width 0.25)
		(layer "B.Cu")
		(net 23)
	)
	(segment
		(start 117.5 143.25)
		(end 117.8 143.55)
		(width 0.25)
		(layer "B.Cu")
		(net 23)
	)
	(segment
		(start 138.930001 117.149998)
		(end 138.929999 117.15)
		(width 0.25)
		(layer "B.Cu")
		(net 23)
	)
	(segment
		(start 124.68 125.33)
		(end 124.925 125.575)
		(width 0.25)
		(layer "B.Cu")
		(net 23)
	)
	(segment
		(start 149.705 76.03)
		(end 149.7 76.025)
		(width 0.2)
		(layer "B.Cu")
		(net 23)
	)
	(segment
		(start 134.850002 132.600002)
		(end 134.85 132.6)
		(width 0.25)
		(layer "B.Cu")
		(net 23)
	)
	(segment
		(start 163.95 130.5)
		(end 164.75 130.5)
		(width 0.25)
		(layer "B.Cu")
		(net 23)
	)
	(segment
		(start 131.425 121.025)
		(end 131.425 121.52)
		(width 0.25)
		(layer "B.Cu")
		(net 23)
	)
	(segment
		(start 124.78 150.6)
		(end 124.78 149.77)
		(width 0.25)
		(layer "B.Cu")
		(net 23)
	)
	(segment
		(start 136.98 122.15)
		(end 137 122.15)
		(width 0.25)
		(layer "B.Cu")
		(net 23)
	)
	(segment
		(start 126.338998 119.461002)
		(end 126.66 119.14)
		(width 0.25)
		(layer "B.Cu")
		(net 23)
	)
	(segment
		(start 149.681866 93.681866)
		(end 150 94)
		(width 0.1)
		(layer "B.Cu")
		(net 23)
	)
	(segment
		(start 126.875 126.875)
		(end 126.875 127.045)
		(width 0.25)
		(layer "B.Cu")
		(net 23)
	)
	(segment
		(start 132.860001 132.52)
		(end 132.760002 132.619999)
		(width 0.25)
		(layer "B.Cu")
		(net 23)
	)
	(segment
		(start 151.58 146.179998)
		(end 151.6 146.159998)
		(width 0.1)
		(layer "B.Cu")
		(net 23)
	)
	(segment
		(start 134.850002 131.579998)
		(end 134.829998 131.579998)
		(width 0.1)
		(layer "B.Cu")
		(net 23)
	)
	(segment
		(start 130.9 131.58)
		(end 130.9 131.6)
		(width 0.1)
		(layer "B.Cu")
		(net 23)
	)
	(segment
		(start 128.345 122.325)
		(end 128.5 122.48)
		(width 0.25)
		(layer "B.Cu")
		(net 23)
	)
	(segment
		(start 138.830001 134.380001)
		(end 138.8 134.35)
		(width 0.25)
		(layer "B.Cu")
		(net 23)
	)
	(segment
		(start 146 105.48)
		(end 146 105.5)
		(width 0.1)
		(layer "B.Cu")
		(net 23)
	)
	(segment
		(start 138.830001 134.599997)
		(end 138.830001 134.380001)
		(width 0.25)
		(layer "B.Cu")
		(net 23)
	)
	(segment
		(start 129.9 131.58)
		(end 129.9 131.6)
		(width 0.1)
		(layer "B.Cu")
		(net 23)
	)
	(segment
		(start 165.5 139.25)
		(end 164.5 139.25)
		(width 0.25)
		(layer "B.Cu")
		(net 23)
	)
	(segment
		(start 144.52 71.745)
		(end 144.515 71.75)
		(width 0.5)
		(layer "B.Cu")
		(net 23)
	)
	(segment
		(start 130.449999 128.900001)
		(end 130.34 129.01)
		(width 0.25)
		(layer "B.Cu")
		(net 23)
	)
	(segment
		(start 132.169999 132.619999)
		(end 132.15 132.6)
		(width 0.25)
		(layer "B.Cu")
		(net 23)
	)
	(segment
		(start 125.385 87.735)
		(end 125.4 87.75)
		(width 0.1)
		(layer "B.Cu")
		(net 23)
	)
	(segment
		(start 178.998 72.348)
		(end 178.998 71.702)
		(width 0.1)
		(layer "B.Cu")
		(net 23)
	)
	(segment
		(start 154.05 77.23)
		(end 154.03 77.25)
		(width 0.15)
		(layer "B.Cu")
		(net 23)
	)
	(segment
		(start 135.88 138.209109)
		(end 135.761535 138.327574)
		(width 0.25)
		(layer "B.Cu")
		(net 23)
	)
	(segment
		(start 181.73 136)
		(end 182.5 136)
		(width 0.25)
		(layer "B.Cu")
		(net 23)
	)
	(segment
		(start 130.209999 119.81)
		(end 130.45 119.569999)
		(width 0.25)
		(layer "B.Cu")
		(net 23)
	)
	(segment
		(start 125.575 122.975)
		(end 125.575 123.469999)
		(width 0.25)
		(layer "B.Cu")
		(net 23)
	)
	(segment
		(start 178.998 74.898)
		(end 178.998 74.202)
		(width 0.1)
		(layer "B.Cu")
		(net 23)
	)
	(segment
		(start 136.98 115.100001)
		(end 136.980001 115.1)
		(width 0.25)
		(layer "B.Cu")
		(net 23)
	)
	(segment
		(start 128.58 144.88)
		(end 128.6 144.9)
		(width 0.25)
		(layer "B.Cu")
		(net 23)
	)
	(segment
		(start 126.379998 121.675)
		(end 126.224999 121.520001)
		(width 0.25)
		(layer "B.Cu")
		(net 23)
	)
	(segment
		(start 128.5 123.47)
		(end 128.5 122.95)
		(width 0.25)
		(layer "B.Cu")
		(net 23)
	)
	(segment
		(start 136.980001 114.419999)
		(end 137 114.4)
		(width 0.25)
		(layer "B.Cu")
		(net 23)
	)
	(segment
		(start 173.600002 146.199998)
		(end 173.620002 146.179998)
		(width 0.1)
		(layer "B.Cu")
		(net 23)
	)
	(segment
		(start 136.98 124.15)
		(end 136.98 125.15)
		(width 0.25)
		(layer "B.Cu")
		(net 23)
	)
	(segment
		(start 149.6 145.6)
		(end 149.58 145.62)
		(width 0.1)
		(layer "B.Cu")
		(net 23)
	)
	(segment
		(start 128.489997 118.609998)
		(end 128.489999 118.61)
		(width 0.25)
		(layer "B.Cu")
		(net 23)
	)
	(segment
		(start 127.369998 121.675)
		(end 127.524999 121.519999)
		(width 0.25)
		(layer "B.Cu")
		(net 23)
	)
	(segment
		(start 126.654 79.539)
		(end 126.654 79.546)
		(width 0.25)
		(layer "B.Cu")
		(net 23)
	)
	(segment
		(start 126.54 127.38)
		(end 126.569999 127.350001)
		(width 0.25)
		(layer "B.Cu")
		(net 23)
	)
	(segment
		(start 122.27 128.775)
		(end 122.27 128.025001)
		(width 0.25)
		(layer "B.Cu")
		(net 23)
	)
	(segment
		(start 124.116 125.33)
		(end 124.68 125.33)
		(width 0.25)
		(layer "B.Cu")
		(net 23)
	)
	(segment
		(start 134.6 113.4)
		(end 134.6 114.5726)
		(width 0.1)
		(layer "B.Cu")
		(net 23)
	)
	(segment
		(start 173.620002 146.179998)
		(end 173.620002 145.42)
		(width 0.1)
		(layer "B.Cu")
		(net 23)
	)
	(segment
		(start 175.620002 146.179998)
		(end 175.620002 145.42)
		(width 0.1)
		(layer "B.Cu")
		(net 23)
	)
	(segment
		(start 125.385 87.73)
		(end 125.385 87.735)
		(width 0.1)
		(layer "B.Cu")
		(net 23)
	)
	(segment
		(start 124.925 125.575)
		(end 124.744997 125.575)
		(width 0.25)
		(layer "B.Cu")
		(net 23)
	)
	(segment
		(start 128.475 122.975)
		(end 128.5 122.95)
		(width 0.25)
		(layer "B.Cu")
		(net 23)
	)
	(segment
		(start 126.219998 119.461002)
		(end 126.338998 119.461002)
		(width 0.25)
		(layer "B.Cu")
		(net 23)
	)
	(segment
		(start 149.65 75.875)
		(end 149.385 75.875)
		(width 0.2)
		(layer "B.Cu")
		(net 23)
	)
	(segment
		(start 132.075 122.325)
		(end 132.075 121.675)
		(width 0.25)
		(layer "B.Cu")
		(net 23)
	)
	(segment
		(start 126.654 91.539)
		(end 126.654 91.546)
		(width 0.1)
		(layer "B.Cu")
		(net 23)
	)
	(segment
		(start 133.88 135.504)
		(end 135.774004 135.504)
		(width 0.25)
		(layer "B.Cu")
		(net 23)
	)
	(segment
		(start 130.885999 119.134)
		(end 130.45 119.569999)
		(width 0.25)
		(layer "B.Cu")
		(net 23)
	)
	(segment
		(start 152.52 86.03)
		(end 152.3 86.25)
		(width 0.1)
		(layer "B.Cu")
		(net 23)
	)
	(segment
		(start 116.201 110.65)
		(end 116.4 110.451)
		(width 0.1)
		(layer "B.Cu")
		(net 23)
	)
	(segment
		(start 136.980001 115.1)
		(end 136.980001 114.419999)
		(width 0.25)
		(layer "B.Cu")
		(net 23)
	)
	(segment
		(start 120.42 151.2)
		(end 119.82 150.6)
		(width 0.25)
		(layer "B.Cu")
		(net 23)
	)
	(segment
		(start 125.575 123.469999)
		(end 125.574999 123.47)
		(width 0.25)
		(layer "B.Cu")
		(net 23)
	)
	(segment
		(start 126.875 121.675)
		(end 126.379998 121.675)
		(width 0.25)
		(layer "B.Cu")
		(net 23)
	)
	(segment
		(start 138.930001 115.100002)
		(end 140.119998 115.100002)
		(width 0.25)
		(layer "B.Cu")
		(net 23)
	)
	(segment
		(start 156.8 90.925)
		(end 157.48 90.925)
		(width 0.1)
		(layer "B.Cu")
		(net 23)
	)
	(segment
		(start 119.82 150.6)
		(end 119.82 149.87)
		(width 0.25)
		(layer "B.Cu")
		(net 23)
	)
	(segment
		(start 118.25 143.25)
		(end 118.25 142.5)
		(width 0.25)
		(layer "B.Cu")
		(net 23)
	)
	(segment
		(start 142.98 118.174998)
		(end 143.674998 118.174998)
		(width 0.25)
		(layer "B.Cu")
		(net 23)
	)
	(segment
		(start 162.6 105.48)
		(end 162.58 105.5)
		(width 0.1)
		(layer "B.Cu")
		(net 23)
	)
	(segment
		(start 128.345 123.625)
		(end 128.5 123.47)
		(width 0.25)
		(layer "B.Cu")
		(net 23)
	)
	(segment
		(start 134.052842 130.62)
		(end 133.85 130.62)
		(width 0.1)
		(layer "B.Cu")
		(net 23)
	)
	(segment
		(start 131.425 121.675)
		(end 131.425 121.520004)
		(width 0.25)
		(layer "B.Cu")
		(net 23)
	)
	(segment
		(start 153.6 146.159998)
		(end 153.6 145.4)
		(width 0.1)
		(layer "B.Cu")
		(net 23)
	)
	(segment
		(start 140.120002 118.170002)
		(end 140.1 118.15)
		(width 0.25)
		(layer "B.Cu")
		(net 23)
	)
	(segment
		(start 165.62 133.25)
		(end 165 133.25)
		(width 0.25)
		(layer "B.Cu")
		(net 23)
	)
	(segment
		(start 144.52 72.755)
		(end 144.515 72.75)
		(width 0.15)
		(layer "B.Cu")
		(net 23)
	)
	(segment
		(start 128.175 123.625)
		(end 128.345 123.625)
		(width 0.25)
		(layer "B.Cu")
		(net 23)
	)
	(segment
		(start 128.489997 117.629999)
		(end 128.489997 116.655003)
		(width 0.25)
		(layer "B.Cu")
		(net 23)
	)
	(segment
		(start 120.5 94.73)
		(end 120.48 94.75)
		(width 0.1)
		(layer "B.Cu")
		(net 23)
	)
	(segment
		(start 126.654 91.546)
		(end 126.65 91.55)
		(width 0.1)
		(layer "B.Cu")
		(net 23)
	)
	(segment
		(start 183.75 86.25)
		(end 183.75 87.25)
		(width 0.1)
		(layer "B.Cu")
		(net 23)
	)
	(segment
		(start 128.5 122.95)
		(end 128.5 122.48)
		(width 0.25)
		(layer "B.Cu")
		(net 23)
	)
	(segment
		(start 117.5 142.5)
		(end 117.5 143.25)
		(width 0.25)
		(layer "B.Cu")
		(net 23)
	)
	(segment
		(start 171.620002 145.42)
		(end 171.620002 145.62)
		(width 0.1)
		(layer "B.Cu")
		(net 23)
	)
	(segment
		(start 127.524999 119.570001)
		(end 127.090001 119.570001)
		(width 0.25)
		(layer "B.Cu")
		(net 23)
	)
	(segment
		(start 129.42 119.134)
		(end 129.42 119.515002)
		(width 0.25)
		(layer "B.Cu")
		(net 23)
	)
	(segment
		(start 143.674998 118.174998)
		(end 143.7 118.2)
		(width 0.25)
		(layer "B.Cu")
		(net 23)
	)
	(segment
		(start 143.52 133.98)
		(end 143.5 134)
		(width 0.25)
		(layer "B.Cu")
		(net 23)
	)
	(segment
		(start 128.489999 118.61)
		(end 128.489999 119.123999)
		(width 0.25)
		(layer "B.Cu")
		(net 23)
	)
	(segment
		(start 135.88 138.04)
		(end 136.13 138.04)
		(width 0.25)
		(layer "B.Cu")
		(net 23)
	)
	(segment
		(start 178.998 69.848)
		(end 178.998 69.202)
		(width 0.1)
		(layer "B.Cu")
		(net 23)
	)
	(segment
		(start 128.499999 119.570001)
		(end 128.499999 119.134001)
		(width 0.25)
		(layer "B.Cu")
		(net 23)
	)
	(segment
		(start 132.96 132.619999)
		(end 132.860001 132.52)
		(width 0.25)
		(layer "B.Cu")
		(net 23)
	)
	(segment
		(start 154.45 77.23)
		(end 154.05 77.23)
		(width 0.15)
		(layer "B.Cu")
		(net 23)
	)
	(segment
		(start 134.75 135.659998)
		(end 134.840001 135.569997)
		(width 0.25)
		(layer "B.Cu")
		(net 23)
	)
	(segment
		(start 153.579998 146.18)
		(end 153.6 146.159998)
		(width 0.1)
		(layer "B.Cu")
		(net 23)
	)
	(segment
		(start 149.385 75.875)
		(end 148.82 75.31)
		(width 0.2)
		(layer "B.Cu")
		(net 23)
	)
	(segment
		(start 134.829998 131.579998)
		(end 134.591421 131.341421)
		(width 0.1)
		(layer "B.Cu")
		(net 23)
	)
	(segment
		(start 129.64 119.57)
		(end 129.88 119.81)
		(width 0.25)
		(layer "B.Cu")
		(net 23)
	)
	(segment
		(start 119.82 149.87)
		(end 119.5 149.55)
		(width 0.25)
		(layer "B.Cu")
		(net 23)
	)
	(segment
		(start 148.88 87.925)
		(end 148.88 86.925)
		(width 0.3)
		(layer "B.Cu")
		(net 23)
	)
	(segment
		(start 180.32 70)
		(end 180.32 69.12)
		(width 0.1)
		(layer "B.Cu")
		(net 23)
	)
	(segment
		(start 129.474998 119.57)
		(end 129.64 119.57)
		(width 0.25)
		(layer "B.Cu")
		(net 23)
	)
	(segment
		(start 131.425 121.520004)
		(end 131.424998 121.520002)
		(width 0.25)
		(layer "B.Cu")
		(net 23)
	)
	(segment
		(start 122.27 128.025001)
		(end 122.27 127.025)
		(width 0.25)
		(layer "B.Cu")
		(net 23)
	)
	(segment
		(start 159.48 136)
		(end 160.25 136)
		(width 0.25)
		(layer "B.Cu")
		(net 23)
	)
	(segment
		(start 136.98 120.15)
		(end 136.98 115.100001)
		(width 0.25)
		(layer "B.Cu")
		(net 23)
	)
	(segment
		(start 124.275 123.625)
		(end 123.779998 123.625)
		(width 0.25)
		(layer "B.Cu")
		(net 23)
	)
	(segment
		(start 171.620002 145.62)
		(end 171.600002 145.64)
		(width 0.1)
		(layer "B.Cu")
		(net 23)
	)
	(segment
		(start 128.499999 127.850001)
		(end 128.225 128.125)
		(width 0.25)
		(layer "B.Cu")
		(net 23)
	)
	(segment
		(start 130.775 121.675)
		(end 130.604998 121.675)
		(width 0.25)
		(layer "B.Cu")
		(net 23)
	)
	(segment
		(start 125.222 119.471)
		(end 125.409 119.471)
		(width 0.25)
		(layer "B.Cu")
		(net 23)
	)
	(segment
		(start 121.7 144.62)
		(end 121.7 144.2)
		(width 0.25)
		(layer "B.Cu")
		(net 23)
	)
	(segment
		(start 136.080001 128.419999)
		(end 135.8 128.7)
		(width 0.1)
		(layer "B.Cu")
		(net 23)
	)
	(segment
		(start 149.6 145.4)
		(end 149.6 145.6)
		(width 0.1)
		(layer "B.Cu")
		(net 23)
	)
	(segment
		(start 156.625 90.75)
		(end 156.8 90.925)
		(width 0.1)
		(layer "B.Cu")
		(net 23)
	)
	(segment
		(start 132.075 121.025)
		(end 132.075 121.675)
		(width 0.25)
		(layer "B.Cu")
		(net 23)
	)
	(segment
		(start 127.800001 141.82)
		(end 126.8 141.82)
		(width 0.25)
		(layer "B.Cu")
		(net 23)
	)
	(segment
		(start 135.25 137.25)
		(end 135.25 136.25)
		(width 0.25)
		(layer "B.Cu")
		(net 23)
	)
	(segment
		(start 159.22 76.25)
		(end 159.22 75.81)
		(width 0.5)
		(layer "B.Cu")
		(net 23)
	)
	(segment
		(start 124.499997 125.33)
		(end 124.594998 125.425001)
		(width 0.25)
		(layer "B.Cu")
		(net 23)
	)
	(segment
		(start 163.249 137.75)
		(end 163.249 138.749)
		(width 0.25)
		(layer "B.Cu")
		(net 23)
	)
	(segment
		(start 128.175 122.975)
		(end 128.475 122.975)
		(width 0.25)
		(layer "B.Cu")
		(net 23)
	)
	(segment
		(start 133.85 132.619999)
		(end 132.96 132.619999)
		(width 0.25)
		(layer "B.Cu")
		(net 23)
	)
	(segment
		(start 126.12 141.82)
		(end 126.1 141.8)
		(width 0.25)
		(layer "B.Cu")
		(net 23)
	)
	(segment
		(start 127.524999 119.570001)
		(end 128.499999 119.570001)
		(width 0.25)
		(layer "B.Cu")
		(net 23)
	)
	(segment
		(start 134.591421 131.341421)
		(end 134.591421 131.158579)
		(width 0.1)
		(layer "B.Cu")
		(net 23)
	)
	(segment
		(start 150.681866 93.431866)
		(end 151.25 94)
		(width 0.1)
		(layer "B.Cu")
		(net 23)
	)
	(segment
		(start 149.705 76.075)
		(end 149.705 76.03)
		(width 0.2)
		(layer "B.Cu")
		(net 23)
	)
	(segment
		(start 128.499999 119.134001)
		(end 128.5 119.134)
		(width 0.25)
		(layer "B.Cu")
		(net 23)
	)
	(segment
		(start 121.601 150.699)
		(end 121.1 151.2)
		(width 0.25)
		(layer "B.Cu")
		(net 23)
	)
	(segment
		(start 159.43 69.905)
		(end 159.105 69.58)
		(width 0.19)
		(layer "F.Cu")
		(net 24)
	)
	(segment
		(start 159.105 69.58)
		(end 159.105 69.555)
		(width 0.19)
		(layer "F.Cu")
		(net 24)
	)
	(segment
		(start 159.43 70)
		(end 159.43 69.905)
		(width 0.19)
		(layer "F.Cu")
		(net 24)
	)
	(segment
		(start 159.43 70.08)
		(end 159.43 70)
		(width 0.19)
		(layer "F.Cu")
		(net 24)
	)
	(segment
		(start 158.72015 70.48)
		(end 158.72015 70.4)
		(width 0.19)
		(layer "F.Cu")
		(net 24)
	)
	(segment
		(start 159.27 70.64)
		(end 158.88015 70.64)
		(width 0.19)
		(layer "F.Cu")
		(net 24)
	)
	(segment
		(start 158.88015 70.24)
		(end 159.27 70.24)
		(width 0.19)
		(layer "F.Cu")
		(net 24)
	)
	(segment
		(start 159.43 71.044999)
		(end 159.43 70.8)
		(width 0.19)
		(layer "F.Cu")
		(net 24)
	)
	(segment
		(start 159.225 71.249999)
		(end 159.43 71.044999)
		(width 0.19)
		(layer "F.Cu")
		(net 24)
	)
	(arc
		(start 159.43 70.8)
		(mid 159.383137 70.686863)
		(end 159.27 70.64)
		(width 0.19)
		(layer "F.Cu")
		(net 24)
	)
	(arc
		(start 158.88015 70.64)
		(mid 158.767013 70.593137)
		(end 158.72015 70.48)
		(width 0.19)
		(layer "F.Cu")
		(net 24)
	)
	(arc
		(start 158.72015 70.4)
		(mid 158.767013 70.286863)
		(end 158.88015 70.24)
		(width 0.19)
		(layer "F.Cu")
		(net 24)
	)
	(arc
		(start 159.27 70.24)
		(mid 159.383137 70.193137)
		(end 159.43 70.08)
		(width 0.19)
		(layer "F.Cu")
		(net 24)
	)
	(segment
		(start 159.11 67.605001)
		(end 159.11 67.630001)
		(width 0.16)
		(layer "F.Cu")
		(net 25)
	)
	(segment
		(start 159.11 67.630001)
		(end 159.42 67.940001)
		(width 0.19)
		(layer "F.Cu")
		(net 25)
	)
	(segment
		(start 159.42 68.260001)
		(end 159.11 68.570001)
		(width 0.19)
		(layer "F.Cu")
		(net 25)
	)
	(segment
		(start 159.11 68.570001)
		(end 159.11 68.595001)
		(width 0.16)
		(layer "F.Cu")
		(net 25)
	)
	(segment
		(start 159.42 67.940001)
		(end 159.42 68.260001)
		(width 0.19)
		(layer "F.Cu")
		(net 25)
	)
	(segment
		(start 159.11 67.605001)
		(end 158.109999 67.605001)
		(width 0.19)
		(layer "F.Cu")
		(net 25)
	)
	(segment
		(start 159.78 69.905)
		(end 159.78 71.42)
		(width 0.19)
		(layer "F.Cu")
		(net 26)
	)
	(segment
		(start 159.78 71.42)
		(end 159.225 71.975)
		(width 0.19)
		(layer "F.Cu")
		(net 26)
	)
	(segment
		(start 159.225 71.975)
		(end 159.225 72.249999)
		(width 0.19)
		(layer "F.Cu")
		(net 26)
	)
	(segment
		(start 160.105 69.58)
		(end 159.78 69.905)
		(width 0.19)
		(layer "F.Cu")
		(net 26)
	)
	(segment
		(start 160.105 69.555)
		(end 160.105 69.58)
		(width 0.19)
		(layer "F.Cu")
		(net 26)
	)
	(segment
		(start 141.175 72.2)
		(end 140.6 72.2)
		(width 0.19)
		(layer "F.Cu")
		(net 27)
	)
	(segment
		(start 138.505 72.25)
		(end 138.48 72.25)
		(width 0.19)
		(layer "F.Cu")
		(net 27)
	)
	(segment
		(start 140.6 72.2)
		(end 140.225 72.575)
		(width 0.19)
		(layer "F.Cu")
		(net 27)
	)
	(segment
		(start 138.83 72.575)
		(end 138.505 72.25)
		(width 0.19)
		(layer "F.Cu")
		(net 27)
	)
	(segment
		(start 141.325 72.484999)
		(end 141.325 72.35)
		(width 0.19)
		(layer "F.Cu")
		(net 27)
	)
	(segment
		(start 141.06 72.749999)
		(end 141.325 72.484999)
		(width 0.19)
		(layer "F.Cu")
		(net 27)
	)
	(segment
		(start 140.225 72.575)
		(end 138.83 72.575)
		(width 0.19)
		(layer "F.Cu")
		(net 27)
	)
	(segment
		(start 141.325 72.35)
		(end 141.175 72.2)
		(width 0.19)
		(layer "F.Cu")
		(net 27)
	)
	(segment
		(start 141.875001 73.2)
		(end 141.925 73.249999)
		(width 0.19)
		(layer "F.Cu")
		(net 28)
	)
	(segment
		(start 138.505 73.25)
		(end 138.83 72.925)
		(width 0.19)
		(layer "F.Cu")
		(net 28)
	)
	(segment
		(start 140.125 72.925)
		(end 140.4 73.2)
		(width 0.19)
		(layer "F.Cu")
		(net 28)
	)
	(segment
		(start 138.83 72.925)
		(end 140.125 72.925)
		(width 0.19)
		(layer "F.Cu")
		(net 28)
	)
	(segment
		(start 138.48 73.25)
		(end 138.505 73.25)
		(width 0.19)
		(layer "F.Cu")
		(net 28)
	)
	(segment
		(start 140.4 73.2)
		(end 141.875001 73.2)
		(width 0.19)
		(layer "F.Cu")
		(net 28)
	)
	(segment
		(start 140.735 75.074999)
		(end 141.06 74.749999)
		(width 0.19)
		(layer "F.Cu")
		(net 29)
	)
	(segment
		(start 138.83 75.075)
		(end 140.735 75.074999)
		(width 0.19)
		(layer "F.Cu")
		(net 29)
	)
	(segment
		(start 138.48 74.75)
		(end 138.505 74.75)
		(width 0.19)
		(layer "F.Cu")
		(net 29)
	)
	(segment
		(start 138.505 74.75)
		(end 138.83 75.075)
		(width 0.19)
		(layer "F.Cu")
		(net 29)
	)
	(segment
		(start 138.83 75.425)
		(end 140.735001 75.425)
		(width 0.19)
		(layer "F.Cu")
		(net 30)
	)
	(segment
		(start 138.505 75.75)
		(end 138.83 75.425)
		(width 0.19)
		(layer "F.Cu")
		(net 30)
	)
	(segment
		(start 138.48 75.75)
		(end 138.505 75.75)
		(width 0.19)
		(layer "F.Cu")
		(net 30)
	)
	(segment
		(start 140.735001 75.425)
		(end 141.06 75.749999)
		(width 0.19)
		(layer "F.Cu")
		(net 30)
	)
	(segment
		(start 138.505 77.75)
		(end 138.83 78.075)
		(width 0.19)
		(layer "F.Cu")
		(net 31)
	)
	(segment
		(start 138.83 78.075)
		(end 140.2 78.075)
		(width 0.19)
		(layer "F.Cu")
		(net 31)
	)
	(segment
		(start 140.2 78.075)
		(end 140.735 78.074999)
		(width 0.19)
		(layer "F.Cu")
		(net 31)
	)
	(segment
		(start 138.48 77.75)
		(end 138.505 77.75)
		(width 0.19)
		(layer "F.Cu")
		(net 31)
	)
	(segment
		(start 140.735 78.074999)
		(end 141.06 77.749999)
		(width 0.19)
		(layer "F.Cu")
		(net 31)
	)
	(segment
		(start 138.83 78.425)
		(end 140.2 78.425)
		(width 0.19)
		(layer "F.Cu")
		(net 32)
	)
	(segment
		(start 140.2 78.425)
		(end 140.735 78.424999)
		(width 0.19)
		(layer "F.Cu")
		(net 32)
	)
	(segment
		(start 138.48 78.75)
		(end 138.505 78.75)
		(width 0.19)
		(layer "F.Cu")
		(net 32)
	)
	(segment
		(start 140.735 78.424999)
		(end 141.06 78.749999)
		(width 0.19)
		(layer "F.Cu")
		(net 32)
	)
	(segment
		(start 138.505 78.75)
		(end 138.83 78.425)
		(width 0.19)
		(layer "F.Cu")
		(net 32)
	)
	(segment
		(start 140.735 81.074999)
		(end 141.06 80.749999)
		(width 0.19)
		(layer "F.Cu")
		(net 33)
	)
	(segment
		(start 138.83 81.075)
		(end 140.4 81.075)
		(width 0.19)
		(layer "F.Cu")
		(net 33)
	)
	(segment
		(start 138.48 80.75)
		(end 138.505 80.75)
		(width 0.19)
		(layer "F.Cu")
		(net 33)
	)
	(segment
		(start 138.505 80.75)
		(end 138.83 81.075)
		(width 0.19)
		(layer "F.Cu")
		(net 33)
	)
	(segment
		(start 140.4 81.075)
		(end 140.735 81.074999)
		(width 0.19)
		(layer "F.Cu")
		(net 33)
	)
	(segment
		(start 138.505 81.75)
		(end 138.83 81.425)
		(width 0.19)
		(layer "F.Cu")
		(net 34)
	)
	(segment
		(start 140.400001 81.424999)
		(end 140.735 81.424999)
		(width 0.19)
		(layer "F.Cu")
		(net 34)
	)
	(segment
		(start 138.48 81.75)
		(end 138.505 81.75)
		(width 0.19)
		(layer "F.Cu")
		(net 34)
	)
	(segment
		(start 138.83 81.425)
		(end 140.4 81.425)
		(width 0.19)
		(layer "F.Cu")
		(net 34)
	)
	(segment
		(start 140.4 81.425)
		(end 140.400001 81.424999)
		(width 0.19)
		(layer "F.Cu")
		(net 34)
	)
	(segment
		(start 140.735 81.424999)
		(end 141.06 81.749999)
		(width 0.19)
		(layer "F.Cu")
		(net 34)
	)
	(via
		(at 147.105 90.25)
		(size 0.45)
		(drill 0.2)
		(layers "F.Cu" "B.Cu")
		(remove_unused_layers yes)
		(keep_end_layers yes)
		(zone_layer_connections)
		(net 35)
	)
	(segment
		(start 147.681866 91.081866)
		(end 147.681866 92.005117)
		(width 0.1)
		(layer "B.Cu")
		(net 35)
	)
	(segment
		(start 147.105 90.25)
		(end 147.105 90.505)
		(width 0.1)
		(layer "B.Cu")
		(net 35)
	)
	(segment
		(start 147.105 90.505)
		(end 147.681866 91.081866)
		(width 0.1)
		(layer "B.Cu")
		(net 35)
	)
	(segment
		(start 147.681867 92.005116)
		(end 147.681866 92.005117)
		(width 0.1)
		(layer "B.Cu")
		(net 35)
	)
	(segment
		(start 150.681866 92.005116)
		(end 147.681867 92.005116)
		(width 0.1)
		(layer "B.Cu")
		(net 35)
	)
	(via
		(at 160.08 89.75)
		(size 0.45)
		(drill 0.2)
		(layers "F.Cu" "B.Cu")
		(remove_unused_layers yes)
		(keep_end_layers yes)
		(zone_layer_connections)
		(net 36)
	)
	(segment
		(start 165.719797 118.327692)
		(end 165.66295 118.270844)
		(width 0.15)
		(layer "B.Cu")
		(net 36)
	)
	(segment
		(start 167.25 114.822974)
		(end 167.25 112.769353)
		(width 0.15)
		(layer "B.Cu")
		(net 36)
	)
	(segment
		(start 164.517714 119.529775)
		(end 164.393971 119.406032)
		(width 0.15)
		(layer "B.Cu")
		(net 36)
	)
	(segment
		(start 166.453925 119.061819)
		(end 165.843539 118.451433)
		(width 0.15)
		(layer "B.Cu")
		(net 36)
	)
	(segment
		(start 166.50143 117.298574)
		(end 166.722124 117.07788)
		(width 0.15)
		(layer "B.Cu")
		(net 36)
	)
	(segment
		(start 164.334524 118.732716)
		(end 164.569186 118.498055)
		(width 0.15)
		(layer "B.Cu")
		(net 36)
	)
	(segment
		(start 150.446961 134.231809)
		(end 151.046961 134.231809)
		(width 0.15)
		(layer "B.Cu")
		(net 36)
	)
	(segment
		(start 151.825 130.727512)
		(end 151.825 125.375)
		(width 0.15)
		(layer "B.Cu")
		(net 36)
	)
	(segment
		(start 163.2 120.6)
		(end 163.676256 120.123744)
		(width 0.15)
		(layer "B.Cu")
		(net 36)
	)
	(segment
		(start 165.489984 118.804989)
		(end 166.10037 119.415374)
		(width 0.15)
		(layer "B.Cu")
		(net 36)
	)
	(segment
		(start 151.046961 134.231809)
		(end 151.344449 133.934321)
		(width 0.15)
		(layer "B.Cu")
		(net 36)
	)
	(segment
		(start 165.366241 118.681246)
		(end 165.489984 118.804989)
		(width 0.15)
		(layer "B.Cu")
		(net 36)
	)
	(segment
		(start 151.825 125.375)
		(end 156.6 120.6)
		(width 0.15)
		(layer "B.Cu")
		(net 36)
	)
	(segment
		(start 166.895021 115.302974)
		(end 166.895021 115.222974)
		(width 0.15)
		(layer "B.Cu")
		(net 36)
	)
	(segment
		(start 151.344449 133.934321)
		(end 151.344449 131.208063)
		(width 0.15)
		(layer "B.Cu")
		(net 36)
	)
	(segment
		(start 163.676256 120.123744)
		(end 163.676257 120.123745)
		(width 0.15)
		(layer "B.Cu")
		(net 36)
	)
	(segment
		(start 166.722124 117.07788)
		(end 167.0625 116.7375)
		(width 0.15)
		(layer "B.Cu")
		(net 36)
	)
	(segment
		(start 167.055021 115.062974)
		(end 167.09 115.062974)
		(width 0.15)
		(layer "B.Cu")
		(net 36)
	)
	(segment
		(start 164.404575 120.123745)
		(end 164.898282 120.617452)
		(width 0.15)
		(layer "B.Cu")
		(net 36)
	)
	(segment
		(start 148.999449 135.871809)
		(end 149.839449 135.031809)
		(width 0.15)
		(layer "B.Cu")
		(net 36)
	)
	(segment
		(start 164.517713 119.529773)
		(end 164.517714 119.529775)
		(width 0.15)
		(layer "B.Cu")
		(net 36)
	)
	(segment
		(start 165.251837 120.263897)
		(end 164.758129 119.770189)
		(width 0.15)
		(layer "B.Cu")
		(net 36)
	)
	(segment
		(start 156.6 120.6)
		(end 163.2 120.6)
		(width 0.15)
		(layer "B.Cu")
		(net 36)
	)
	(segment
		(start 167.25 105.255026)
		(end 171.625 100.880026)
		(width 0.15)
		(layer "B.Cu")
		(net 36)
	)
	(segment
		(start 165.131629 120.617452)
		(end 165.251837 120.497243)
		(width 0.15)
		(layer "B.Cu")
		(net 36)
	)
	(segment
		(start 165.539207 117.538433)
		(end 165.779068 117.298573)
		(width 0.15)
		(layer "B.Cu")
		(net 36)
	)
	(segment
		(start 167.25 116.55)
		(end 167.25 115.622974)
		(width 0.15)
		(layer "B.Cu")
		(net 36)
	)
	(segment
		(start 165.66295 118.270844)
		(end 165.539207 118.147101)
		(width 0.15)
		(layer "B.Cu")
		(net 36)
	)
	(segment
		(start 167.25 112.769353)
		(end 167.25 105.255026)
		(width 0.15)
		(layer "B.Cu")
		(net 36)
	)
	(segment
		(start 160.105 89.775)
		(end 160.08 89.75)
		(width 0.15)
		(layer "B.Cu")
		(net 36)
	)
	(segment
		(start 164.393971 119.406032)
		(end 164.334524 119.346584)
		(width 0.15)
		(layer "B.Cu")
		(net 36)
	)
	(segment
		(start 151.344449 131.208063)
		(end 151.825 130.727512)
		(width 0.15)
		(layer "B.Cu")
		(net 36)
	)
	(segment
		(start 149.839449 135.031809)
		(end 149.839449 134.839321)
		(width 0.15)
		(layer "B.Cu")
		(net 36)
	)
	(segment
		(start 165.183054 118.498055)
		(end 165.242502 118.557503)
		(width 0.15)
		(layer "B.Cu")
		(net 36)
	)
	(segment
		(start 167.25 114.902974)
		(end 167.25 114.822974)
		(width 0.15)
		(layer "B.Cu")
		(net 36)
	)
	(segment
		(start 167.09 115.462974)
		(end 167.055021 115.462974)
		(width 0.15)
		(layer "B.Cu")
		(net 36)
	)
	(segment
		(start 167.0625 116.7375)
		(end 167.25 116.55)
		(width 0.15)
		(layer "B.Cu")
		(net 36)
	)
	(segment
		(start 171.625 100.880026)
		(end 171.625 95.522056)
		(width 0.15)
		(layer "B.Cu")
		(net 36)
	)
	(segment
		(start 149.839449 134.839321)
		(end 150.446961 134.231809)
		(width 0.15)
		(layer "B.Cu")
		(net 36)
	)
	(segment
		(start 165.843539 118.451433)
		(end 165.719796 118.32769)
		(width 0.15)
		(layer "B.Cu")
		(net 36)
	)
	(segment
		(start 166.333717 119.415374)
		(end 166.453925 119.295165)
		(width 0.15)
		(layer "B.Cu")
		(net 36)
	)
	(segment
		(start 165.366245 118.681246)
		(end 165.366241 118.681246)
		(width 0.15)
		(layer "B.Cu")
		(net 36)
	)
	(segment
		(start 165.877944 89.775)
		(end 160.105 89.775)
		(width 0.15)
		(layer "B.Cu")
		(net 36)
	)
	(segment
		(start 164.758129 119.770189)
		(end 164.517713 119.529773)
		(width 0.15)
		(layer "B.Cu")
		(net 36)
	)
	(segment
		(start 171.625 95.522056)
		(end 165.877944 89.775)
		(width 0.15)
		(layer "B.Cu")
		(net 36)
	)
	(segment
		(start 165.719796 118.32769)
		(end 165.719797 118.327692)
		(width 0.15)
		(layer "B.Cu")
		(net 36)
	)
	(segment
		(start 165.242502 118.557503)
		(end 165.366245 118.681246)
		(width 0.15)
		(layer "B.Cu")
		(net 36)
	)
	(arc
		(start 166.10037 119.415374)
		(mid 166.217044 119.463701)
		(end 166.333717 119.415374)
		(width 0.15)
		(layer "B.Cu")
		(net 36)
	)
	(arc
		(start 166.387734 117.298574)
		(mid 166.444583 117.32212)
		(end 166.50143 117.298574)
		(width 0.15)
		(layer "B.Cu")
		(net 36)
	)
	(arc
		(start 164.569186 118.498055)
		(mid 164.87612 118.370919)
		(end 165.183054 118.498055)
		(width 0.15)
		(layer "B.Cu")
		(net 36)
	)
	(arc
		(start 166.453925 119.295165)
		(mid 166.502253 119.178492)
		(end 166.453925 119.061819)
		(width 0.15)
		(layer "B.Cu")
		(net 36)
	)
	(arc
		(start 165.251837 120.497243)
		(mid 165.300165 120.38057)
		(end 165.251837 120.263897)
		(width 0.15)
		(layer "B.Cu")
		(net 36)
	)
	(arc
		(start 167.25 115.622974)
		(mid 167.203137 115.509837)
		(end 167.09 115.462974)
		(width 0.15)
		(layer "B.Cu")
		(net 36)
	)
	(arc
		(start 165.539207 118.147101)
		(mid 165.413147 117.842768)
		(end 165.539207 117.538433)
		(width 0.15)
		(layer "B.Cu")
		(net 36)
	)
	(arc
		(start 166.895021 115.222974)
		(mid 166.941884 115.109837)
		(end 167.055021 115.062974)
		(width 0.15)
		(layer "B.Cu")
		(net 36)
	)
	(arc
		(start 164.334524 119.346584)
		(mid 164.207388 119.03965)
		(end 164.334524 118.732716)
		(width 0.15)
		(layer "B.Cu")
		(net 36)
	)
	(arc
		(start 163.676257 120.123745)
		(mid 164.040416 119.972905)
		(end 164.404575 120.123745)
		(width 0.15)
		(layer "B.Cu")
		(net 36)
	)
	(arc
		(start 165.779068 117.298573)
		(mid 166.083401 117.172515)
		(end 166.387734 117.298574)
		(width 0.15)
		(layer "B.Cu")
		(net 36)
	)
	(arc
		(start 167.055021 115.462974)
		(mid 166.941884 115.416111)
		(end 166.895021 115.302974)
		(width 0.15)
		(layer "B.Cu")
		(net 36)
	)
	(arc
		(start 164.898282 120.617452)
		(mid 165.014956 120.665779)
		(end 165.131629 120.617452)
		(width 0.15)
		(layer "B.Cu")
		(net 36)
	)
	(arc
		(start 167.09 115.062974)
		(mid 167.203137 115.016111)
		(end 167.25 114.902974)
		(width 0.15)
		(layer "B.Cu")
		(net 36)
	)
	(via
		(at 160.945 90.25)
		(size 0.45)
		(drill 0.2)
		(layers "F.Cu" "B.Cu")
		(remove_unused_layers yes)
		(keep_end_layers yes)
		(zone_layer_connections)
		(net 37)
	)
	(segment
		(start 162.847918 119.75)
		(end 166.4 116.197918)
		(width 0.15)
		(layer "B.Cu")
		(net 37)
	)
	(segment
		(start 170.775 100.527946)
		(end 170.775 95.874138)
		(width 0.15)
		(layer "B.Cu")
		(net 37)
	)
	(segment
		(start 150.975 129.872488)
		(end 150.975 125.022918)
		(width 0.15)
		(layer "B.Cu")
		(net 37)
	)
	(segment
		(start 166.050002 113.153269)
		(end 165.28556 113.153269)
		(width 0.15)
		(layer "B.Cu")
		(net 37)
	)
	(segment
		(start 165.282783 114.403267)
		(end 165.865001 114.403267)
		(width 0.15)
		(layer "B.Cu")
		(net 37)
	)
	(segment
		(start 166.899998 112.178269)
		(end 166.899998 111.778267)
		(width 0.15)
		(layer "B.Cu")
		(net 37)
	)
	(segment
		(start 166.4 108.468268)
		(end 166.4 108.288268)
		(width 0.15)
		(layer "B.Cu")
		(net 37)
	)
	(segment
		(start 165.097782 114.768268)
		(end 165.097782 114.588268)
		(width 0.15)
		(layer "B.Cu")
		(net 37)
	)
	(segment
		(start 150.975 125.022918)
		(end 156.247918 119.75)
		(width 0.15)
		(layer "B.Cu")
		(net 37)
	)
	(segment
		(start 149.175 132.51)
		(end 149.175 131.672488)
		(width 0.15)
		(layer "B.Cu")
		(net 37)
	)
	(segment
		(start 165.1061 111.168268)
		(end 165.1061 110.988268)
		(width 0.15)
		(layer "B.Cu")
		(net 37)
	)
	(segment
		(start 166.475 113.153269)
		(end 166.4 113.153269)
		(width 0.15)
		(layer "B.Cu")
		(net 37)
	)
	(segment
		(start 161.969333 90.280284)
		(end 161.969333 90.285)
		(width 0.15)
		(layer "B.Cu")
		(net 37)
	)
	(segment
		(start 165.313318 109.003267)
		(end 165.865001 109.003267)
		(width 0.15)
		(layer "B.Cu")
		(net 37)
	)
	(segment
		(start 165.128317 109.368268)
		(end 165.128317 109.188268)
		(width 0.15)
		(layer "B.Cu")
		(net 37)
	)
	(segment
		(start 166.4 114.403267)
		(end 166.475 114.403267)
		(width 0.15)
		(layer "B.Cu")
		(net 37)
	)
	(segment
		(start 166.475 109.553269)
		(end 166.4 109.553269)
		(width 0.15)
		(layer "B.Cu")
		(net 37)
	)
	(segment
		(start 162.319333 90.285)
		(end 162.319333 90.280309)
		(width 0.15)
		(layer "B.Cu")
		(net 37)
	)
	(segment
		(start 166.475 111.353269)
		(end 166.4 111.353269)
		(width 0.15)
		(layer "B.Cu")
		(net 37)
	)
	(segment
		(start 166.4 111.353269)
		(end 166.050002 111.353269)
		(width 0.15)
		(layer "B.Cu")
		(net 37)
	)
	(segment
		(start 156.247918 119.75)
		(end 162.847918 119.75)
		(width 0.15)
		(layer "B.Cu")
		(net 37)
	)
	(segment
		(start 162.809333 90.425)
		(end 165.325862 90.425)
		(width 0.15)
		(layer "B.Cu")
		(net 37)
	)
	(segment
		(start 166.4 110.803267)
		(end 166.475 110.803267)
		(width 0.15)
		(layer "B.Cu")
		(net 37)
	)
	(segment
		(start 161.759333 90.140284)
		(end 161.829333 90.140284)
		(width 0.15)
		(layer "B.Cu")
		(net 37)
	)
	(segment
		(start 166.748484 104.554462)
		(end 170.775 100.527946)
		(width 0.15)
		(layer "B.Cu")
		(net 37)
	)
	(segment
		(start 165.865001 109.553269)
		(end 165.313318 109.553269)
		(width 0.15)
		(layer "B.Cu")
		(net 37)
	)
	(segment
		(start 166.050002 110.803267)
		(end 166.4 110.803267)
		(width 0.15)
		(layer "B.Cu")
		(net 37)
	)
	(segment
		(start 166.4 113.153269)
		(end 166.050002 113.153269)
		(width 0.15)
		(layer "B.Cu")
		(net 37)
	)
	(segment
		(start 170.775 95.874138)
		(end 165.325862 90.425)
		(width 0.15)
		(layer "B.Cu")
		(net 37)
	)
	(segment
		(start 165.291101 110.803267)
		(end 166.050002 110.803267)
		(width 0.15)
		(layer "B.Cu")
		(net 37)
	)
	(segment
		(start 161.619333 90.285)
		(end 161.619333 90.280284)
		(width 0.15)
		(layer "B.Cu")
		(net 37)
	)
	(segment
		(start 161.12 90.425)
		(end 161.479333 90.425)
		(width 0.15)
		(layer "B.Cu")
		(net 37)
	)
	(segment
		(start 165.100559 112.968268)
		(end 165.100559 112.788268)
		(width 0.15)
		(layer "B.Cu")
		(net 37)
	)
	(segment
		(start 149.175 131.672488)
		(end 150.975 129.872488)
		(width 0.15)
		(layer "B.Cu")
		(net 37)
	)
	(segment
		(start 166.4 109.553269)
		(end 165.865001 109.553269)
		(width 0.15)
		(layer "B.Cu")
		(net 37)
	)
	(segment
		(start 166.899998 113.978269)
		(end 166.899998 113.578267)
		(width 0.15)
		(layer "B.Cu")
		(net 37)
	)
	(segment
		(start 160.945 90.25)
		(end 161.12 90.425)
		(width 0.15)
		(layer "B.Cu")
		(net 37)
	)
	(segment
		(start 166.4 104.902946)
		(end 166.748484 104.554462)
		(width 0.15)
		(layer "B.Cu")
		(net 37)
	)
	(segment
		(start 165.28556 112.603267)
		(end 166.050002 112.603267)
		(width 0.15)
		(layer "B.Cu")
		(net 37)
	)
	(segment
		(start 166.4 112.603267)
		(end 166.475 112.603267)
		(width 0.15)
		(layer "B.Cu")
		(net 37)
	)
	(segment
		(start 166.050002 111.353269)
		(end 165.291101 111.353269)
		(width 0.15)
		(layer "B.Cu")
		(net 37)
	)
	(segment
		(start 165.865001 114.403267)
		(end 166.4 114.403267)
		(width 0.15)
		(layer "B.Cu")
		(net 37)
	)
	(segment
		(start 166.4 116.197918)
		(end 166.4 115.488268)
		(width 0.15)
		(layer "B.Cu")
		(net 37)
	)
	(segment
		(start 166.050002 112.603267)
		(end 166.4 112.603267)
		(width 0.15)
		(layer "B.Cu")
		(net 37)
	)
	(segment
		(start 165.865001 114.953269)
		(end 165.282783 114.953269)
		(width 0.15)
		(layer "B.Cu")
		(net 37)
	)
	(segment
		(start 162.109333 90.425)
		(end 162.179333 90.425)
		(width 0.15)
		(layer "B.Cu")
		(net 37)
	)
	(segment
		(start 162.459333 90.140309)
		(end 162.529333 90.140309)
		(width 0.15)
		(layer "B.Cu")
		(net 37)
	)
	(segment
		(start 162.669333 90.280309)
		(end 162.669333 90.285)
		(width 0.15)
		(layer "B.Cu")
		(net 37)
	)
	(segment
		(start 166.899998 110.378269)
		(end 166.899998 109.978267)
		(width 0.15)
		(layer "B.Cu")
		(net 37)
	)
	(segment
		(start 150.015 133.35)
		(end 149.175 132.51)
		(width 0.15)
		(layer "B.Cu")
		(net 37)
	)
	(segment
		(start 166.4 108.288268)
		(end 166.4 104.902946)
		(width 0.15)
		(layer "B.Cu")
		(net 37)
	)
	(arc
		(start 166.899998 109.978267)
		(mid 166.775519 109.677748)
		(end 166.475 109.553269)
		(width 0.15)
		(layer "B.Cu")
		(net 37)
	)
	(arc
		(start 165.100559 112.788268)
		(mid 165.154745 112.657453)
		(end 165.28556 112.603267)
		(width 0.15)
		(layer "B.Cu")
		(net 37)
	)
	(arc
		(start 165.128317 109.188268)
		(mid 165.182503 109.057453)
		(end 165.313318 109.003267)
		(width 0.15)
		(layer "B.Cu")
		(net 37)
	)
	(arc
		(start 165.097782 114.588268)
		(mid 165.151968 114.457453)
		(end 165.282783 114.403267)
		(width 0.15)
		(layer "B.Cu")
		(net 37)
	)
	(arc
		(start 166.475 110.803267)
		(mid 166.775519 110.678788)
		(end 166.899998 110.378269)
		(width 0.15)
		(layer "B.Cu")
		(net 37)
	)
	(arc
		(start 166.475 114.403267)
		(mid 166.775519 114.278788)
		(end 166.899998 113.978269)
		(width 0.15)
		(layer "B.Cu")
		(net 37)
	)
	(arc
		(start 165.291101 111.353269)
		(mid 165.160286 111.299083)
		(end 165.1061 111.168268)
		(width 0.15)
		(layer "B.Cu")
		(net 37)
	)
	(arc
		(start 162.319333 90.280309)
		(mid 162.360338 90.181314)
		(end 162.459333 90.140309)
		(width 0.15)
		(layer "B.Cu")
		(net 37)
	)
	(arc
		(start 162.529333 90.140309)
		(mid 162.628328 90.181314)
		(end 162.669333 90.280309)
		(width 0.15)
		(layer "B.Cu")
		(net 37)
	)
	(arc
		(start 161.619333 90.280284)
		(mid 161.660338 90.181289)
		(end 161.759333 90.140284)
		(width 0.15)
		(layer "B.Cu")
		(net 37)
	)
	(arc
		(start 166.475 112.603267)
		(mid 166.775519 112.478788)
		(end 166.899998 112.178269)
		(width 0.15)
		(layer "B.Cu")
		(net 37)
	)
	(arc
		(start 162.669333 90.285)
		(mid 162.710338 90.383995)
		(end 162.809333 90.425)
		(width 0.15)
		(layer "B.Cu")
		(net 37)
	)
	(arc
		(start 162.179333 90.425)
		(mid 162.278328 90.383995)
		(end 162.319333 90.285)
		(width 0.15)
		(layer "B.Cu")
		(net 37)
	)
	(arc
		(start 165.1061 110.988268)
		(mid 165.160286 110.857453)
		(end 165.291101 110.803267)
		(width 0.15)
		(layer "B.Cu")
		(net 37)
	)
	(arc
		(start 166.4 115.488268)
		(mid 166.243302 115.109967)
		(end 165.865001 114.953269)
		(width 0.15)
		(layer "B.Cu")
		(net 37)
	)
	(arc
		(start 165.865001 109.003267)
		(mid 166.243302 108.846569)
		(end 166.4 108.468268)
		(width 0.15)
		(layer "B.Cu")
		(net 37)
	)
	(arc
		(start 165.313318 109.553269)
		(mid 165.182503 109.499083)
		(end 165.128317 109.368268)
		(width 0.15)
		(layer "B.Cu")
		(net 37)
	)
	(arc
		(start 165.282783 114.953269)
		(mid 165.151968 114.899083)
		(end 165.097782 114.768268)
		(width 0.15)
		(layer "B.Cu")
		(net 37)
	)
	(arc
		(start 165.28556 113.153269)
		(mid 165.154745 113.099083)
		(end 165.100559 112.968268)
		(width 0.15)
		(layer "B.Cu")
		(net 37)
	)
	(arc
		(start 161.829333 90.140284)
		(mid 161.928328 90.181289)
		(end 161.969333 90.280284)
		(width 0.15)
		(layer "B.Cu")
		(net 37)
	)
	(arc
		(start 166.899998 111.778267)
		(mid 166.775519 111.477748)
		(end 166.475 111.353269)
		(width 0.15)
		(layer "B.Cu")
		(net 37)
	)
	(arc
		(start 161.479333 90.425)
		(mid 161.578328 90.383995)
		(end 161.619333 90.285)
		(width 0.15)
		(layer "B.Cu")
		(net 37)
	)
	(arc
		(start 161.969333 90.285)
		(mid 162.010338 90.383995)
		(end 162.109333 90.425)
		(width 0.15)
		(layer "B.Cu")
		(net 37)
	)
	(arc
		(start 166.899998 113.578267)
		(mid 166.775519 113.277748)
		(end 166.475 113.153269)
		(width 0.15)
		(layer "B.Cu")
		(net 37)
	)
	(via
		(at 160.945 88.25)
		(size 0.45)
		(drill 0.2)
		(layers "F.Cu" "B.Cu")
		(remove_unused_layers yes)
		(keep_end_layers yes)
		(zone_layer_connections)
		(net 38)
	)
	(segment
		(start 162.186445 88.425)
		(end 162.256445 88.425)
		(width 0.15)
		(layer "B.Cu")
		(net 38)
	)
	(segment
		(start 160.945 88.25)
		(end 161.12 88.425)
		(width 0.15)
		(layer "B.Cu")
		(net 38)
	)
	(segment
		(start 162.536445 88.140284)
		(end 162.606445 88.140284)
		(width 0.15)
		(layer "B.Cu")
		(net 38)
	)
	(segment
		(start 161.836445 88.14026)
		(end 161.906445 88.14026)
		(width 0.15)
		(layer "B.Cu")
		(net 38)
	)
	(segment
		(start 162.046445 88.28026)
		(end 162.046445 88.285)
		(width 0.15)
		(layer "B.Cu")
		(net 38)
	)
	(segment
		(start 153.375 126.017032)
		(end 157.242032 122.15)
		(width 0.15)
		(layer "B.Cu")
		(net 38)
	)
	(segment
		(start 157.242032 122.15)
		(end 165.45 122.15)
		(width 0.15)
		(layer "B.Cu")
		(net 38)
	)
	(segment
		(start 153.375 131.072488)
		(end 153.375 126.017032)
		(width 0.15)
		(layer "B.Cu")
		(net 38)
	)
	(segment
		(start 173.175 99.377082)
		(end 173.175 94.880026)
		(width 0.15)
		(layer "B.Cu")
		(net 38)
	)
	(segment
		(start 162.396445 88.285)
		(end 162.396445 88.280284)
		(width 0.15)
		(layer "B.Cu")
		(net 38)
	)
	(segment
		(start 154.26 135.06)
		(end 154.26 134.867512)
		(width 0.15)
		(layer "B.Cu")
		(net 38)
	)
	(segment
		(start 153.652488 134.26)
		(end 153.052488 134.26)
		(width 0.15)
		(layer "B.Cu")
		(net 38)
	)
	(segment
		(start 165.45 122.15)
		(end 177.2 110.4)
		(width 0.15)
		(layer "B.Cu")
		(net 38)
	)
	(segment
		(start 162.746445 88.280284)
		(end 162.746445 88.285)
		(width 0.15)
		(layer "B.Cu")
		(net 38)
	)
	(segment
		(start 162.886445 88.425)
		(end 166.719974 88.425)
		(width 0.15)
		(layer "B.Cu")
		(net 38)
	)
	(segment
		(start 154.26 134.867512)
		(end 153.652488 134.26)
		(width 0.15)
		(layer "B.Cu")
		(net 38)
	)
	(segment
		(start 177.2 103.402082)
		(end 173.175 99.377082)
		(width 0.15)
		(layer "B.Cu")
		(net 38)
	)
	(segment
		(start 173.175 94.880026)
		(end 166.719974 88.425)
		(width 0.15)
		(layer "B.Cu")
		(net 38)
	)
	(segment
		(start 161.696445 88.285)
		(end 161.696445 88.28026)
		(width 0.15)
		(layer "B.Cu")
		(net 38)
	)
	(segment
		(start 153.052488 134.26)
		(end 152.755 133.962512)
		(width 0.15)
		(layer "B.Cu")
		(net 38)
	)
	(segment
		(start 161.12 88.425)
		(end 161.556445 88.425)
		(width 0.15)
		(layer "B.Cu")
		(net 38)
	)
	(segment
		(start 177.2 110.4)
		(end 177.2 103.402082)
		(width 0.15)
		(layer "B.Cu")
		(net 38)
	)
	(segment
		(start 152.755 131.692488)
		(end 153.375 131.072488)
		(width 0.15)
		(layer "B.Cu")
		(net 38)
	)
	(segment
		(start 152.755 133.962512)
		(end 152.755 131.692488)
		(width 0.15)
		(layer "B.Cu")
		(net 38)
	)
	(segment
		(start 155.1 135.9)
		(end 154.26 135.06)
		(width 0.15)
		(layer "B.Cu")
		(net 38)
	)
	(arc
		(start 162.256445 88.425)
		(mid 162.35544 88.383995)
		(end 162.396445 88.285)
		(width 0.15)
		(layer "B.Cu")
		(net 38)
	)
	(arc
		(start 162.746445 88.285)
		(mid 162.78745 88.383995)
		(end 162.886445 88.425)
		(width 0.15)
		(layer "B.Cu")
		(net 38)
	)
	(arc
		(start 161.906445 88.14026)
		(mid 162.00544 88.181265)
		(end 162.046445 88.28026)
		(width 0.15)
		(layer "B.Cu")
		(net 38)
	)
	(arc
		(start 161.696445 88.28026)
		(mid 161.73745 88.181265)
		(end 161.836445 88.14026)
		(width 0.15)
		(layer "B.Cu")
		(net 38)
	)
	(arc
		(start 162.046445 88.285)
		(mid 162.08745 88.383995)
		(end 162.186445 88.425)
		(width 0.15)
		(layer "B.Cu")
		(net 38)
	)
	(arc
		(start 161.556445 88.425)
		(mid 161.65544 88.383995)
		(end 161.696445 88.285)
		(width 0.15)
		(layer "B.Cu")
		(net 38)
	)
	(arc
		(start 162.396445 88.280284)
		(mid 162.43745 88.181289)
		(end 162.536445 88.140284)
		(width 0.15)
		(layer "B.Cu")
		(net 38)
	)
	(arc
		(start 162.606445 88.140284)
		(mid 162.70544 88.181289)
		(end 162.746445 88.280284)
		(width 0.15)
		(layer "B.Cu")
		(net 38)
	)
	(via
		(at 160.945 89.25)
		(size 0.45)
		(drill 0.2)
		(layers "F.Cu" "B.Cu")
		(remove_unused_layers yes)
		(keep_end_layers yes)
		(zone_layer_connections)
		(net 39)
	)
	(segment
		(start 167.599999 116.694975)
		(end 167.599999 105.400001)
		(width 0.15)
		(layer "B.Cu")
		(net 39)
	)
	(segment
		(start 171.975 95.377082)
		(end 166.022918 89.425)
		(width 0.15)
		(layer "B.Cu")
		(net 39)
	)
	(segment
		(start 161.715723 89.285)
		(end 161.715723 89.280309)
		(width 0.15)
		(layer "B.Cu")
		(net 39)
	)
	(segment
		(start 165.242499 119.052474)
		(end 165.852884 119.66286)
		(width 0.15)
		(layer "B.Cu")
		(net 39)
	)
	(segment
		(start 163.923743 120.371231)
		(end 163.923742 120.37123)
		(width 0.15)
		(layer "B.Cu")
		(net 39)
	)
	(segment
		(start 164.995016 118.804989)
		(end 165.118759 118.928732)
		(width 0.15)
		(layer "B.Cu")
		(net 39)
	)
	(segment
		(start 164.765201 119.282288)
		(end 164.641458 119.158545)
		(width 0.15)
		(layer "B.Cu")
		(net 39)
	)
	(segment
		(start 152.175 125.519974)
		(end 156.744975 120.949999)
		(width 0.15)
		(layer "B.Cu")
		(net 39)
	)
	(segment
		(start 164.935568 118.745541)
		(end 164.995016 118.804989)
		(width 0.15)
		(layer "B.Cu")
		(net 39)
	)
	(segment
		(start 162.765723 89.280333)
		(end 162.765723 89.285)
		(width 0.15)
		(layer "B.Cu")
		(net 39)
	)
	(segment
		(start 165.967284 118.080205)
		(end 165.910436 118.023358)
		(width 0.15)
		(layer "B.Cu")
		(net 39)
	)
	(segment
		(start 165.005615 119.522702)
		(end 164.765199 119.282286)
		(width 0.15)
		(layer "B.Cu")
		(net 39)
	)
	(segment
		(start 162.205723 89.425)
		(end 162.275723 89.425)
		(width 0.15)
		(layer "B.Cu")
		(net 39)
	)
	(segment
		(start 165.910436 118.023358)
		(end 165.786693 117.899615)
		(width 0.15)
		(layer "B.Cu")
		(net 39)
	)
	(segment
		(start 162.905723 89.425)
		(end 166.022918 89.425)
		(width 0.15)
		(layer "B.Cu")
		(net 39)
	)
	(segment
		(start 164.765199 119.282286)
		(end 164.765201 119.282288)
		(width 0.15)
		(layer "B.Cu")
		(net 39)
	)
	(segment
		(start 150.189449 134.984297)
		(end 150.591937 134.581809)
		(width 0.15)
		(layer "B.Cu")
		(net 39)
	)
	(segment
		(start 165.499323 120.01641)
		(end 165.005615 119.522702)
		(width 0.15)
		(layer "B.Cu")
		(net 39)
	)
	(segment
		(start 151.029449 135.871809)
		(end 150.189449 135.031809)
		(width 0.15)
		(layer "B.Cu")
		(net 39)
	)
	(segment
		(start 166.091025 118.203947)
		(end 165.967282 118.080204)
		(width 0.15)
		(layer "B.Cu")
		(net 39)
	)
	(segment
		(start 163.344975 120.949999)
		(end 163.923743 120.371231)
		(width 0.15)
		(layer "B.Cu")
		(net 39)
	)
	(segment
		(start 161.855723 89.140309)
		(end 161.925723 89.140309)
		(width 0.15)
		(layer "B.Cu")
		(net 39)
	)
	(segment
		(start 162.555723 89.140333)
		(end 162.625723 89.140333)
		(width 0.15)
		(layer "B.Cu")
		(net 39)
	)
	(segment
		(start 165.118759 118.928732)
		(end 165.118756 118.928731)
		(width 0.15)
		(layer "B.Cu")
		(net 39)
	)
	(segment
		(start 152.175 130.872488)
		(end 152.175 125.519974)
		(width 0.15)
		(layer "B.Cu")
		(net 39)
	)
	(segment
		(start 167.599999 105.400001)
		(end 171.975 101.025)
		(width 0.15)
		(layer "B.Cu")
		(net 39)
	)
	(segment
		(start 166.748916 117.54606)
		(end 166.969609 117.325365)
		(width 0.15)
		(layer "B.Cu")
		(net 39)
	)
	(segment
		(start 161.12 89.425)
		(end 161.575723 89.425)
		(width 0.15)
		(layer "B.Cu")
		(net 39)
	)
	(segment
		(start 162.065723 89.280309)
		(end 162.065723 89.285)
		(width 0.15)
		(layer "B.Cu")
		(net 39)
	)
	(segment
		(start 166.701411 118.814333)
		(end 166.091025 118.203947)
		(width 0.15)
		(layer "B.Cu")
		(net 39)
	)
	(segment
		(start 166.581203 119.66286)
		(end 166.701411 119.542651)
		(width 0.15)
		(layer "B.Cu")
		(net 39)
	)
	(segment
		(start 166.969609 117.325365)
		(end 167.309987 116.984987)
		(width 0.15)
		(layer "B.Cu")
		(net 39)
	)
	(segment
		(start 151.694449 131.353039)
		(end 152.175 130.872488)
		(width 0.15)
		(layer "B.Cu")
		(net 39)
	)
	(segment
		(start 150.591937 134.581809)
		(end 151.191937 134.581809)
		(width 0.15)
		(layer "B.Cu")
		(net 39)
	)
	(segment
		(start 150.189449 135.031809)
		(end 150.189449 134.984297)
		(width 0.15)
		(layer "B.Cu")
		(net 39)
	)
	(segment
		(start 156.744975 120.949999)
		(end 163.344975 120.949999)
		(width 0.15)
		(layer "B.Cu")
		(net 39)
	)
	(segment
		(start 151.191937 134.581809)
		(end 151.694449 134.079297)
		(width 0.15)
		(layer "B.Cu")
		(net 39)
	)
	(segment
		(start 167.309987 116.984987)
		(end 167.599999 116.694975)
		(width 0.15)
		(layer "B.Cu")
		(net 39)
	)
	(segment
		(start 165.786693 117.785919)
		(end 166.026554 117.546059)
		(width 0.15)
		(layer "B.Cu")
		(net 39)
	)
	(segment
		(start 151.694449 134.079297)
		(end 151.694449 131.353039)
		(width 0.15)
		(layer "B.Cu")
		(net 39)
	)
	(segment
		(start 164.157089 120.37123)
		(end 164.650796 120.864937)
		(width 0.15)
		(layer "B.Cu")
		(net 39)
	)
	(segment
		(start 171.975 101.025)
		(end 171.975 95.377082)
		(width 0.15)
		(layer "B.Cu")
		(net 39)
	)
	(segment
		(start 164.641458 119.158545)
		(end 164.58201 119.099098)
		(width 0.15)
		(layer "B.Cu")
		(net 39)
	)
	(segment
		(start 164.58201 118.980202)
		(end 164.816672 118.745541)
		(width 0.15)
		(layer "B.Cu")
		(net 39)
	)
	(segment
		(start 165.379115 120.864937)
		(end 165.499323 120.744728)
		(width 0.15)
		(layer "B.Cu")
		(net 39)
	)
	(segment
		(start 165.967282 118.080204)
		(end 165.967284 118.080205)
		(width 0.15)
		(layer "B.Cu")
		(net 39)
	)
	(segment
		(start 165.118756 118.928731)
		(end 165.242499 119.052474)
		(width 0.15)
		(layer "B.Cu")
		(net 39)
	)
	(segment
		(start 162.415723 89.285)
		(end 162.415723 89.280333)
		(width 0.15)
		(layer "B.Cu")
		(net 39)
	)
	(segment
		(start 160.945 89.25)
		(end 161.12 89.425)
		(width 0.15)
		(layer "B.Cu")
		(net 39)
	)
	(arc
		(start 164.816672 118.745541)
		(mid 164.87612 118.720917)
		(end 164.935568 118.745541)
		(width 0.15)
		(layer "B.Cu")
		(net 39)
	)
	(arc
		(start 165.499323 120.744728)
		(mid 165.650163 120.380569)
		(end 165.499323 120.01641)
		(width 0.15)
		(layer "B.Cu")
		(net 39)
	)
	(arc
		(start 162.765723 89.285)
		(mid 162.806728 89.383995)
		(end 162.905723 89.425)
		(width 0.15)
		(layer "B.Cu")
		(net 39)
	)
	(arc
		(start 162.275723 89.425)
		(mid 162.374718 89.383995)
		(end 162.415723 89.285)
		(width 0.15)
		(layer "B.Cu")
		(net 39)
	)
	(arc
		(start 162.065723 89.285)
		(mid 162.106728 89.383995)
		(end 162.205723 89.425)
		(width 0.15)
		(layer "B.Cu")
		(net 39)
	)
	(arc
		(start 165.786693 117.899615)
		(mid 165.763147 117.842766)
		(end 165.786693 117.785919)
		(width 0.15)
		(layer "B.Cu")
		(net 39)
	)
	(arc
		(start 162.625723 89.140333)
		(mid 162.724718 89.181338)
		(end 162.765723 89.280333)
		(width 0.15)
		(layer "B.Cu")
		(net 39)
	)
	(arc
		(start 166.140248 117.54606)
		(mid 166.444583 117.672118)
		(end 166.748916 117.54606)
		(width 0.15)
		(layer "B.Cu")
		(net 39)
	)
	(arc
		(start 161.575723 89.425)
		(mid 161.674718 89.383995)
		(end 161.715723 89.285)
		(width 0.15)
		(layer "B.Cu")
		(net 39)
	)
	(arc
		(start 162.415723 89.280333)
		(mid 162.456728 89.181338)
		(end 162.555723 89.140333)
		(width 0.15)
		(layer "B.Cu")
		(net 39)
	)
	(arc
		(start 163.923742 120.37123)
		(mid 164.040415 120.322902)
		(end 164.157089 120.37123)
		(width 0.15)
		(layer "B.Cu")
		(net 39)
	)
	(arc
		(start 165.852884 119.66286)
		(mid 166.217044 119.813699)
		(end 166.581203 119.66286)
		(width 0.15)
		(layer "B.Cu")
		(net 39)
	)
	(arc
		(start 164.650796 120.864937)
		(mid 165.014956 121.015776)
		(end 165.379115 120.864937)
		(width 0.15)
		(layer "B.Cu")
		(net 39)
	)
	(arc
		(start 166.701411 119.542651)
		(mid 166.852251 119.178492)
		(end 166.701411 118.814333)
		(width 0.15)
		(layer "B.Cu")
		(net 39)
	)
	(arc
		(start 161.715723 89.280309)
		(mid 161.756728 89.181314)
		(end 161.855723 89.140309)
		(width 0.15)
		(layer "B.Cu")
		(net 39)
	)
	(arc
		(start 164.58201 119.099098)
		(mid 164.557386 119.03965)
		(end 164.58201 118.980202)
		(width 0.15)
		(layer "B.Cu")
		(net 39)
	)
	(arc
		(start 161.925723 89.140309)
		(mid 162.024718 89.181314)
		(end 162.065723 89.280309)
		(width 0.15)
		(layer "B.Cu")
		(net 39)
	)
	(arc
		(start 166.026554 117.546059)
		(mid 166.083401 117.522513)
		(end 166.140248 117.54606)
		(width 0.15)
		(layer "B.Cu")
		(net 39)
	)
	(segment
		(start 124 71.5)
		(end 124 70.48)
		(width 0.1)
		(layer "F.Cu")
		(net 40)
	)
	(segment
		(start 130.88 145.5)
		(end 131.7 145.5)
		(width 0.25)
		(layer "F.Cu")
		(net 40)
	)
	(segment
		(start 122.5 70.25)
		(end 122.75 70)
		(width 0.25)
		(layer "F.Cu")
		(net 40)
	)
	(segment
		(start 141.036 62.204)
		(end 139.796 62.204)
		(width 0.25)
		(layer "F.Cu")
		(net 40)
	)
	(segment
		(start 124 70.48)
		(end 123.52 70)
		(width 0.1)
		(layer "F.Cu")
		(net 40)
	)
	(segment
		(start 123.52 70)
		(end 122.75 70)
		(width 0.25)
		(layer "F.Cu")
		(net 40)
	)
	(segment
		(start 124.48 72)
		(end 124.48 71.98)
		(width 0.1)
		(layer "F.Cu")
		(net 40)
	)
	(segment
		(start 139.796 62.204)
		(end 139.75 62.25)
		(width 0.25)
		(layer "F.Cu")
		(net 40)
	)
	(segment
		(start 134.68 59.221)
		(end 134.701 59.2)
		(width 0.5)
		(layer "F.Cu")
		(net 40)
	)
	(segment
		(start 140.77 63.25)
		(end 140.92 63.4)
		(width 0.25)
		(layer "F.Cu")
		(net 40)
	)
	(segment
		(start 116.52 71.9)
		(end 115.8 71.9)
		(width 0.1)
		(layer "F.Cu")
		(net 40)
	)
	(segment
		(start 122 70.25)
		(end 122.5 70.25)
		(width 0.25)
		(layer "F.Cu")
		(net 40)
	)
	(segment
		(start 134.68 60.4)
		(end 134.68 59.221)
		(width 0.5)
		(layer "F.Cu")
		(net 40)
	)
	(segment
		(start 139.75 63.25)
		(end 140.77 63.25)
		(width 0.25)
		(layer "F.Cu")
		(net 40)
	)
	(segment
		(start 124.48 71.98)
		(end 124 71.5)
		(width 0.1)
		(layer "F.Cu")
		(net 40)
	)
	(segment
		(start 137.601 59.2)
		(end 137.75 59.051)
		(width 0.5)
		(layer "F.Cu")
		(net 40)
	)
	(segment
		(start 134.701 59.2)
		(end 137.601 59.2)
		(width 0.5)
		(layer "F.Cu")
		(net 40)
	)
	(segment
		(start 116.52 69.9)
		(end 115.8 69.9)
		(width 0.1)
		(layer "F.Cu")
		(net 40)
	)
	(via
		(at 139.75 63.75)
		(size 0.45)
		(drill 0.2)
		(layers "F.Cu" "B.Cu")
		(remove_unused_layers yes)
		(keep_end_layers yes)
		(free yes)
		(zone_layer_connections "In3.Cu")
		(net 40)
	)
	(via
		(at 130.264607 97.422956)
		(size 0.45)
		(drill 0.2)
		(layers "F.Cu" "B.Cu")
		(remove_unused_layers yes)
		(keep_end_layers yes)
		(zone_layer_connections "In3.Cu")
		(net 40)
	)
	(via
		(at 156.2 111.7)
		(size 0.45)
		(drill 0.2)
		(layers "F.Cu" "B.Cu")
		(remove_unused_layers yes)
		(keep_end_layers yes)
		(zone_layer_connections "In3.Cu")
		(net 40)
	)
	(via
		(at 139.25 63.25)
		(size 0.45)
		(drill 0.2)
		(layers "F.Cu" "B.Cu")
		(remove_unused_layers yes)
		(keep_end_layers yes)
		(free yes)
		(zone_layer_connections "In3.Cu")
		(net 40)
	)
	(via
		(at 155.3 112.699999)
		(size 0.45)
		(drill 0.2)
		(layers "F.Cu" "B.Cu")
		(remove_unused_layers yes)
		(keep_end_layers yes)
		(zone_layer_connections "In3.Cu")
		(net 40)
	)
	(via
		(at 155.3 114.7)
		(size 0.45)
		(drill 0.2)
		(layers "F.Cu" "B.Cu")
		(remove_unused_layers yes)
		(keep_end_layers yes)
		(zone_layer_connections "In3.Cu")
		(net 40)
	)
	(via
		(at 140 112.9)
		(size 0.45)
		(drill 0.2)
		(layers "F.Cu" "B.Cu")
		(remove_unused_layers yes)
		(keep_end_layers yes)
		(zone_layer_connections "In3.Cu")
		(net 40)
	)
	(via
		(at 163.9 113.700001)
		(size 0.45)
		(drill 0.2)
		(layers "F.Cu" "B.Cu")
		(remove_unused_layers yes)
		(keep_end_layers yes)
		(zone_layer_connections "In3.Cu")
		(net 40)
	)
	(via
		(at 115.8 71.9)
		(size 0.45)
		(drill 0.2)
		(layers "F.Cu" "B.Cu")
		(remove_unused_layers yes)
		(keep_end_layers yes)
		(zone_layer_connections "In3.Cu")
		(net 40)
	)
	(via
		(at 156.2 112.699999)
		(size 0.45)
		(drill 0.2)
		(layers "F.Cu" "B.Cu")
		(remove_unused_layers yes)
		(keep_end_layers yes)
		(zone_layer_connections "In3.Cu")
		(net 40)
	)
	(via
		(at 148.5 114.7)
		(size 0.45)
		(drill 0.2)
		(layers "F.Cu" "B.Cu")
		(remove_unused_layers yes)
		(keep_end_layers yes)
		(zone_layer_connections "In3.Cu")
		(net 40)
	)
	(via
		(at 140.9 112.2)
		(size 0.45)
		(drill 0.2)
		(layers "F.Cu" "B.Cu")
		(remove_unused_layers yes)
		(keep_end_layers yes)
		(zone_layer_connections "In3.Cu")
		(net 40)
	)
	(via
		(at 139.75 62.25)
		(size 0.45)
		(drill 0.2)
		(layers "F.Cu" "B.Cu")
		(remove_unused_layers yes)
		(keep_end_layers yes)
		(free yes)
		(zone_layer_connections "In3.Cu")
		(net 40)
	)
	(via
		(at 129.914607 96.972956)
		(size 0.45)
		(drill 0.2)
		(layers "F.Cu" "B.Cu")
		(remove_unused_layers yes)
		(keep_end_layers yes)
		(zone_layer_connections "In3.Cu")
		(net 40)
	)
	(via
		(at 156.2 114.7)
		(size 0.45)
		(drill 0.2)
		(layers "F.Cu" "B.Cu")
		(remove_unused_layers yes)
		(keep_end_layers yes)
		(zone_layer_connections "In3.Cu")
		(net 40)
	)
	(via
		(at 147.6 112.699999)
		(size 0.45)
		(drill 0.2)
		(layers "F.Cu" "B.Cu")
		(remove_unused_layers yes)
		(keep_end_layers yes)
		(zone_layer_connections "In3.Cu")
		(net 40)
	)
	(via
		(at 163 114.7)
		(size 0.45)
		(drill 0.2)
		(layers "F.Cu" "B.Cu")
		(remove_unused_layers yes)
		(keep_end_layers yes)
		(zone_layer_connections "In3.Cu")
		(net 40)
	)
	(via
		(at 129.564607 96.522956)
		(size 0.45)
		(drill 0.2)
		(layers "F.Cu" "B.Cu")
		(remove_unused_layers yes)
		(keep_end_layers yes)
		(zone_layer_connections "In3.Cu")
		(net 40)
	)
	(via
		(at 139.5 57.75)
		(size 0.45)
		(drill 0.2)
		(layers "F.Cu" "B.Cu")
		(remove_unused_layers yes)
		(keep_end_layers yes)
		(zone_layer_connections)
		(net 40)
	)
	(via
		(at 120.8 79.7)
		(size 0.45)
		(drill 0.2)
		(layers "F.Cu" "B.Cu")
		(remove_unused_layers yes)
		(keep_end_layers yes)
		(zone_layer_connections "In3.Cu")
		(net 40)
	)
	(via
		(at 115.8 69.9)
		(size 0.45)
		(drill 0.2)
		(layers "F.Cu" "B.Cu")
		(remove_unused_layers yes)
		(keep_end_layers yes)
		(zone_layer_connections "In3.Cu")
		(net 40)
	)
	(via
		(at 155.3 111.7)
		(size 0.45)
		(drill 0.2)
		(layers "F.Cu" "B.Cu")
		(remove_unused_layers yes)
		(keep_end_layers yes)
		(zone_layer_connections "In3.Cu")
		(net 40)
	)
	(via
		(at 140 112.2)
		(size 0.45)
		(drill 0.2)
		(layers "F.Cu" "B.Cu")
		(remove_unused_layers yes)
		(keep_end_layers yes)
		(zone_layer_connections "In3.Cu")
		(net 40)
	)
	(via
		(at 130.964607 96.522956)
		(size 0.45)
		(drill 0.2)
		(layers "F.Cu" "B.Cu")
		(remove_unused_layers yes)
		(keep_end_layers yes)
		(zone_layer_connections "In3.Cu")
		(net 40)
	)
	(via
		(at 163 112.699999)
		(size 0.45)
		(drill 0.2)
		(layers "F.Cu" "B.Cu")
		(remove_unused_layers yes)
		(keep_end_layers yes)
		(zone_layer_connections "In3.Cu")
		(net 40)
	)
	(via
		(at 163 113.700001)
		(size 0.45)
		(drill 0.2)
		(layers "F.Cu" "B.Cu")
		(remove_unused_layers yes)
		(keep_end_layers yes)
		(zone_layer_connections "In3.Cu")
		(net 40)
	)
	(via
		(at 163 111.7)
		(size 0.45)
		(drill 0.2)
		(layers "F.Cu" "B.Cu")
		(remove_unused_layers yes)
		(keep_end_layers yes)
		(zone_layer_connections "In3.Cu")
		(net 40)
	)
	(via
		(at 139.25 62.75)
		(size 0.45)
		(drill 0.2)
		(layers "F.Cu" "B.Cu")
		(remove_unused_layers yes)
		(keep_end_layers yes)
		(free yes)
		(zone_layer_connections "In3.Cu")
		(net 40)
	)
	(via
		(at 138.75 62.25)
		(size 0.45)
		(drill 0.2)
		(layers "F.Cu" "B.Cu")
		(remove_unused_layers yes)
		(keep_end_layers yes)
		(free yes)
		(zone_layer_connections "In3.Cu")
		(net 40)
	)
	(via
		(at 140.9 111.5)
		(size 0.45)
		(drill 0.2)
		(layers "F.Cu" "B.Cu")
		(remove_unused_layers yes)
		(keep_end_layers yes)
		(zone_layer_connections "In3.Cu")
		(net 40)
	)
	(via
		(at 138.75 62.75)
		(size 0.45)
		(drill 0.2)
		(layers "F.Cu" "B.Cu")
		(remove_unused_layers yes)
		(keep_end_layers yes)
		(free yes)
		(zone_layer_connections "In3.Cu")
		(net 40)
	)
	(via
		(at 138.75 63.75)
		(size 0.45)
		(drill 0.2)
		(layers "F.Cu" "B.Cu")
		(remove_unused_layers yes)
		(keep_end_layers yes)
		(free yes)
		(zone_layer_connections "In3.Cu")
		(net 40)
	)
	(via
		(at 129.564607 97.422956)
		(size 0.45)
		(drill 0.2)
		(layers "F.Cu" "B.Cu")
		(remove_unused_layers yes)
		(keep_end_layers yes)
		(zone_layer_connections "In3.Cu")
		(net 40)
	)
	(via
		(at 139.75 62.75)
		(size 0.45)
		(drill 0.2)
		(layers "F.Cu" "B.Cu")
		(remove_unused_layers yes)
		(keep_end_layers yes)
		(free yes)
		(zone_layer_connections "In3.Cu")
		(net 40)
	)
	(via
		(at 163.9 114.7)
		(size 0.45)
		(drill 0.2)
		(layers "F.Cu" "B.Cu")
		(remove_unused_layers yes)
		(keep_end_layers yes)
		(zone_layer_connections "In3.Cu")
		(net 40)
	)
	(via
		(at 163.9 112.699999)
		(size 0.45)
		(drill 0.2)
		(layers "F.Cu" "B.Cu")
		(remove_unused_layers yes)
		(keep_end_layers yes)
		(zone_layer_connections "In3.Cu")
		(net 40)
	)
	(via
		(at 120.8 80.3)
		(size 0.45)
		(drill 0.2)
		(layers "F.Cu" "B.Cu")
		(remove_unused_layers yes)
		(keep_end_layers yes)
		(zone_layer_connections "In3.Cu")
		(net 40)
	)
	(via
		(at 147.6 111.7)
		(size 0.45)
		(drill 0.2)
		(layers "F.Cu" "B.Cu")
		(remove_unused_layers yes)
		(keep_end_layers yes)
		(zone_layer_connections "In3.Cu")
		(net 40)
	)
	(via
		(at 156.2 113.700001)
		(size 0.45)
		(drill 0.2)
		(layers "F.Cu" "B.Cu")
		(remove_unused_layers yes)
		(keep_end_layers yes)
		(zone_layer_connections "In3.Cu")
		(net 40)
	)
	(via
		(at 148.5 112.699999)
		(size 0.45)
		(drill 0.2)
		(layers "F.Cu" "B.Cu")
		(remove_unused_layers yes)
		(keep_end_layers yes)
		(zone_layer_connections "In3.Cu")
		(net 40)
	)
	(via
		(at 147.6 114.7)
		(size 0.45)
		(drill 0.2)
		(layers "F.Cu" "B.Cu")
		(remove_unused_layers yes)
		(keep_end_layers yes)
		(zone_layer_connections "In3.Cu")
		(net 40)
	)
	(via
		(at 130.264607 96.522956)
		(size 0.45)
		(drill 0.2)
		(layers "F.Cu" "B.Cu")
		(remove_unused_layers yes)
		(keep_end_layers yes)
		(zone_layer_connections "In3.Cu")
		(net 40)
	)
	(via
		(at 140 111.5)
		(size 0.45)
		(drill 0.2)
		(layers "F.Cu" "B.Cu")
		(remove_unused_layers yes)
		(keep_end_layers yes)
		(zone_layer_connections "In3.Cu")
		(net 40)
	)
	(via
		(at 148.5 113.700001)
		(size 0.45)
		(drill 0.2)
		(layers "F.Cu" "B.Cu")
		(remove_unused_layers yes)
		(keep_end_layers yes)
		(zone_layer_connections "In3.Cu")
		(net 40)
	)
	(via
		(at 131.7 145.5)
		(size 0.45)
		(drill 0.2)
		(layers "F.Cu" "B.Cu")
		(remove_unused_layers yes)
		(keep_end_layers yes)
		(zone_layer_connections)
		(net 40)
	)
	(via
		(at 148.5 111.7)
		(size 0.45)
		(drill 0.2)
		(layers "F.Cu" "B.Cu")
		(remove_unused_layers yes)
		(keep_end_layers yes)
		(zone_layer_connections "In3.Cu")
		(net 40)
	)
	(via
		(at 140.45 111.85)
		(size 0.45)
		(drill 0.2)
		(layers "F.Cu" "B.Cu")
		(remove_unused_layers yes)
		(keep_end_layers yes)
		(zone_layer_connections "In3.Cu")
		(net 40)
	)
	(via
		(at 138.75 63.25)
		(size 0.45)
		(drill 0.2)
		(layers "F.Cu" "B.Cu")
		(remove_unused_layers yes)
		(keep_end_layers yes)
		(free yes)
		(zone_layer_connections "In3.Cu")
		(net 40)
	)
	(via
		(at 130.614607 96.972956)
		(size 0.45)
		(drill 0.2)
		(layers "F.Cu" "B.Cu")
		(remove_unused_layers yes)
		(keep_end_layers yes)
		(zone_layer_connections "In3.Cu")
		(net 40)
	)
	(via
		(at 163.9 111.7)
		(size 0.45)
		(drill 0.2)
		(layers "F.Cu" "B.Cu")
		(remove_unused_layers yes)
		(keep_end_layers yes)
		(zone_layer_connections "In3.Cu")
		(net 40)
	)
	(via
		(at 147.6 113.700001)
		(size 0.45)
		(drill 0.2)
		(layers "F.Cu" "B.Cu")
		(remove_unused_layers yes)
		(keep_end_layers yes)
		(zone_layer_connections "In3.Cu")
		(net 40)
	)
	(via
		(at 155.3 113.700001)
		(size 0.45)
		(drill 0.2)
		(layers "F.Cu" "B.Cu")
		(remove_unused_layers yes)
		(keep_end_layers yes)
		(zone_layer_connections "In3.Cu")
		(net 40)
	)
	(via
		(at 140.9 112.9)
		(size 0.45)
		(drill 0.2)
		(layers "F.Cu" "B.Cu")
		(remove_unused_layers yes)
		(keep_end_layers yes)
		(zone_layer_connections "In3.Cu")
		(net 40)
	)
	(via
		(at 139.25 62.25)
		(size 0.45)
		(drill 0.2)
		(layers "F.Cu" "B.Cu")
		(remove_unused_layers yes)
		(keep_end_layers yes)
		(free yes)
		(zone_layer_connections "In3.Cu")
		(net 40)
	)
	(via
		(at 140.45 112.55)
		(size 0.45)
		(drill 0.2)
		(layers "F.Cu" "B.Cu")
		(remove_unused_layers yes)
		(keep_end_layers yes)
		(zone_layer_connections "In3.Cu")
		(net 40)
	)
	(via
		(at 122.75 70)
		(size 0.45)
		(drill 0.2)
		(layers "F.Cu" "B.Cu")
		(remove_unused_layers yes)
		(keep_end_layers yes)
		(zone_layer_connections "In3.Cu")
		(net 40)
	)
	(via
		(at 130.964607 97.429814)
		(size 0.45)
		(drill 0.2)
		(layers "F.Cu" "B.Cu")
		(remove_unused_layers yes)
		(keep_end_layers yes)
		(zone_layer_connections "In3.Cu")
		(net 40)
	)
	(via
		(at 139.75 63.25)
		(size 0.45)
		(drill 0.2)
		(layers "F.Cu" "B.Cu")
		(remove_unused_layers yes)
		(keep_end_layers yes)
		(free yes)
		(zone_layer_connections "In3.Cu")
		(net 40)
	)
	(via
		(at 139.25 63.75)
		(size 0.45)
		(drill 0.2)
		(layers "F.Cu" "B.Cu")
		(remove_unused_layers yes)
		(keep_end_layers yes)
		(free yes)
		(zone_layer_connections "In3.Cu")
		(net 40)
	)
	(segment
		(start 140.25 57.75)
		(end 139.5 57.75)
		(width 0.1)
		(layer "B.Cu")
		(net 40)
	)
	(segment
		(start 120.799 81.1)
		(end 120.799 80.301)
		(width 0.5)
		(layer "B.Cu")
		(net 40)
	)
	(segment
		(start 120.8 80.3)
		(end 120.8 79.7)
		(width 0.5)
		(layer "B.Cu")
		(net 40)
	)
	(segment
		(start 120.799 80.301)
		(end 120.8 80.3)
		(width 0.5)
		(layer "B.Cu")
		(net 40)
	)
	(segment
		(start 120.799 81.1)
		(end 118.52 81.1)
		(width 0.5)
		(layer "B.Cu")
		(net 40)
	)
	(segment
		(start 118.52 81.1)
		(end 118.5 81.08)
		(width 0.5)
		(layer "B.Cu")
		(net 40)
	)
	(segment
		(start 140.65 146.4)
		(end 141.35 146.4)
		(width 0.25)
		(layer "In3.Cu")
		(net 40)
	)
	(segment
		(start 131.7 145.5)
		(end 135.8 145.5)
		(width 0.25)
		(layer "In3.Cu")
		(net 40)
	)
	(segment
		(start 149.8 129.75)
		(end 155.3 124.25)
		(width 0.25)
		(layer "In3.Cu")
		(net 40)
	)
	(segment
		(start 136.2 145.9)
		(end 140.15 145.9)
		(width 0.25)
		(layer "In3.Cu")
		(net 40)
	)
	(segment
		(start 135.8 145.5)
		(end 136.2 145.9)
		(width 0.25)
		(layer "In3.Cu")
		(net 40)
	)
	(segment
		(start 144.7 129.75)
		(end 149.8 129.75)
		(width 0.25)
		(layer "In3.Cu")
		(net 40)
	)
	(segment
		(start 140.15 145.9)
		(end 140.65 146.4)
		(width 0.25)
		(layer "In3.Cu")
		(net 40)
	)
	(segment
		(start 155.3 124.25)
		(end 155.3 114.7)
		(width 0.25)
		(layer "In3.Cu")
		(net 40)
	)
	(segment
		(start 141.6 146.15)
		(end 141.6 140.3)
		(width 0.25)
		(layer "In3.Cu")
		(net 40)
	)
	(segment
		(start 141.6 140.3)
		(end 142.5 139.4)
		(width 0.25)
		(layer "In3.Cu")
		(net 40)
	)
	(segment
		(start 141.35 146.4)
		(end 141.6 146.15)
		(width 0.25)
		(layer "In3.Cu")
		(net 40)
	)
	(segment
		(start 142.5 131.95)
		(end 144.7 129.75)
		(width 0.25)
		(layer "In3.Cu")
		(net 40)
	)
	(segment
		(start 142.5 139.4)
		(end 142.5 131.95)
		(width 0.25)
		(layer "In3.Cu")
		(net 40)
	)
	(via
		(at 160.945 87.25)
		(size 0.45)
		(drill 0.2)
		(layers "F.Cu" "B.Cu")
		(remove_unused_layers yes)
		(keep_end_layers yes)
		(zone_layer_connections)
		(net 41)
	)
	(segment
		(start 169.385027 120.11709)
		(end 169.691124 120.423187)
		(width 0.15)
		(layer "B.Cu")
		(net 41)
	)
	(segment
		(start 178.400001 110.897057)
		(end 178.400001 102.905025)
		(width 0.15)
		(layer "B.Cu")
		(net 41)
	)
	(segment
		(start 162.379226 87.425)
		(end 167.417032 87.425)
		(width 0.15)
		(layer "B.Cu")
		(net 41)
	)
	(segment
		(start 170.39116 120.423187)
		(end 170.504297 120.310049)
		(width 0.15)
		(layer "B.Cu")
		(net 41)
	)
	(segment
		(start 174.375 98.880024)
		(end 174.375 94.382968)
		(width 0.15)
		(layer "B.Cu")
		(net 41)
	)
	(segment
		(start 157.739088 123.35)
		(end 165.947058 123.35)
		(width 0.15)
		(layer "B.Cu")
		(net 41)
	)
	(segment
		(start 161.12 87.425)
		(end 161.749226 87.425)
		(width 0.15)
		(layer "B.Cu")
		(net 41)
	)
	(segment
		(start 155.28 130.032512)
		(end 154.575 129.327512)
		(width 0.15)
		(layer "B.Cu")
		(net 41)
	)
	(segment
		(start 160.945 87.25)
		(end 161.12 87.425)
		(width 0.15)
		(layer "B.Cu")
		(net 41)
	)
	(segment
		(start 174.375 94.382968)
		(end 167.417032 87.425)
		(width 0.15)
		(layer "B.Cu")
		(net 41)
	)
	(segment
		(start 155.28 132.52)
		(end 155.28 130.032512)
		(width 0.15)
		(layer "B.Cu")
		(net 41)
	)
	(segment
		(start 156.12 133.36)
		(end 155.28 132.52)
		(width 0.15)
		(layer "B.Cu")
		(net 41)
	)
	(segment
		(start 162.239226 87.115844)
		(end 162.239226 87.285)
		(width 0.15)
		(layer "B.Cu")
		(net 41)
	)
	(segment
		(start 161.889226 87.285)
		(end 161.889226 87.115844)
		(width 0.15)
		(layer "B.Cu")
		(net 41)
	)
	(segment
		(start 162.029226 86.975844)
		(end 162.099226 86.975844)
		(width 0.15)
		(layer "B.Cu")
		(net 41)
	)
	(segment
		(start 165.947058 123.35)
		(end 169.179967 120.117091)
		(width 0.15)
		(layer "B.Cu")
		(net 41)
	)
	(segment
		(start 170.523744 118.773314)
		(end 178.400001 110.897057)
		(width 0.15)
		(layer "B.Cu")
		(net 41)
	)
	(segment
		(start 169.179967 120.117091)
		(end 169.179966 120.11709)
		(width 0.15)
		(layer "B.Cu")
		(net 41)
	)
	(segment
		(start 170.198199 119.098855)
		(end 170.311337 118.985719)
		(width 0.15)
		(layer "B.Cu")
		(net 41)
	)
	(segment
		(start 170.311337 118.985719)
		(end 170.523744 118.773314)
		(width 0.15)
		(layer "B.Cu")
		(net 41)
	)
	(segment
		(start 178.400001 102.905025)
		(end 174.375 98.880024)
		(width 0.15)
		(layer "B.Cu")
		(net 41)
	)
	(segment
		(start 170.504297 119.610014)
		(end 170.198199 119.303916)
		(width 0.15)
		(layer "B.Cu")
		(net 41)
	)
	(segment
		(start 154.575 129.327512)
		(end 154.575 126.514088)
		(width 0.15)
		(layer "B.Cu")
		(net 41)
	)
	(segment
		(start 154.575 126.514088)
		(end 157.739088 123.35)
		(width 0.15)
		(layer "B.Cu")
		(net 41)
	)
	(arc
		(start 161.749226 87.425)
		(mid 161.848221 87.383995)
		(end 161.889226 87.285)
		(width 0.15)
		(layer "B.Cu")
		(net 41)
	)
	(arc
		(start 162.239226 87.285)
		(mid 162.280231 87.383995)
		(end 162.379226 87.425)
		(width 0.15)
		(layer "B.Cu")
		(net 41)
	)
	(arc
		(start 169.691124 120.423187)
		(mid 170.041142 120.568169)
		(end 170.39116 120.423187)
		(width 0.15)
		(layer "B.Cu")
		(net 41)
	)
	(arc
		(start 162.099226 86.975844)
		(mid 162.198221 87.016849)
		(end 162.239226 87.115844)
		(width 0.15)
		(layer "B.Cu")
		(net 41)
	)
	(arc
		(start 170.504297 120.310049)
		(mid 170.649279 119.960031)
		(end 170.504297 119.610014)
		(width 0.15)
		(layer "B.Cu")
		(net 41)
	)
	(arc
		(start 161.889226 87.115844)
		(mid 161.930231 87.016849)
		(end 162.029226 86.975844)
		(width 0.15)
		(layer "B.Cu")
		(net 41)
	)
	(arc
		(start 170.198199 119.303916)
		(mid 170.155729 119.201386)
		(end 170.198199 119.098855)
		(width 0.15)
		(layer "B.Cu")
		(net 41)
	)
	(arc
		(start 169.179966 120.11709)
		(mid 169.282496 120.074621)
		(end 169.385027 120.11709)
		(width 0.15)
		(layer "B.Cu")
		(net 41)
	)
	(via
		(at 160.08 90.75)
		(size 0.45)
		(drill 0.2)
		(layers "F.Cu" "B.Cu")
		(remove_unused_layers yes)
		(keep_end_layers yes)
		(zone_layer_connections)
		(net 42)
	)
	(segment
		(start 170.425 96.019112)
		(end 165.180888 90.775)
		(width 0.15)
		(layer "B.Cu")
		(net 42)
	)
	(segment
		(start 166.4 111.703267)
		(end 166.050002 111.703267)
		(width 0.15)
		(layer "B.Cu")
		(net 42)
	)
	(segment
		(start 170.425 100.382972)
		(end 170.425 96.019112)
		(width 0.15)
		(layer "B.Cu")
		(net 42)
	)
	(segment
		(start 164.756102 111.168268)
		(end 164.756102 110.988268)
		(width 0.15)
		(layer "B.Cu")
		(net 42)
	)
	(segment
		(start 166.55 113.978269)
		(end 166.55 113.578267)
		(width 0.15)
		(layer "B.Cu")
		(net 42)
	)
	(segment
		(start 166.050002 108.288268)
		(end 166.050001 104.757971)
		(width 0.15)
		(layer "B.Cu")
		(net 42)
	)
	(segment
		(start 164.750561 112.968268)
		(end 164.750561 112.788268)
		(width 0.15)
		(layer "B.Cu")
		(net 42)
	)
	(segment
		(start 166.050001 104.757971)
		(end 166.500997 104.306975)
		(width 0.15)
		(layer "B.Cu")
		(net 42)
	)
	(segment
		(start 164.079078 117.748848)
		(end 164.100624 117.770394)
		(width 0.15)
		(layer "B.Cu")
		(net 42)
	)
	(segment
		(start 166.55 112.178269)
		(end 166.55 111.778267)
		(width 0.15)
		(layer "B.Cu")
		(net 42)
	)
	(segment
		(start 166.4 109.903267)
		(end 165.865001 109.903267)
		(width 0.15)
		(layer "B.Cu")
		(net 42)
	)
	(segment
		(start 148.825 132.51)
		(end 148.825 131.527512)
		(width 0.15)
		(layer "B.Cu")
		(net 42)
	)
	(segment
		(start 164.747784 114.768268)
		(end 164.747784 114.588268)
		(width 0.15)
		(layer "B.Cu")
		(net 42)
	)
	(segment
		(start 150.625 124.877944)
		(end 156.102943 119.400001)
		(width 0.15)
		(layer "B.Cu")
		(net 42)
	)
	(segment
		(start 165.865001 109.903267)
		(end 165.313318 109.903267)
		(width 0.15)
		(layer "B.Cu")
		(net 42)
	)
	(segment
		(start 166.55 110.378269)
		(end 166.55 109.978267)
		(width 0.15)
		(layer "B.Cu")
		(net 42)
	)
	(segment
		(start 166.050002 111.703267)
		(end 165.291101 111.703267)
		(width 0.15)
		(layer "B.Cu")
		(net 42)
	)
	(segment
		(start 165.875464 116.227481)
		(end 166.050001 116.052945)
		(width 0.15)
		(layer "B.Cu")
		(net 42)
	)
	(segment
		(start 147.985 133.35)
		(end 148.825 132.51)
		(width 0.15)
		(layer "B.Cu")
		(net 42)
	)
	(segment
		(start 164.778319 109.368268)
		(end 164.778319 109.188268)
		(width 0.15)
		(layer "B.Cu")
		(net 42)
	)
	(segment
		(start 165.865001 115.303267)
		(end 165.282783 115.303267)
		(width 0.15)
		(layer "B.Cu")
		(net 42)
	)
	(segment
		(start 165.282783 114.053269)
		(end 165.865001 114.053269)
		(width 0.15)
		(layer "B.Cu")
		(net 42)
	)
	(segment
		(start 163.810709 118.060306)
		(end 163.789164 118.038761)
		(width 0.15)
		(layer "B.Cu")
		(net 42)
	)
	(segment
		(start 166.050002 113.503267)
		(end 165.28556 113.503267)
		(width 0.15)
		(layer "B.Cu")
		(net 42)
	)
	(segment
		(start 164.332556 117.770393)
		(end 164.390537 117.71241)
		(width 0.15)
		(layer "B.Cu")
		(net 42)
	)
	(segment
		(start 165.313318 108.653269)
		(end 165.865001 108.653269)
		(width 0.15)
		(layer "B.Cu")
		(net 42)
	)
	(segment
		(start 166.500997 104.306975)
		(end 170.425 100.382972)
		(width 0.15)
		(layer "B.Cu")
		(net 42)
	)
	(segment
		(start 166.4 110.453269)
		(end 166.475 110.453269)
		(width 0.15)
		(layer "B.Cu")
		(net 42)
	)
	(segment
		(start 166.050001 116.052945)
		(end 166.050001 115.488268)
		(width 0.15)
		(layer "B.Cu")
		(net 42)
	)
	(segment
		(start 148.825 131.527512)
		(end 150.625 129.727512)
		(width 0.15)
		(layer "B.Cu")
		(net 42)
	)
	(segment
		(start 166.4 114.053269)
		(end 166.475 114.053269)
		(width 0.15)
		(layer "B.Cu")
		(net 42)
	)
	(segment
		(start 166.475 113.503267)
		(end 166.4 113.503267)
		(width 0.15)
		(layer "B.Cu")
		(net 42)
	)
	(segment
		(start 166.050002 112.253269)
		(end 166.4 112.253269)
		(width 0.15)
		(layer "B.Cu")
		(net 42)
	)
	(segment
		(start 163.789163 117.806831)
		(end 163.847148 117.748847)
		(width 0.15)
		(layer "B.Cu")
		(net 42)
	)
	(segment
		(start 165.865001 114.053269)
		(end 166.4 114.053269)
		(width 0.15)
		(layer "B.Cu")
		(net 42)
	)
	(segment
		(start 164.390537 117.71241)
		(end 165.875464 116.227481)
		(width 0.15)
		(layer "B.Cu")
		(net 42)
	)
	(segment
		(start 166.4 113.503267)
		(end 166.050002 113.503267)
		(width 0.15)
		(layer "B.Cu")
		(net 42)
	)
	(segment
		(start 165.180888 90.775)
		(end 160.105 90.775)
		(width 0.15)
		(layer "B.Cu")
		(net 42)
	)
	(segment
		(start 160.105 90.775)
		(end 160.08 90.75)
		(width 0.15)
		(layer "B.Cu")
		(net 42)
	)
	(segment
		(start 150.625 129.727512)
		(end 150.625 124.877944)
		(width 0.15)
		(layer "B.Cu")
		(net 42)
	)
	(segment
		(start 166.475 109.903267)
		(end 166.4 109.903267)
		(width 0.15)
		(layer "B.Cu")
		(net 42)
	)
	(segment
		(start 156.102943 119.400001)
		(end 162.702945 119.400001)
		(width 0.15)
		(layer "B.Cu")
		(net 42)
	)
	(segment
		(start 166.050001 115.488268)
		(end 166.050002 115.488268)
		(width 0.15)
		(layer "B.Cu")
		(net 42)
	)
	(segment
		(start 166.050002 108.468268)
		(end 166.050002 108.288268)
		(width 0.15)
		(layer "B.Cu")
		(net 42)
	)
	(segment
		(start 166.4 112.253269)
		(end 166.475 112.253269)
		(width 0.15)
		(layer "B.Cu")
		(net 42)
	)
	(segment
		(start 165.28556 112.253269)
		(end 166.050002 112.253269)
		(width 0.15)
		(layer "B.Cu")
		(net 42)
	)
	(segment
		(start 166.475 111.703267)
		(end 166.4 111.703267)
		(width 0.15)
		(layer "B.Cu")
		(net 42)
	)
	(segment
		(start 166.050002 110.453269)
		(end 166.4 110.453269)
		(width 0.15)
		(layer "B.Cu")
		(net 42)
	)
	(segment
		(start 162.702945 119.400001)
		(end 163.810708 118.292238)
		(width 0.15)
		(layer "B.Cu")
		(net 42)
	)
	(segment
		(start 165.291101 110.453269)
		(end 166.050002 110.453269)
		(width 0.15)
		(layer "B.Cu")
		(net 42)
	)
	(arc
		(start 164.747784 114.588268)
		(mid 164.904482 114.209967)
		(end 165.282783 114.053269)
		(width 0.15)
		(layer "B.Cu")
		(net 42)
	)
	(arc
		(start 166.55 109.978267)
		(mid 166.528033 109.925234)
		(end 166.475 109.903267)
		(width 0.15)
		(layer "B.Cu")
		(net 42)
	)
	(arc
		(start 165.282783 115.303267)
		(mid 164.904482 115.146569)
		(end 164.747784 114.768268)
		(width 0.15)
		(layer "B.Cu")
		(net 42)
	)
	(arc
		(start 164.756102 110.988268)
		(mid 164.9128 110.609967)
		(end 165.291101 110.453269)
		(width 0.15)
		(layer "B.Cu")
		(net 42)
	)
	(arc
		(start 165.28556 113.503267)
		(mid 164.907259 113.346569)
		(end 164.750561 112.968268)
		(width 0.15)
		(layer "B.Cu")
		(net 42)
	)
	(arc
		(start 166.55 111.778267)
		(mid 166.528033 111.725234)
		(end 166.475 111.703267)
		(width 0.15)
		(layer "B.Cu")
		(net 42)
	)
	(arc
		(start 165.291101 111.703267)
		(mid 164.9128 111.546569)
		(end 164.756102 111.168268)
		(width 0.15)
		(layer "B.Cu")
		(net 42)
	)
	(arc
		(start 165.313318 109.903267)
		(mid 164.935017 109.746569)
		(end 164.778319 109.368268)
		(width 0.15)
		(layer "B.Cu")
		(net 42)
	)
	(arc
		(start 164.100624 117.770394)
		(mid 164.216589 117.818429)
		(end 164.332556 117.770393)
		(width 0.15)
		(layer "B.Cu")
		(net 42)
	)
	(arc
		(start 166.475 110.453269)
		(mid 166.528033 110.431302)
		(end 166.55 110.378269)
		(width 0.15)
		(layer "B.Cu")
		(net 42)
	)
	(arc
		(start 164.778319 109.188268)
		(mid 164.935017 108.809967)
		(end 165.313318 108.653269)
		(width 0.15)
		(layer "B.Cu")
		(net 42)
	)
	(arc
		(start 166.475 114.053269)
		(mid 166.528033 114.031302)
		(end 166.55 113.978269)
		(width 0.15)
		(layer "B.Cu")
		(net 42)
	)
	(arc
		(start 166.55 113.578267)
		(mid 166.528033 113.525234)
		(end 166.475 113.503267)
		(width 0.15)
		(layer "B.Cu")
		(net 42)
	)
	(arc
		(start 166.050002 115.488268)
		(mid 165.995816 115.357453)
		(end 165.865001 115.303267)
		(width 0.15)
		(layer "B.Cu")
		(net 42)
	)
	(arc
		(start 163.789164 118.038761)
		(mid 163.74113 117.922795)
		(end 163.789163 117.806831)
		(width 0.15)
		(layer "B.Cu")
		(net 42)
	)
	(arc
		(start 166.475 112.253269)
		(mid 166.528033 112.231302)
		(end 166.55 112.178269)
		(width 0.15)
		(layer "B.Cu")
		(net 42)
	)
	(arc
		(start 163.847148 117.748847)
		(mid 163.963113 117.700813)
		(end 164.079078 117.748848)
		(width 0.15)
		(layer "B.Cu")
		(net 42)
	)
	(arc
		(start 163.810708 118.292238)
		(mid 163.858743 118.176272)
		(end 163.810709 118.060306)
		(width 0.15)
		(layer "B.Cu")
		(net 42)
	)
	(arc
		(start 165.865001 108.653269)
		(mid 165.995816 108.599083)
		(end 166.050002 108.468268)
		(width 0.15)
		(layer "B.Cu")
		(net 42)
	)
	(arc
		(start 164.750561 112.788268)
		(mid 164.907259 112.409967)
		(end 165.28556 112.253269)
		(width 0.15)
		(layer "B.Cu")
		(net 42)
	)
	(via
		(at 160.08 87.75)
		(size 0.45)
		(drill 0.2)
		(layers "F.Cu" "B.Cu")
		(remove_unused_layers yes)
		(keep_end_layers yes)
		(zone_layer_connections)
		(net 43)
	)
	(segment
		(start 154.225 129.472488)
		(end 154.225 126.369112)
		(width 0.15)
		(layer "B.Cu")
		(net 43)
	)
	(segment
		(start 174.025 94.527944)
		(end 167.272056 87.775)
		(width 0.15)
		(layer "B.Cu")
		(net 43)
	)
	(segment
		(start 178.05 110.752082)
		(end 178.05 103.05)
		(width 0.15)
		(layer "B.Cu")
		(net 43)
	)
	(segment
		(start 154.225 126.369112)
		(end 157.594113 122.999999)
		(width 0.15)
		(layer "B.Cu")
		(net 43)
	)
	(segment
		(start 170.25681 119.857501)
		(end 169.950712 119.551403)
		(width 0.15)
		(layer "B.Cu")
		(net 43)
	)
	(segment
		(start 173.015258 115.786823)
		(end 173.194217 115.607865)
		(width 0.15)
		(layer "B.Cu")
		(net 43)
	)
	(segment
		(start 169.632515 119.869603)
		(end 169.938612 120.1757)
		(width 0.15)
		(layer "B.Cu")
		(net 43)
	)
	(segment
		(start 170.975369 117.324905)
		(end 171.03194 117.268335)
		(width 0.15)
		(layer "B.Cu")
		(net 43)
	)
	(segment
		(start 154.93 132.52)
		(end 154.93 130.177488)
		(width 0.15)
		(layer "B.Cu")
		(net 43)
	)
	(segment
		(start 167.272056 87.775)
		(end 160.105 87.775)
		(width 0.15)
		(layer "B.Cu")
		(net 43)
	)
	(segment
		(start 173.194217 115.607865)
		(end 178.05 110.752082)
		(width 0.15)
		(layer "B.Cu")
		(net 43)
	)
	(segment
		(start 174.025 99.025)
		(end 174.025 94.527944)
		(width 0.15)
		(layer "B.Cu")
		(net 43)
	)
	(segment
		(start 154.93 130.177488)
		(end 154.225 129.472488)
		(width 0.15)
		(layer "B.Cu")
		(net 43)
	)
	(segment
		(start 171.565686 117.236397)
		(end 173.015258 115.786823)
		(width 0.15)
		(layer "B.Cu")
		(net 43)
	)
	(segment
		(start 160.105 87.775)
		(end 160.08 87.75)
		(width 0.15)
		(layer "B.Cu")
		(net 43)
	)
	(segment
		(start 170.143673 120.1757)
		(end 170.25681 120.062562)
		(width 0.15)
		(layer "B.Cu")
		(net 43)
	)
	(segment
		(start 165.802083 122.999999)
		(end 168.932479 119.869603)
		(width 0.15)
		(layer "B.Cu")
		(net 43)
	)
	(segment
		(start 178.05 103.05)
		(end 174.025 99.025)
		(width 0.15)
		(layer "B.Cu")
		(net 43)
	)
	(segment
		(start 171.509119 117.292966)
		(end 171.565686 117.236397)
		(width 0.15)
		(layer "B.Cu")
		(net 43)
	)
	(segment
		(start 170.999999 117.575809)
		(end 170.975369 117.551179)
		(width 0.15)
		(layer "B.Cu")
		(net 43)
	)
	(segment
		(start 157.594113 122.999999)
		(end 165.802083 122.999999)
		(width 0.15)
		(layer "B.Cu")
		(net 43)
	)
	(segment
		(start 170.276256 118.525826)
		(end 170.999999 117.802083)
		(width 0.15)
		(layer "B.Cu")
		(net 43)
	)
	(segment
		(start 169.950712 118.851367)
		(end 170.06385 118.738232)
		(width 0.15)
		(layer "B.Cu")
		(net 43)
	)
	(segment
		(start 170.06385 118.738232)
		(end 170.276256 118.525826)
		(width 0.15)
		(layer "B.Cu")
		(net 43)
	)
	(segment
		(start 171.258214 117.268335)
		(end 171.282845 117.292966)
		(width 0.15)
		(layer "B.Cu")
		(net 43)
	)
	(segment
		(start 154.09 133.36)
		(end 154.93 132.52)
		(width 0.15)
		(layer "B.Cu")
		(net 43)
	)
	(arc
		(start 169.938612 120.1757)
		(mid 170.041143 120.218169)
		(end 170.143673 120.1757)
		(width 0.15)
		(layer "B.Cu")
		(net 43)
	)
	(arc
		(start 171.03194 117.268335)
		(mid 171.145077 117.221472)
		(end 171.258214 117.268335)
		(width 0.15)
		(layer "B.Cu")
		(net 43)
	)
	(arc
		(start 168.932479 119.869603)
		(mid 169.282497 119.724621)
		(end 169.632515 119.869603)
		(width 0.15)
		(layer "B.Cu")
		(net 43)
	)
	(arc
		(start 170.25681 120.062562)
		(mid 170.29928 119.960031)
		(end 170.25681 119.857501)
		(width 0.15)
		(layer "B.Cu")
		(net 43)
	)
	(arc
		(start 170.975369 117.551179)
		(mid 170.928506 117.438042)
		(end 170.975369 117.324905)
		(width 0.15)
		(layer "B.Cu")
		(net 43)
	)
	(arc
		(start 171.282845 117.292966)
		(mid 171.395982 117.339829)
		(end 171.509119 117.292966)
		(width 0.15)
		(layer "B.Cu")
		(net 43)
	)
	(arc
		(start 169.950712 119.551403)
		(mid 169.80573 119.201385)
		(end 169.950712 118.851367)
		(width 0.15)
		(layer "B.Cu")
		(net 43)
	)
	(arc
		(start 170.999999 117.802083)
		(mid 171.046862 117.688946)
		(end 170.999999 117.575809)
		(width 0.15)
		(layer "B.Cu")
		(net 43)
	)
	(via
		(at 160.08 88.75)
		(size 0.45)
		(drill 0.2)
		(layers "F.Cu" "B.Cu")
		(remove_unused_layers yes)
		(keep_end_layers yes)
		(zone_layer_connections)
		(net 44)
	)
	(segment
		(start 169.778533 117.050614)
		(end 169.803337 117.075418)
		(width 0.15)
		(layer "B.Cu")
		(net 44)
	)
	(segment
		(start 172.487802 114.617224)
		(end 176.850001 110.255025)
		(width 0.15)
		(layer "B.Cu")
		(net 44)
	)
	(segment
		(start 172.825 99.522054)
		(end 172.825 95.025)
		(width 0.15)
		(layer "B.Cu")
		(net 44)
	)
	(segment
		(start 153.07 135.9)
		(end 153.91 135.06)
		(width 0.15)
		(layer "B.Cu")
		(net 44)
	)
	(segment
		(start 153.507512 134.61)
		(end 152.907512 134.61)
		(width 0.15)
		(layer "B.Cu")
		(net 44)
	)
	(segment
		(start 169.520491 117.358261)
		(end 169.495688 117.333458)
		(width 0.15)
		(layer "B.Cu")
		(net 44)
	)
	(segment
		(start 166.575 88.775)
		(end 160.105 88.775)
		(width 0.15)
		(layer "B.Cu")
		(net 44)
	)
	(segment
		(start 170.086178 117.018849)
		(end 172.487802 114.617224)
		(width 0.15)
		(layer "B.Cu")
		(net 44)
	)
	(segment
		(start 152.405 131.547512)
		(end 153.025 130.927512)
		(width 0.15)
		(layer "B.Cu")
		(net 44)
	)
	(segment
		(start 172.825 95.025)
		(end 166.575 88.775)
		(width 0.15)
		(layer "B.Cu")
		(net 44)
	)
	(segment
		(start 170.029611 117.075418)
		(end 170.086178 117.018849)
		(width 0.15)
		(layer "B.Cu")
		(net 44)
	)
	(segment
		(start 153.025 125.872056)
		(end 157.097057 121.799999)
		(width 0.15)
		(layer "B.Cu")
		(net 44)
	)
	(segment
		(start 160.105 88.775)
		(end 160.08 88.75)
		(width 0.15)
		(layer "B.Cu")
		(net 44)
	)
	(segment
		(start 176.850001 103.547055)
		(end 172.825 99.522054)
		(width 0.15)
		(layer "B.Cu")
		(net 44)
	)
	(segment
		(start 176.850001 110.255025)
		(end 176.850001 103.547055)
		(width 0.15)
		(layer "B.Cu")
		(net 44)
	)
	(segment
		(start 157.097057 121.799999)
		(end 165.305027 121.799999)
		(width 0.15)
		(layer "B.Cu")
		(net 44)
	)
	(segment
		(start 153.91 135.06)
		(end 153.91 135.012488)
		(width 0.15)
		(layer "B.Cu")
		(net 44)
	)
	(segment
		(start 152.405 134.107488)
		(end 152.405 131.547512)
		(width 0.15)
		(layer "B.Cu")
		(net 44)
	)
	(segment
		(start 169.495688 117.107184)
		(end 169.552259 117.050614)
		(width 0.15)
		(layer "B.Cu")
		(net 44)
	)
	(segment
		(start 153.91 135.012488)
		(end 153.507512 134.61)
		(width 0.15)
		(layer "B.Cu")
		(net 44)
	)
	(segment
		(start 153.025 130.927512)
		(end 153.025 125.872056)
		(width 0.15)
		(layer "B.Cu")
		(net 44)
	)
	(segment
		(start 165.305027 121.799999)
		(end 169.520491 117.584535)
		(width 0.15)
		(layer "B.Cu")
		(net 44)
	)
	(segment
		(start 152.907512 134.61)
		(end 152.405 134.107488)
		(width 0.15)
		(layer "B.Cu")
		(net 44)
	)
	(arc
		(start 169.520491 117.584535)
		(mid 169.567354 117.471398)
		(end 169.520491 117.358261)
		(width 0.15)
		(layer "B.Cu")
		(net 44)
	)
	(arc
		(start 169.495688 117.333458)
		(mid 169.448825 117.220321)
		(end 169.495688 117.107184)
		(width 0.15)
		(layer "B.Cu")
		(net 44)
	)
	(arc
		(start 169.552259 117.050614)
		(mid 169.665396 117.003751)
		(end 169.778533 117.050614)
		(width 0.15)
		(layer "B.Cu")
		(net 44)
	)
	(arc
		(start 169.803337 117.075418)
		(mid 169.916474 117.122281)
		(end 170.029611 117.075418)
		(width 0.15)
		(layer "B.Cu")
		(net 44)
	)
	(via
		(at 160.08 82.75)
		(size 0.45)
		(drill 0.2)
		(layers "F.Cu" "B.Cu")
		(remove_unused_layers yes)
		(keep_end_layers yes)
		(zone_layer_connections)
		(net 45)
	)
	(segment
		(start 180.225176 118.502934)
		(end 180.135717 118.413475)
		(width 0.15)
		(layer "B.Cu")
		(net 45)
	)
	(segment
		(start 175.825 129.372488)
		(end 175.825 121.877082)
		(width 0.15)
		(layer "B.Cu")
		(net 45)
	)
	(segment
		(start 183.35 114.352082)
		(end 183.35 112.685513)
		(width 0.15)
		(layer "B.Cu")
		(net 45)
	)
	(segment
		(start 182.340292 115.36179)
		(end 183.35 114.352082)
		(width 0.15)
		(layer "B.Cu")
		(net 45)
	)
	(segment
		(start 183.35 111.485513)
		(end 183.35 109.403905)
		(width 0.15)
		(layer "B.Cu")
		(net 45)
	)
	(segment
		(start 170.872054 82.775)
		(end 160.105 82.775)
		(width 0.15)
		(layer "B.Cu")
		(net 45)
	)
	(segment
		(start 180.285626 117.416457)
		(end 182.340292 115.36179)
		(width 0.15)
		(layer "B.Cu")
		(net 45)
	)
	(segment
		(start 180.135717 117.566363)
		(end 180.285626 117.416457)
		(width 0.15)
		(layer "B.Cu")
		(net 45)
	)
	(segment
		(start 182.968938 112.304451)
		(end 182.968938 112.085513)
		(width 0.15)
		(layer "B.Cu")
		(net 45)
	)
	(segment
		(start 176.115 133.335)
		(end 176.955 132.495)
		(width 0.15)
		(layer "B.Cu")
		(net 45)
	)
	(segment
		(start 176.955 130.502488)
		(end 175.825 129.372488)
		(width 0.15)
		(layer "B.Cu")
		(net 45)
	)
	(segment
		(start 175.825 121.877082)
		(end 178.786559 118.915523)
		(width 0.15)
		(layer "B.Cu")
		(net 45)
	)
	(segment
		(start 183.35 111.704451)
		(end 183.35 111.485513)
		(width 0.15)
		(layer "B.Cu")
		(net 45)
	)
	(segment
		(start 180.07527 119.004982)
		(end 180.225176 118.855075)
		(width 0.15)
		(layer "B.Cu")
		(net 45)
	)
	(segment
		(start 183.35 95.252946)
		(end 170.872054 82.775)
		(width 0.15)
		(layer "B.Cu")
		(net 45)
	)
	(segment
		(start 178.786559 118.915523)
		(end 178.78656 118.915524)
		(width 0.15)
		(layer "B.Cu")
		(net 45)
	)
	(segment
		(start 183.35 109.403905)
		(end 183.35 95.252946)
		(width 0.15)
		(layer "B.Cu")
		(net 45)
	)
	(segment
		(start 160.105 82.775)
		(end 160.08 82.75)
		(width 0.15)
		(layer "B.Cu")
		(net 45)
	)
	(segment
		(start 176.955 132.495)
		(end 176.955 130.502488)
		(width 0.15)
		(layer "B.Cu")
		(net 45)
	)
	(segment
		(start 179.633672 118.915524)
		(end 179.72313 119.004982)
		(width 0.15)
		(layer "B.Cu")
		(net 45)
	)
	(arc
		(start 180.225176 118.855075)
		(mid 180.298107 118.679004)
		(end 180.225176 118.502934)
		(width 0.15)
		(layer "B.Cu")
		(net 45)
	)
	(arc
		(start 182.968938 112.085513)
		(mid 183.024743 111.950787)
		(end 183.159469 111.894982)
		(width 0.15)
		(layer "B.Cu")
		(net 45)
	)
	(arc
		(start 183.35 112.685513)
		(mid 183.294195 112.550787)
		(end 183.159469 112.494982)
		(width 0.15)
		(layer "B.Cu")
		(net 45)
	)
	(arc
		(start 179.72313 119.004982)
		(mid 179.8992 119.077913)
		(end 180.07527 119.004982)
		(width 0.15)
		(layer "B.Cu")
		(net 45)
	)
	(arc
		(start 183.159469 111.894982)
		(mid 183.294195 111.839177)
		(end 183.35 111.704451)
		(width 0.15)
		(layer "B.Cu")
		(net 45)
	)
	(arc
		(start 180.135717 118.413475)
		(mid 179.960274 117.989919)
		(end 180.135717 117.566363)
		(width 0.15)
		(layer "B.Cu")
		(net 45)
	)
	(arc
		(start 178.78656 118.915524)
		(mid 179.210116 118.740081)
		(end 179.633672 118.915524)
		(width 0.15)
		(layer "B.Cu")
		(net 45)
	)
	(arc
		(start 183.159469 112.494982)
		(mid 183.024743 112.439177)
		(end 182.968938 112.304451)
		(width 0.15)
		(layer "B.Cu")
		(net 45)
	)
	(via
		(at 160.945 83.25)
		(size 0.45)
		(drill 0.2)
		(layers "F.Cu" "B.Cu")
		(remove_unused_layers yes)
		(keep_end_layers yes)
		(zone_layer_connections)
		(net 46)
	)
	(segment
		(start 162.942574 83.425)
		(end 170.319974 83.425)
		(width 0.15)
		(layer "B.Cu")
		(net 46)
	)
	(segment
		(start 162.102574 83.280382)
		(end 162.102574 83.285)
		(width 0.15)
		(layer "B.Cu")
		(net 46)
	)
	(segment
		(start 176.285 135.035)
		(end 176.285 134.842512)
		(width 0.15)
		(layer "B.Cu")
		(net 46)
	)
	(segment
		(start 174.78 133.937512)
		(end 174.78 121.72)
		(width 0.15)
		(layer "B.Cu")
		(net 46)
	)
	(segment
		(start 175.077488 134.235)
		(end 174.78 133.937512)
		(width 0.15)
		(layer "B.Cu")
		(net 46)
	)
	(segment
		(start 174.78 121.72)
		(end 182.5 114)
		(width 0.15)
		(layer "B.Cu")
		(net 46)
	)
	(segment
		(start 161.892574 83.140382)
		(end 161.962574 83.140382)
		(width 0.15)
		(layer "B.Cu")
		(net 46)
	)
	(segment
		(start 162.802574 83.280382)
		(end 162.802574 83.285)
		(width 0.15)
		(layer "B.Cu")
		(net 46)
	)
	(segment
		(start 175.677488 134.235)
		(end 175.077488 134.235)
		(width 0.15)
		(layer "B.Cu")
		(net 46)
	)
	(segment
		(start 161.12 83.425)
		(end 161.612574 83.425)
		(width 0.15)
		(layer "B.Cu")
		(net 46)
	)
	(segment
		(start 182.5 114)
		(end 182.5 95.605026)
		(width 0.15)
		(layer "B.Cu")
		(net 46)
	)
	(segment
		(start 182.5 95.605026)
		(end 170.319974 83.425)
		(width 0.15)
		(layer "B.Cu")
		(net 46)
	)
	(segment
		(start 162.242574 83.425)
		(end 162.312574 83.425)
		(width 0.15)
		(layer "B.Cu")
		(net 46)
	)
	(segment
		(start 161.752574 83.285)
		(end 161.752574 83.280382)
		(width 0.15)
		(layer "B.Cu")
		(net 46)
	)
	(segment
		(start 162.452574 83.285)
		(end 162.452574 83.280382)
		(width 0.15)
		(layer "B.Cu")
		(net 46)
	)
	(segment
		(start 177.125 135.875)
		(end 176.285 135.035)
		(width 0.15)
		(layer "B.Cu")
		(net 46)
	)
	(segment
		(start 162.592574 83.140382)
		(end 162.662574 83.140382)
		(width 0.15)
		(layer "B.Cu")
		(net 46)
	)
	(segment
		(start 160.945 83.25)
		(end 161.12 83.425)
		(width 0.15)
		(layer "B.Cu")
		(net 46)
	)
	(segment
		(start 176.285 134.842512)
		(end 175.677488 134.235)
		(width 0.15)
		(layer "B.Cu")
		(net 46)
	)
	(arc
		(start 161.752574 83.280382)
		(mid 161.793579 83.181387)
		(end 161.892574 83.140382)
		(width 0.15)
		(layer "B.Cu")
		(net 46)
	)
	(arc
		(start 162.102574 83.285)
		(mid 162.143579 83.383995)
		(end 162.242574 83.425)
		(width 0.15)
		(layer "B.Cu")
		(net 46)
	)
	(arc
		(start 162.452574 83.280382)
		(mid 162.493579 83.181387)
		(end 162.592574 83.140382)
		(width 0.15)
		(layer "B.Cu")
		(net 46)
	)
	(arc
		(start 162.662574 83.140382)
		(mid 162.761569 83.181387)
		(end 162.802574 83.280382)
		(width 0.15)
		(layer "B.Cu")
		(net 46)
	)
	(arc
		(start 162.312574 83.425)
		(mid 162.411569 83.383995)
		(end 162.452574 83.285)
		(width 0.15)
		(layer "B.Cu")
		(net 46)
	)
	(arc
		(start 161.612574 83.425)
		(mid 161.711569 83.383995)
		(end 161.752574 83.285)
		(width 0.15)
		(layer "B.Cu")
		(net 46)
	)
	(arc
		(start 162.802574 83.285)
		(mid 162.843579 83.383995)
		(end 162.942574 83.425)
		(width 0.15)
		(layer "B.Cu")
		(net 46)
	)
	(arc
		(start 161.962574 83.140382)
		(mid 162.061569 83.181387)
		(end 162.102574 83.280382)
		(width 0.15)
		(layer "B.Cu")
		(net 46)
	)
	(via
		(at 160.08 83.75)
		(size 0.45)
		(drill 0.2)
		(layers "F.Cu" "B.Cu")
		(remove_unused_layers yes)
		(keep_end_layers yes)
		(zone_layer_connections)
		(net 47)
	)
	(segment
		(start 182.150001 95.750001)
		(end 170.175 83.775)
		(width 0.15)
		(layer "B.Cu")
		(net 47)
	)
	(segment
		(start 175.532512 134.585)
		(end 174.932512 134.585)
		(width 0.15)
		(layer "B.Cu")
		(net 47)
	)
	(segment
		(start 175.935 135.035)
		(end 175.935 134.987488)
		(width 0.15)
		(layer "B.Cu")
		(net 47)
	)
	(segment
		(start 160.105 83.775)
		(end 160.08 83.75)
		(width 0.15)
		(layer "B.Cu")
		(net 47)
	)
	(segment
		(start 182.150001 113.855025)
		(end 182.150001 112.515775)
		(width 0.15)
		(layer "B.Cu")
		(net 47)
	)
	(segment
		(start 182.150001 111.315775)
		(end 182.150001 110.026279)
		(width 0.15)
		(layer "B.Cu")
		(net 47)
	)
	(segment
		(start 175.935 134.987488)
		(end 175.532512 134.585)
		(width 0.15)
		(layer "B.Cu")
		(net 47)
	)
	(segment
		(start 182.150001 110.026279)
		(end 182.150001 95.750001)
		(width 0.15)
		(layer "B.Cu")
		(net 47)
	)
	(segment
		(start 182.150001 111.535051)
		(end 182.150001 111.315775)
		(width 0.15)
		(layer "B.Cu")
		(net 47)
	)
	(segment
		(start 174.43 134.082488)
		(end 174.43 121.575026)
		(width 0.15)
		(layer "B.Cu")
		(net 47)
	)
	(segment
		(start 170.175 83.775)
		(end 160.105 83.775)
		(width 0.15)
		(layer "B.Cu")
		(net 47)
	)
	(segment
		(start 175.095 135.875)
		(end 175.935 135.035)
		(width 0.15)
		(layer "B.Cu")
		(net 47)
	)
	(segment
		(start 181.769277 112.135051)
		(end 181.769277 111.915775)
		(width 0.15)
		(layer "B.Cu")
		(net 47)
	)
	(segment
		(start 174.932512 134.585)
		(end 174.43 134.082488)
		(width 0.15)
		(layer "B.Cu")
		(net 47)
	)
	(segment
		(start 174.43 121.575026)
		(end 182.150001 113.855025)
		(width 0.15)
		(layer "B.Cu")
		(net 47)
	)
	(arc
		(start 181.769277 111.915775)
		(mid 181.825033 111.781169)
		(end 181.959639 111.725413)
		(width 0.15)
		(layer "B.Cu")
		(net 47)
	)
	(arc
		(start 181.959639 111.725413)
		(mid 182.094245 111.669657)
		(end 182.150001 111.535051)
		(width 0.15)
		(layer "B.Cu")
		(net 47)
	)
	(arc
		(start 182.150001 112.515775)
		(mid 182.094245 112.381169)
		(end 181.959639 112.325413)
		(width 0.15)
		(layer "B.Cu")
		(net 47)
	)
	(arc
		(start 181.959639 112.325413)
		(mid 181.825033 112.269657)
		(end 181.769277 112.135051)
		(width 0.15)
		(layer "B.Cu")
		(net 47)
	)
	(via
		(at 160.945 84.25)
		(size 0.45)
		(drill 0.2)
		(layers "F.Cu" "B.Cu")
		(remove_unused_layers yes)
		(keep_end_layers yes)
		(zone_layer_connections)
		(net 48)
	)
	(segment
		(start 173.719449 134.054297)
		(end 173.719449 132.071961)
		(width 0.15)
		(layer "B.Cu")
		(net 48)
	)
	(segment
		(start 171.934748 126.268206)
		(end 171.934748 126.062206)
		(width 0.15)
		(layer "B.Cu")
		(net 48)
	)
	(segment
		(start 172.975 122.479494)
		(end 172.975 121.827944)
		(width 0.15)
		(layer "B.Cu")
		(net 48)
	)
	(segment
		(start 162.88233 84.425)
		(end 169.622918 84.425)
		(width 0.15)
		(layer "B.Cu")
		(net 48)
	)
	(segment
		(start 173.216937 134.556809)
		(end 173.719449 134.054297)
		(width 0.15)
		(layer "B.Cu")
		(net 48)
	)
	(segment
		(start 172.975 125.238206)
		(end 172.975 125.032206)
		(width 0.15)
		(layer "B.Cu")
		(net 48)
	)
	(segment
		(start 173.719449 132.071961)
		(end 172.975 131.327512)
		(width 0.15)
		(layer "B.Cu")
		(net 48)
	)
	(segment
		(start 172.214449 135.006809)
		(end 172.214449 134.959297)
		(width 0.15)
		(layer "B.Cu")
		(net 48)
	)
	(segment
		(start 172.171748 125.825206)
		(end 172.388 125.825206)
		(width 0.15)
		(layer "B.Cu")
		(net 48)
	)
	(segment
		(start 181.300001 96.102083)
		(end 169.622918 84.425)
		(width 0.15)
		(layer "B.Cu")
		(net 48)
	)
	(segment
		(start 181.300001 113.502943)
		(end 181.300001 96.102083)
		(width 0.15)
		(layer "B.Cu")
		(net 48)
	)
	(segment
		(start 162.74233 84.280284)
		(end 162.74233 84.285)
		(width 0.15)
		(layer "B.Cu")
		(net 48)
	)
	(segment
		(start 162.39233 84.285)
		(end 162.39233 84.280284)
		(width 0.15)
		(layer "B.Cu")
		(net 48)
	)
	(segment
		(start 173.054449 135.846809)
		(end 172.214449 135.006809)
		(width 0.15)
		(layer "B.Cu")
		(net 48)
	)
	(segment
		(start 172.975 131.327512)
		(end 172.975 127.092206)
		(width 0.15)
		(layer "B.Cu")
		(net 48)
	)
	(segment
		(start 172.388 126.505206)
		(end 172.171748 126.505206)
		(width 0.15)
		(layer "B.Cu")
		(net 48)
	)
	(segment
		(start 160.945 84.25)
		(end 161.12 84.425)
		(width 0.15)
		(layer "B.Cu")
		(net 48)
	)
	(segment
		(start 172.975 121.827944)
		(end 181.300001 113.502943)
		(width 0.15)
		(layer "B.Cu")
		(net 48)
	)
	(segment
		(start 172.616937 134.556809)
		(end 173.216937 134.556809)
		(width 0.15)
		(layer "B.Cu")
		(net 48)
	)
	(segment
		(start 172.975 125.032206)
		(end 172.975 122.479494)
		(width 0.15)
		(layer "B.Cu")
		(net 48)
	)
	(segment
		(start 161.12 84.425)
		(end 161.55233 84.425)
		(width 0.15)
		(layer "B.Cu")
		(net 48)
	)
	(segment
		(start 162.18233 84.425)
		(end 162.25233 84.425)
		(width 0.15)
		(layer "B.Cu")
		(net 48)
	)
	(segment
		(start 161.69233 84.285)
		(end 161.69233 84.280309)
		(width 0.15)
		(layer "B.Cu")
		(net 48)
	)
	(segment
		(start 172.214449 134.959297)
		(end 172.616937 134.556809)
		(width 0.15)
		(layer "B.Cu")
		(net 48)
	)
	(segment
		(start 162.53233 84.140284)
		(end 162.60233 84.140284)
		(width 0.15)
		(layer "B.Cu")
		(net 48)
	)
	(segment
		(start 162.04233 84.280309)
		(end 162.04233 84.285)
		(width 0.15)
		(layer "B.Cu")
		(net 48)
	)
	(segment
		(start 161.83233 84.140309)
		(end 161.90233 84.140309)
		(width 0.15)
		(layer "B.Cu")
		(net 48)
	)
	(arc
		(start 162.60233 84.140284)
		(mid 162.701325 84.181289)
		(end 162.74233 84.280284)
		(width 0.15)
		(layer "B.Cu")
		(net 48)
	)
	(arc
		(start 161.55233 84.425)
		(mid 161.651325 84.383995)
		(end 161.69233 84.285)
		(width 0.15)
		(layer "B.Cu")
		(net 48)
	)
	(arc
		(start 162.04233 84.285)
		(mid 162.083335 84.383995)
		(end 162.18233 84.425)
		(width 0.15)
		(layer "B.Cu")
		(net 48)
	)
	(arc
		(start 161.69233 84.280309)
		(mid 161.733335 84.181314)
		(end 161.83233 84.140309)
		(width 0.15)
		(layer "B.Cu")
		(net 48)
	)
	(arc
		(start 162.25233 84.425)
		(mid 162.351325 84.383995)
		(end 162.39233 84.285)
		(width 0.15)
		(layer "B.Cu")
		(net 48)
	)
	(arc
		(start 162.39233 84.280284)
		(mid 162.433335 84.181289)
		(end 162.53233 84.140284)
		(width 0.15)
		(layer "B.Cu")
		(net 48)
	)
	(arc
		(start 162.74233 84.285)
		(mid 162.783335 84.383995)
		(end 162.88233 84.425)
		(width 0.15)
		(layer "B.Cu")
		(net 48)
	)
	(arc
		(start 172.975 127.092206)
		(mid 172.803072 126.677134)
		(end 172.388 126.505206)
		(width 0.15)
		(layer "B.Cu")
		(net 48)
	)
	(arc
		(start 172.171748 126.505206)
		(mid 172.004164 126.43579)
		(end 171.934748 126.268206)
		(width 0.15)
		(layer "B.Cu")
		(net 48)
	)
	(arc
		(start 171.934748 126.062206)
		(mid 172.004164 125.894622)
		(end 172.171748 125.825206)
		(width 0.15)
		(layer "B.Cu")
		(net 48)
	)
	(arc
		(start 161.90233 84.140309)
		(mid 162.001325 84.181314)
		(end 162.04233 84.280309)
		(width 0.15)
		(layer "B.Cu")
		(net 48)
	)
	(arc
		(start 172.388 125.825206)
		(mid 172.803072 125.653278)
		(end 172.975 125.238206)
		(width 0.15)
		(layer "B.Cu")
		(net 48)
	)
	(via
		(at 160.08 84.75)
		(size 0.45)
		(drill 0.2)
		(layers "F.Cu" "B.Cu")
		(remove_unused_layers yes)
		(keep_end_layers yes)
		(zone_layer_connections)
		(net 49)
	)
	(segment
		(start 172.625 125.238206)
		(end 172.625 125.032206)
		(width 0.15)
		(layer "B.Cu")
		(net 49)
	)
	(segment
		(start 172.471961 134.206809)
		(end 173.071961 134.206809)
		(width 0.15)
		(layer "B.Cu")
		(net 49)
	)
	(segment
		(start 172.625 122.479494)
		(end 172.625 121.682968)
		(width 0.15)
		(layer "B.Cu")
		(net 49)
	)
	(segment
		(start 172.625 125.032206)
		(end 172.625 122.479494)
		(width 0.15)
		(layer "B.Cu")
		(net 49)
	)
	(segment
		(start 173.071961 134.206809)
		(end 173.369449 133.909321)
		(width 0.15)
		(layer "B.Cu")
		(net 49)
	)
	(segment
		(start 172.625 121.682968)
		(end 180.95 113.357968)
		(width 0.15)
		(layer "B.Cu")
		(net 49)
	)
	(segment
		(start 173.369449 132.216937)
		(end 172.625 131.472488)
		(width 0.15)
		(layer "B.Cu")
		(net 49)
	)
	(segment
		(start 180.95 111.477853)
		(end 180.95 111.259195)
		(width 0.15)
		(layer "B.Cu")
		(net 49)
	)
	(segment
		(start 171.864449 134.814321)
		(end 172.471961 134.206809)
		(width 0.15)
		(layer "B.Cu")
		(net 49)
	)
	(segment
		(start 171.584748 126.268206)
		(end 171.584748 126.062206)
		(width 0.15)
		(layer "B.Cu")
		(net 49)
	)
	(segment
		(start 172.171748 125.475206)
		(end 172.388 125.475206)
		(width 0.15)
		(layer "B.Cu")
		(net 49)
	)
	(segment
		(start 171.024449 135.846809)
		(end 171.864449 135.006809)
		(width 0.15)
		(layer "B.Cu")
		(net 49)
	)
	(segment
		(start 171.864449 135.006809)
		(end 171.864449 134.814321)
		(width 0.15)
		(layer "B.Cu")
		(net 49)
	)
	(segment
		(start 160.105 84.775)
		(end 160.08 84.75)
		(width 0.15)
		(layer "B.Cu")
		(net 49)
	)
	(segment
		(start 180.95 113.357968)
		(end 180.95 112.459195)
		(width 0.15)
		(layer "B.Cu")
		(net 49)
	)
	(segment
		(start 180.568658 112.077853)
		(end 180.568658 111.859195)
		(width 0.15)
		(layer "B.Cu")
		(net 49)
	)
	(segment
		(start 172.625 131.472488)
		(end 172.625 127.092206)
		(width 0.15)
		(layer "B.Cu")
		(net 49)
	)
	(segment
		(start 180.95 96.247058)
		(end 169.477942 84.775)
		(width 0.15)
		(layer "B.Cu")
		(net 49)
	)
	(segment
		(start 172.388 126.855206)
		(end 172.171748 126.855206)
		(width 0.15)
		(layer "B.Cu")
		(net 49)
	)
	(segment
		(start 173.369449 133.909321)
		(end 173.369449 132.216937)
		(width 0.15)
		(layer "B.Cu")
		(net 49)
	)
	(segment
		(start 180.95 109.743382)
		(end 180.95 96.247058)
		(width 0.15)
		(layer "B.Cu")
		(net 49)
	)
	(segment
		(start 169.477942 84.775)
		(end 160.105 84.775)
		(width 0.15)
		(layer "B.Cu")
		(net 49)
	)
	(segment
		(start 180.95 111.259195)
		(end 180.95 109.743382)
		(width 0.15)
		(layer "B.Cu")
		(net 49)
	)
	(arc
		(start 180.568658 111.859195)
		(mid 180.624504 111.72437)
		(end 180.759329 111.668524)
		(width 0.15)
		(layer "B.Cu")
		(net 49)
	)
	(arc
		(start 180.759329 111.668524)
		(mid 180.894154 111.612678)
		(end 180.95 111.477853)
		(width 0.15)
		(layer "B.Cu")
		(net 49)
	)
	(arc
		(start 171.584748 126.062206)
		(mid 171.756676 125.647134)
		(end 172.171748 125.475206)
		(width 0.15)
		(layer "B.Cu")
		(net 49)
	)
	(arc
		(start 172.625 127.092206)
		(mid 172.555584 126.924622)
		(end 172.388 126.855206)
		(width 0.15)
		(layer "B.Cu")
		(net 49)
	)
	(arc
		(start 172.388 125.475206)
		(mid 172.555584 125.40579)
		(end 172.625 125.238206)
		(width 0.15)
		(layer "B.Cu")
		(net 49)
	)
	(arc
		(start 180.95 112.459195)
		(mid 180.894154 112.32437)
		(end 180.759329 112.268524)
		(width 0.15)
		(layer "B.Cu")
		(net 49)
	)
	(arc
		(start 180.759329 112.268524)
		(mid 180.624504 112.212678)
		(end 180.568658 112.077853)
		(width 0.15)
		(layer "B.Cu")
		(net 49)
	)
	(arc
		(start 172.171748 126.855206)
		(mid 171.756676 126.683278)
		(end 171.584748 126.268206)
		(width 0.15)
		(layer "B.Cu")
		(net 49)
	)
	(via
		(at 160.08 85.75)
		(size 0.45)
		(drill 0.2)
		(layers "F.Cu" "B.Cu")
		(remove_unused_layers yes)
		(keep_end_layers yes)
		(zone_layer_connections)
		(net 50)
	)
	(segment
		(start 173.762948 118.847965)
		(end 173.677894 118.762911)
		(width 0.15)
		(layer "B.Cu")
		(net 50)
	)
	(segment
		(start 174.010435 119.09545)
		(end 173.886691 118.971706)
		(width 0.15)
		(layer "B.Cu")
		(net 50)
	)
	(segment
		(start 174.077812 119.162827)
		(end 174.010435 119.09545)
		(width 0.15)
		(layer "B.Cu")
		(net 50)
	)
	(segment
		(start 179.75 96.744114)
		(end 168.780886 85.775)
		(width 0.15)
		(layer "B.Cu")
		(net 50)
	)
	(segment
		(start 173.677895 118.097827)
		(end 173.953266 117.822457)
		(width 0.15)
		(layer "B.Cu")
		(net 50)
	)
	(segment
		(start 173.441216 119.417188)
		(end 173.441214 119.417185)
		(width 0.15)
		(layer "B.Cu")
		(net 50)
	)
	(segment
		(start 176.213077 116.645327)
		(end 176.213074 116.645325)
		(width 0.15)
		(layer "B.Cu")
		(net 50)
	)
	(segment
		(start 176.538902 116.83643)
		(end 176.849657 116.525674)
		(width 0.15)
		(layer "B.Cu")
		(net 50)
	)
	(segment
		(start 173.317473 119.293445)
		(end 173.441216 119.417188)
		(width 0.15)
		(layer "B.Cu")
		(net 50)
	)
	(segment
		(start 175.396364 117.70952)
		(end 175.272621 117.585777)
		(width 0.15)
		(layer "B.Cu")
		(net 50)
	)
	(segment
		(start 176.089333 116.521583)
		(end 176.213077 116.645327)
		(width 0.15)
		(layer "B.Cu")
		(net 50)
	)
	(segment
		(start 176.449776 115.326029)
		(end 176.725187 115.050619)
		(width 0.15)
		(layer "B.Cu")
		(net 50)
	)
	(segment
		(start 174.703403 117.907513)
		(end 174.827147 118.031257)
		(width 0.15)
		(layer "B.Cu")
		(net 50)
	)
	(segment
		(start 175.148878 117.462035)
		(end 175.063824 117.376981)
		(width 0.15)
		(layer "B.Cu")
		(net 50)
	)
	(segment
		(start 179.75 108.413765)
		(end 179.75 96.744114)
		(width 0.15)
		(layer "B.Cu")
		(net 50)
	)
	(segment
		(start 176.782295 116.32359)
		(end 176.658551 116.199846)
		(width 0.15)
		(layer "B.Cu")
		(net 50)
	)
	(segment
		(start 175.272622 117.585779)
		(end 175.148878 117.462035)
		(width 0.15)
		(layer "B.Cu")
		(net 50)
	)
	(segment
		(start 173.441214 119.417185)
		(end 173.564958 119.540929)
		(width 0.15)
		(layer "B.Cu")
		(net 50)
	)
	(segment
		(start 170.01 133.325)
		(end 170.85 132.485)
		(width 0.15)
		(layer "B.Cu")
		(net 50)
	)
	(segment
		(start 173.234894 119.210866)
		(end 173.317473 119.293445)
		(width 0.15)
		(layer "B.Cu")
		(net 50)
	)
	(segment
		(start 177.390229 115.050618)
		(end 177.475263 115.135652)
		(width 0.15)
		(layer "B.Cu")
		(net 50)
	)
	(segment
		(start 179.667957 112.942955)
		(end 179.75 112.860912)
		(width 0.15)
		(layer "B.Cu")
		(net 50)
	)
	(segment
		(start 175.272621 117.585777)
		(end 175.272622 117.585779)
		(width 0.15)
		(layer "B.Cu")
		(net 50)
	)
	(segment
		(start 177.917504 115.448057)
		(end 178.233143 115.132417)
		(width 0.15)
		(layer "B.Cu")
		(net 50)
	)
	(segment
		(start 174.827144 118.031255)
		(end 174.950888 118.154999)
		(width 0.15)
		(layer "B.Cu")
		(net 50)
	)
	(segment
		(start 175.463745 117.776901)
		(end 175.396364 117.70952)
		(width 0.15)
		(layer "B.Cu")
		(net 50)
	)
	(segment
		(start 174.950888 118.154999)
		(end 175.018268 118.222379)
		(width 0.15)
		(layer "B.Cu")
		(net 50)
	)
	(segment
		(start 176.213074 116.645325)
		(end 176.336818 116.769069)
		(width 0.15)
		(layer "B.Cu")
		(net 50)
	)
	(segment
		(start 173.767086 119.608305)
		(end 174.077812 119.297578)
		(width 0.15)
		(layer "B.Cu")
		(net 50)
	)
	(segment
		(start 179.368534 112.02115)
		(end 179.368534 111.802616)
		(width 0.15)
		(layer "B.Cu")
		(net 50)
	)
	(segment
		(start 179.75 111.42115)
		(end 179.75 111.202616)
		(width 0.15)
		(layer "B.Cu")
		(net 50)
	)
	(segment
		(start 175.063825 116.711897)
		(end 175.339196 116.436527)
		(width 0.15)
		(layer "B.Cu")
		(net 50)
	)
	(segment
		(start 160.105 85.775)
		(end 160.08 85.75)
		(width 0.15)
		(layer "B.Cu")
		(net 50)
	)
	(segment
		(start 177.599004 115.259395)
		(end 177.663923 115.324314)
		(width 0.15)
		(layer "B.Cu")
		(net 50)
	)
	(segment
		(start 170.85 132.485)
		(end 170.85 121.760912)
		(width 0.15)
		(layer "B.Cu")
		(net 50)
	)
	(segment
		(start 170.85 121.760912)
		(end 172.276256 120.334656)
		(width 0.15)
		(layer "B.Cu")
		(net 50)
	)
	(segment
		(start 174.827147 118.031257)
		(end 174.827144 118.031255)
		(width 0.15)
		(layer "B.Cu")
		(net 50)
	)
	(segment
		(start 177.663923 115.324314)
		(end 177.787667 115.448057)
		(width 0.15)
		(layer "B.Cu")
		(net 50)
	)
	(segment
		(start 168.780886 85.775)
		(end 160.105 85.775)
		(width 0.15)
		(layer "B.Cu")
		(net 50)
	)
	(segment
		(start 173.564958 119.540929)
		(end 173.632335 119.608305)
		(width 0.15)
		(layer "B.Cu")
		(net 50)
	)
	(segment
		(start 176.336818 116.769069)
		(end 176.40418 116.83643)
		(width 0.15)
		(layer "B.Cu")
		(net 50)
	)
	(segment
		(start 174.618348 117.822458)
		(end 174.703403 117.907513)
		(width 0.15)
		(layer "B.Cu")
		(net 50)
	)
	(segment
		(start 176.004278 116.436528)
		(end 176.089333 116.521583)
		(width 0.15)
		(layer "B.Cu")
		(net 50)
	)
	(segment
		(start 173.886691 118.971706)
		(end 173.886692 118.971709)
		(width 0.15)
		(layer "B.Cu")
		(net 50)
	)
	(segment
		(start 172.276257 119.509371)
		(end 172.574764 119.210865)
		(width 0.15)
		(layer "B.Cu")
		(net 50)
	)
	(segment
		(start 175.153027 118.222379)
		(end 175.463745 117.91166)
		(width 0.15)
		(layer "B.Cu")
		(net 50)
	)
	(segment
		(start 177.475263 115.135652)
		(end 177.599007 115.259396)
		(width 0.15)
		(layer "B.Cu")
		(net 50)
	)
	(segment
		(start 173.886692 118.971709)
		(end 173.762948 118.847965)
		(width 0.15)
		(layer "B.Cu")
		(net 50)
	)
	(segment
		(start 179.75 111.202616)
		(end 179.75 108.413765)
		(width 0.15)
		(layer "B.Cu")
		(net 50)
	)
	(segment
		(start 176.658551 116.199846)
		(end 176.658552 116.199849)
		(width 0.15)
		(layer "B.Cu")
		(net 50)
	)
	(segment
		(start 178.530618 114.080294)
		(end 179.667957 112.942955)
		(width 0.15)
		(layer "B.Cu")
		(net 50)
	)
	(segment
		(start 176.534808 116.076105)
		(end 176.449775 115.991071)
		(width 0.15)
		(layer "B.Cu")
		(net 50)
	)
	(segment
		(start 176.849657 116.390952)
		(end 176.782295 116.32359)
		(width 0.15)
		(layer "B.Cu")
		(net 50)
	)
	(segment
		(start 177.599007 115.259396)
		(end 177.599004 115.259395)
		(width 0.15)
		(layer "B.Cu")
		(net 50)
	)
	(segment
		(start 179.75 112.860912)
		(end 179.75 112.402616)
		(width 0.15)
		(layer "B.Cu")
		(net 50)
	)
	(segment
		(start 176.658552 116.199849)
		(end 176.534808 116.076105)
		(width 0.15)
		(layer "B.Cu")
		(net 50)
	)
	(segment
		(start 172.276256 120.334656)
		(end 172.276257 120.334657)
		(width 0.15)
		(layer "B.Cu")
		(net 50)
	)
	(segment
		(start 178.233143 114.377766)
		(end 178.530618 114.080294)
		(width 0.15)
		(layer "B.Cu")
		(net 50)
	)
	(arc
		(start 175.018268 118.222379)
		(mid 175.085648 118.250288)
		(end 175.153027 118.222379)
		(width 0.15)
		(layer "B.Cu")
		(net 50)
	)
	(arc
		(start 176.849657 116.525674)
		(mid 176.877559 116.458313)
		(end 176.849657 116.390952)
		(width 0.15)
		(layer "B.Cu")
		(net 50)
	)
	(arc
		(start 176.725187 115.050619)
		(mid 177.057708 114.912884)
		(end 177.390229 115.050618)
		(width 0.15)
		(layer "B.Cu")
		(net 50)
	)
	(arc
		(start 173.632335 119.608305)
		(mid 173.699711 119.636212)
		(end 173.767086 119.608305)
		(width 0.15)
		(layer "B.Cu")
		(net 50)
	)
	(arc
		(start 174.077812 119.297578)
		(mid 174.10572 119.230202)
		(end 174.077812 119.162827)
		(width 0.15)
		(layer "B.Cu")
		(net 50)
	)
	(arc
		(start 176.40418 116.83643)
		(mid 176.471541 116.864332)
		(end 176.538902 116.83643)
		(width 0.15)
		(layer "B.Cu")
		(net 50)
	)
	(arc
		(start 172.276257 120.169501)
		(mid 172.13954 119.839436)
		(end 172.276257 119.509371)
		(width 0.15)
		(layer "B.Cu")
		(net 50)
	)
	(arc
		(start 177.787667 115.448057)
		(mid 177.852586 115.474947)
		(end 177.917504 115.448057)
		(width 0.15)
		(layer "B.Cu")
		(net 50)
	)
	(arc
		(start 175.463745 117.91166)
		(mid 175.491655 117.84428)
		(end 175.463745 117.776901)
		(width 0.15)
		(layer "B.Cu")
		(net 50)
	)
	(arc
		(start 175.339196 116.436527)
		(mid 175.671737 116.298785)
		(end 176.004278 116.436528)
		(width 0.15)
		(layer "B.Cu")
		(net 50)
	)
	(arc
		(start 178.233143 115.002579)
		(mid 178.103739 114.690173)
		(end 178.233143 114.377766)
		(width 0.15)
		(layer "B.Cu")
		(net 50)
	)
	(arc
		(start 172.276257 120.334657)
		(mid 172.310463 120.252078)
		(end 172.276257 120.169501)
		(width 0.15)
		(layer "B.Cu")
		(net 50)
	)
	(arc
		(start 173.677894 118.762911)
		(mid 173.540152 118.430368)
		(end 173.677895 118.097827)
		(width 0.15)
		(layer "B.Cu")
		(net 50)
	)
	(arc
		(start 179.559267 111.611883)
		(mid 179.694136 111.556019)
		(end 179.75 111.42115)
		(width 0.15)
		(layer "B.Cu")
		(net 50)
	)
	(arc
		(start 172.574764 119.210865)
		(mid 172.90483 119.074147)
		(end 173.234894 119.210866)
		(width 0.15)
		(layer "B.Cu")
		(net 50)
	)
	(arc
		(start 173.953266 117.822457)
		(mid 174.285807 117.684715)
		(end 174.618348 117.822458)
		(width 0.15)
		(layer "B.Cu")
		(net 50)
	)
	(arc
		(start 175.063824 117.376981)
		(mid 174.926082 117.044438)
		(end 175.063825 116.711897)
		(width 0.15)
		(layer "B.Cu")
		(net 50)
	)
	(arc
		(start 179.559267 112.211883)
		(mid 179.424398 112.156019)
		(end 179.368534 112.02115)
		(width 0.15)
		(layer "B.Cu")
		(net 50)
	)
	(arc
		(start 176.449775 115.991071)
		(mid 176.31204 115.658551)
		(end 176.449776 115.326029)
		(width 0.15)
		(layer "B.Cu")
		(net 50)
	)
	(arc
		(start 179.75 112.402616)
		(mid 179.694136 112.267747)
		(end 179.559267 112.211883)
		(width 0.15)
		(layer "B.Cu")
		(net 50)
	)
	(arc
		(start 179.368534 111.802616)
		(mid 179.424398 111.667747)
		(end 179.559267 111.611883)
		(width 0.15)
		(layer "B.Cu")
		(net 50)
	)
	(arc
		(start 178.233143 115.132417)
		(mid 178.260033 115.067498)
		(end 178.233143 115.002579)
		(width 0.15)
		(layer "B.Cu")
		(net 50)
	)
	(via
		(at 160.945 85.25)
		(size 0.45)
		(drill 0.2)
		(layers "F.Cu" "B.Cu")
		(remove_unused_layers yes)
		(keep_end_layers yes)
		(zone_layer_connections)
		(net 51)
	)
	(segment
		(start 174.57966 118.278743)
		(end 174.579657 118.278742)
		(width 0.15)
		(layer "B.Cu")
		(net 51)
	)
	(segment
		(start 172.987406 119.458352)
		(end 173.069985 119.540931)
		(width 0.15)
		(layer "B.Cu")
		(net 51)
	)
	(segment
		(start 174.455916 118.154999)
		(end 174.57966 118.278743)
		(width 0.15)
		(layer "B.Cu")
		(net 51)
	)
	(segment
		(start 162.479349 85.285)
		(end 162.479349 85.28026)
		(width 0.15)
		(layer "B.Cu")
		(net 51)
	)
	(segment
		(start 174.257923 118.847963)
		(end 174.134179 118.724219)
		(width 0.15)
		(layer "B.Cu")
		(net 51)
	)
	(segment
		(start 175.756791 116.684014)
		(end 175.841846 116.769069)
		(width 0.15)
		(layer "B.Cu")
		(net 51)
	)
	(segment
		(start 173.925382 118.345314)
		(end 174.200753 118.069944)
		(width 0.15)
		(layer "B.Cu")
		(net 51)
	)
	(segment
		(start 176.906041 115.95236)
		(end 176.782297 115.828616)
		(width 0.15)
		(layer "B.Cu")
		(net 51)
	)
	(segment
		(start 174.579657 118.278742)
		(end 174.703401 118.402486)
		(width 0.15)
		(layer "B.Cu")
		(net 51)
	)
	(segment
		(start 174.014574 119.855793)
		(end 174.3253 119.545066)
		(width 0.15)
		(layer "B.Cu")
		(net 51)
	)
	(segment
		(start 180.100001 113.005887)
		(end 180.100001 96.599139)
		(width 0.15)
		(layer "B.Cu")
		(net 51)
	)
	(segment
		(start 177.029782 116.076103)
		(end 176.906038 115.952359)
		(width 0.15)
		(layer "B.Cu")
		(net 51)
	)
	(segment
		(start 177.35152 115.506883)
		(end 177.351517 115.506882)
		(width 0.15)
		(layer "B.Cu")
		(net 51)
	)
	(segment
		(start 177.416436 115.571801)
		(end 177.540179 115.695545)
		(width 0.15)
		(layer "B.Cu")
		(net 51)
	)
	(segment
		(start 172.04 133.325)
		(end 171.2 132.485)
		(width 0.15)
		(layer "B.Cu")
		(net 51)
	)
	(segment
		(start 175.520111 117.33829)
		(end 175.396367 117.214546)
		(width 0.15)
		(layer "B.Cu")
		(net 51)
	)
	(segment
		(start 174.010437 118.600476)
		(end 173.925383 118.515422)
		(width 0.15)
		(layer "B.Cu")
		(net 51)
	)
	(segment
		(start 173.193727 119.664672)
		(end 173.317471 119.788416)
		(width 0.15)
		(layer "B.Cu")
		(net 51)
	)
	(segment
		(start 175.311312 116.959384)
		(end 175.586683 116.684014)
		(width 0.15)
		(layer "B.Cu")
		(net 51)
	)
	(segment
		(start 173.193728 119.664674)
		(end 173.193727 119.664672)
		(width 0.15)
		(layer "B.Cu")
		(net 51)
	)
	(segment
		(start 172.523745 119.756856)
		(end 172.82225 119.458352)
		(width 0.15)
		(layer "B.Cu")
		(net 51)
	)
	(segment
		(start 173.069985 119.540931)
		(end 173.193728 119.664674)
		(width 0.15)
		(layer "B.Cu")
		(net 51)
	)
	(segment
		(start 178.480631 114.625254)
		(end 178.778105 114.327781)
		(width 0.15)
		(layer "B.Cu")
		(net 51)
	)
	(segment
		(start 178.778105 114.327781)
		(end 179.915445 113.190443)
		(width 0.15)
		(layer "B.Cu")
		(net 51)
	)
	(segment
		(start 174.703401 118.402486)
		(end 174.770781 118.469866)
		(width 0.15)
		(layer "B.Cu")
		(net 51)
	)
	(segment
		(start 175.711232 117.529413)
		(end 175.643851 117.462032)
		(width 0.15)
		(layer "B.Cu")
		(net 51)
	)
	(segment
		(start 175.643851 117.462032)
		(end 175.520108 117.338289)
		(width 0.15)
		(layer "B.Cu")
		(net 51)
	)
	(segment
		(start 174.3253 118.91534)
		(end 174.257923 118.847963)
		(width 0.15)
		(layer "B.Cu")
		(net 51)
	)
	(segment
		(start 180.100001 96.599139)
		(end 168.925862 85.425)
		(width 0.15)
		(layer "B.Cu")
		(net 51)
	)
	(segment
		(start 161.12 85.425)
		(end 161.639349 85.425)
		(width 0.15)
		(layer "B.Cu")
		(net 51)
	)
	(segment
		(start 162.129349 85.28026)
		(end 162.129349 85.285)
		(width 0.15)
		(layer "B.Cu")
		(net 51)
	)
	(segment
		(start 176.697263 115.573517)
		(end 176.972676 115.298105)
		(width 0.15)
		(layer "B.Cu")
		(net 51)
	)
	(segment
		(start 174.370861 118.069944)
		(end 174.455916 118.154999)
		(width 0.15)
		(layer "B.Cu")
		(net 51)
	)
	(segment
		(start 171.2 121.905888)
		(end 172.523744 120.582144)
		(width 0.15)
		(layer "B.Cu")
		(net 51)
	)
	(segment
		(start 175.520108 117.338289)
		(end 175.520111 117.33829)
		(width 0.15)
		(layer "B.Cu")
		(net 51)
	)
	(segment
		(start 179.915445 113.190443)
		(end 180.100001 113.005887)
		(width 0.15)
		(layer "B.Cu")
		(net 51)
	)
	(segment
		(start 161.779349 85.285)
		(end 161.779349 85.28026)
		(width 0.15)
		(layer "B.Cu")
		(net 51)
	)
	(segment
		(start 174.134181 118.72422)
		(end 174.010437 118.600476)
		(width 0.15)
		(layer "B.Cu")
		(net 51)
	)
	(segment
		(start 176.906038 115.952359)
		(end 176.906041 115.95236)
		(width 0.15)
		(layer "B.Cu")
		(net 51)
	)
	(segment
		(start 173.317471 119.788416)
		(end 173.384847 119.855793)
		(width 0.15)
		(layer "B.Cu")
		(net 51)
	)
	(segment
		(start 160.945 85.25)
		(end 161.12 85.425)
		(width 0.15)
		(layer "B.Cu")
		(net 51)
	)
	(segment
		(start 174.134179 118.724219)
		(end 174.134181 118.72422)
		(width 0.15)
		(layer "B.Cu")
		(net 51)
	)
	(segment
		(start 177.227776 115.383139)
		(end 177.35152 115.506883)
		(width 0.15)
		(layer "B.Cu")
		(net 51)
	)
	(segment
		(start 161.919349 85.14026)
		(end 161.989349 85.14026)
		(width 0.15)
		(layer "B.Cu")
		(net 51)
	)
	(segment
		(start 162.969349 85.425)
		(end 168.925862 85.425)
		(width 0.15)
		(layer "B.Cu")
		(net 51)
	)
	(segment
		(start 175.965587 116.892812)
		(end 176.089331 117.016556)
		(width 0.15)
		(layer "B.Cu")
		(net 51)
	)
	(segment
		(start 177.097144 116.143465)
		(end 177.029782 116.076103)
		(width 0.15)
		(layer "B.Cu")
		(net 51)
	)
	(segment
		(start 175.396367 117.214546)
		(end 175.311313 117.129492)
		(width 0.15)
		(layer "B.Cu")
		(net 51)
	)
	(segment
		(start 175.400514 118.469866)
		(end 175.711232 118.159147)
		(width 0.15)
		(layer "B.Cu")
		(net 51)
	)
	(segment
		(start 177.142742 115.298105)
		(end 177.227776 115.383139)
		(width 0.15)
		(layer "B.Cu")
		(net 51)
	)
	(segment
		(start 162.829349 85.28026)
		(end 162.829349 85.285)
		(width 0.15)
		(layer "B.Cu")
		(net 51)
	)
	(segment
		(start 176.786389 117.083918)
		(end 177.097144 116.773162)
		(width 0.15)
		(layer "B.Cu")
		(net 51)
	)
	(segment
		(start 176.089331 117.016556)
		(end 176.156692 117.083918)
		(width 0.15)
		(layer "B.Cu")
		(net 51)
	)
	(segment
		(start 175.841846 116.769069)
		(end 175.96559 116.892813)
		(width 0.15)
		(layer "B.Cu")
		(net 51)
	)
	(segment
		(start 162.619349 85.14026)
		(end 162.689349 85.14026)
		(width 0.15)
		(layer "B.Cu")
		(net 51)
	)
	(segment
		(start 171.2 132.485)
		(end 171.2 121.905888)
		(width 0.15)
		(layer "B.Cu")
		(net 51)
	)
	(segment
		(start 176.782297 115.828616)
		(end 176.697263 115.743583)
		(width 0.15)
		(layer "B.Cu")
		(net 51)
	)
	(segment
		(start 175.96559 116.892813)
		(end 175.965587 116.892812)
		(width 0.15)
		(layer "B.Cu")
		(net 51)
	)
	(segment
		(start 178.164992 115.695545)
		(end 178.480631 115.379905)
		(width 0.15)
		(layer "B.Cu")
		(net 51)
	)
	(segment
		(start 162.269349 85.425)
		(end 162.339349 85.425)
		(width 0.15)
		(layer "B.Cu")
		(net 51)
	)
	(segment
		(start 177.351517 115.506882)
		(end 177.416436 115.571801)
		(width 0.15)
		(layer "B.Cu")
		(net 51)
	)
	(arc
		(start 172.523745 119.922012)
		(mid 172.489539 119.839435)
		(end 172.523745 119.756856)
		(width 0.15)
		(layer "B.Cu")
		(net 51)
	)
	(arc
		(start 161.779349 85.28026)
		(mid 161.820354 85.181265)
		(end 161.919349 85.14026)
		(width 0.15)
		(layer "B.Cu")
		(net 51)
	)
	(arc
		(start 176.697263 115.743583)
		(mid 176.662042 115.658549)
		(end 176.697263 115.573517)
		(width 0.15)
		(layer "B.Cu")
		(net 51)
	)
	(arc
		(start 162.689349 85.14026)
		(mid 162.788344 85.181265)
		(end 162.829349 85.28026)
		(width 0.15)
		(layer "B.Cu")
		(net 51)
	)
	(arc
		(start 161.989349 85.14026)
		(mid 162.088344 85.181265)
		(end 162.129349 85.28026)
		(width 0.15)
		(layer "B.Cu")
		(net 51)
	)
	(arc
		(start 162.129349 85.285)
		(mid 162.170354 85.383995)
		(end 162.269349 85.425)
		(width 0.15)
		(layer "B.Cu")
		(net 51)
	)
	(arc
		(start 173.925383 118.515422)
		(mid 173.890152 118.430368)
		(end 173.925382 118.345314)
		(width 0.15)
		(layer "B.Cu")
		(net 51)
	)
	(arc
		(start 172.523744 120.582144)
		(mid 172.660461 120.252079)
		(end 172.523745 119.922012)
		(width 0.15)
		(layer "B.Cu")
		(net 51)
	)
	(arc
		(start 175.311313 117.129492)
		(mid 175.276082 117.044438)
		(end 175.311312 116.959384)
		(width 0.15)
		(layer "B.Cu")
		(net 51)
	)
	(arc
		(start 176.972676 115.298105)
		(mid 177.057708 115.262884)
		(end 177.142742 115.298105)
		(width 0.15)
		(layer "B.Cu")
		(net 51)
	)
	(arc
		(start 177.097144 116.773162)
		(mid 177.227559 116.458313)
		(end 177.097144 116.143465)
		(width 0.15)
		(layer "B.Cu")
		(net 51)
	)
	(arc
		(start 174.770781 118.469866)
		(mid 175.085648 118.600287)
		(end 175.400514 118.469866)
		(width 0.15)
		(layer "B.Cu")
		(net 51)
	)
	(arc
		(start 178.480631 115.379905)
		(mid 178.610034 115.067498)
		(end 178.480631 114.755092)
		(width 0.15)
		(layer "B.Cu")
		(net 51)
	)
	(arc
		(start 162.339349 85.425)
		(mid 162.438344 85.383995)
		(end 162.479349 85.285)
		(width 0.15)
		(layer "B.Cu")
		(net 51)
	)
	(arc
		(start 176.156692 117.083918)
		(mid 176.471541 117.214332)
		(end 176.786389 117.083918)
		(width 0.15)
		(layer "B.Cu")
		(net 51)
	)
	(arc
		(start 174.3253 119.545066)
		(mid 174.455721 119.230203)
		(end 174.3253 118.91534)
		(width 0.15)
		(layer "B.Cu")
		(net 51)
	)
	(arc
		(start 162.829349 85.285)
		(mid 162.870354 85.383995)
		(end 162.969349 85.425)
		(width 0.15)
		(layer "B.Cu")
		(net 51)
	)
	(arc
		(start 177.540179 115.695545)
		(mid 177.852586 115.824948)
		(end 178.164992 115.695545)
		(width 0.15)
		(layer "B.Cu")
		(net 51)
	)
	(arc
		(start 161.639349 85.425)
		(mid 161.738344 85.383995)
		(end 161.779349 85.285)
		(width 0.15)
		(layer "B.Cu")
		(net 51)
	)
	(arc
		(start 172.82225 119.458352)
		(mid 172.904829 119.424146)
		(end 172.987406 119.458352)
		(width 0.15)
		(layer "B.Cu")
		(net 51)
	)
	(arc
		(start 173.384847 119.855793)
		(mid 173.699711 119.986213)
		(end 174.014574 119.855793)
		(width 0.15)
		(layer "B.Cu")
		(net 51)
	)
	(arc
		(start 178.480631 114.755092)
		(mid 178.453741 114.690173)
		(end 178.480631 114.625254)
		(width 0.15)
		(layer "B.Cu")
		(net 51)
	)
	(arc
		(start 175.711232 118.159147)
		(mid 175.841654 117.84428)
		(end 175.711232 117.529413)
		(width 0.15)
		(layer "B.Cu")
		(net 51)
	)
	(arc
		(start 174.200753 118.069944)
		(mid 174.285806 118.034714)
		(end 174.370861 118.069944)
		(width 0.15)
		(layer "B.Cu")
		(net 51)
	)
	(arc
		(start 175.586683 116.684014)
		(mid 175.671736 116.648784)
		(end 175.756791 116.684014)
		(width 0.15)
		(layer "B.Cu")
		(net 51)
	)
	(arc
		(start 162.479349 85.28026)
		(mid 162.520354 85.181265)
		(end 162.619349 85.14026)
		(width 0.15)
		(layer "B.Cu")
		(net 51)
	)
	(via
		(at 160.945 82.25)
		(size 0.45)
		(drill 0.2)
		(layers "F.Cu" "B.Cu")
		(remove_unused_layers yes)
		(keep_end_layers yes)
		(zone_layer_connections)
		(net 52)
	)
	(segment
		(start 180.472662 118.255447)
		(end 180.383203 118.165988)
		(width 0.15)
		(layer "B.Cu")
		(net 52)
	)
	(segment
		(start 177.305 130.357512)
		(end 176.175 129.227512)
		(width 0.15)
		(layer "B.Cu")
		(net 52)
	)
	(segment
		(start 162.069105 82.115864)
		(end 162.069105 82.285)
		(width 0.15)
		(layer "B.Cu")
		(net 52)
	)
	(segment
		(start 162.209105 82.425)
		(end 171.017028 82.425)
		(width 0.15)
		(layer "B.Cu")
		(net 52)
	)
	(segment
		(start 177.305 132.495)
		(end 177.305 130.357512)
		(width 0.15)
		(layer "B.Cu")
		(net 52)
	)
	(segment
		(start 161.12 82.425)
		(end 161.579105 82.425)
		(width 0.15)
		(layer "B.Cu")
		(net 52)
	)
	(segment
		(start 183.699999 114.497057)
		(end 183.699999 95.107971)
		(width 0.15)
		(layer "B.Cu")
		(net 52)
	)
	(segment
		(start 161.719105 82.285)
		(end 161.719105 82.115864)
		(width 0.15)
		(layer "B.Cu")
		(net 52)
	)
	(segment
		(start 176.175 129.227512)
		(end 176.175 122.022056)
		(width 0.15)
		(layer "B.Cu")
		(net 52)
	)
	(segment
		(start 161.859105 81.975864)
		(end 161.929105 81.975864)
		(width 0.15)
		(layer "B.Cu")
		(net 52)
	)
	(segment
		(start 179.386186 119.163009)
		(end 179.475644 119.252467)
		(width 0.15)
		(layer "B.Cu")
		(net 52)
	)
	(segment
		(start 160.945 82.25)
		(end 161.12 82.425)
		(width 0.15)
		(layer "B.Cu")
		(net 52)
	)
	(segment
		(start 179.034046 119.16301)
		(end 179.034045 119.163009)
		(width 0.15)
		(layer "B.Cu")
		(net 52)
	)
	(segment
		(start 183.699999 95.107971)
		(end 171.017028 82.425)
		(width 0.15)
		(layer "B.Cu")
		(net 52)
	)
	(segment
		(start 180.533112 117.663943)
		(end 182.587779 115.609277)
		(width 0.15)
		(layer "B.Cu")
		(net 52)
	)
	(segment
		(start 176.175 122.022056)
		(end 179.034046 119.16301)
		(width 0.15)
		(layer "B.Cu")
		(net 52)
	)
	(segment
		(start 178.145 133.335)
		(end 177.305 132.495)
		(width 0.15)
		(layer "B.Cu")
		(net 52)
	)
	(segment
		(start 182.587779 115.609277)
		(end 183.699999 114.497057)
		(width 0.15)
		(layer "B.Cu")
		(net 52)
	)
	(segment
		(start 180.322756 119.252467)
		(end 180.472662 119.10256)
		(width 0.15)
		(layer "B.Cu")
		(net 52)
	)
	(segment
		(start 180.383203 117.813848)
		(end 180.533112 117.663943)
		(width 0.15)
		(layer "B.Cu")
		(net 52)
	)
	(arc
		(start 161.579105 82.425)
		(mid 161.6781 82.383995)
		(end 161.719105 82.285)
		(width 0.15)
		(layer "B.Cu")
		(net 52)
	)
	(arc
		(start 161.929105 81.975864)
		(mid 162.0281 82.016869)
		(end 162.069105 82.115864)
		(width 0.15)
		(layer "B.Cu")
		(net 52)
	)
	(arc
		(start 179.475644 119.252467)
		(mid 179.8992 119.42791)
		(end 180.322756 119.252467)
		(width 0.15)
		(layer "B.Cu")
		(net 52)
	)
	(arc
		(start 180.383203 118.165988)
		(mid 180.310272 117.989918)
		(end 180.383203 117.813848)
		(width 0.15)
		(layer "B.Cu")
		(net 52)
	)
	(arc
		(start 180.472662 119.10256)
		(mid 180.648105 118.679003)
		(end 180.472662 118.255447)
		(width 0.15)
		(layer "B.Cu")
		(net 52)
	)
	(arc
		(start 161.719105 82.115864)
		(mid 161.76011 82.016869)
		(end 161.859105 81.975864)
		(width 0.15)
		(layer "B.Cu")
		(net 52)
	)
	(arc
		(start 162.069105 82.285)
		(mid 162.11011 82.383995)
		(end 162.209105 82.425)
		(width 0.15)
		(layer "B.Cu")
		(net 52)
	)
	(arc
		(start 179.034045 119.163009)
		(mid 179.210115 119.090078)
		(end 179.386186 119.163009)
		(width 0.15)
		(layer "B.Cu")
		(net 52)
	)
	(segment
		(start 126.6 139)
		(end 127.3 139)
		(width 0.5)
		(layer "F.Cu")
		(net 53)
	)
	(segment
		(start 118.497 141.524)
		(end 118.497 140.217)
		(width 0.25)
		(layer "F.Cu")
		(net 53)
	)
	(segment
		(start 126.6 139)
		(end 126.1 139.5)
		(width 0.5)
		(layer "F.Cu")
		(net 53)
	)
	(segment
		(start 118.497 140.217)
		(end 118.48 140.2)
		(width 0.25)
		(layer "F.Cu")
		(net 53)
	)
	(segment
		(start 118.3 139.2)
		(end 118.5 139.4)
		(width 0.1)
		(layer "F.Cu")
		(net 53)
	)
	(segment
		(start 118.5 139.4)
		(end 118.5 140.18)
		(width 0.1)
		(layer "F.Cu")
		(net 53)
	)
	(segment
		(start 117.4 139.2)
		(end 118.3 139.2)
		(width 0.1)
		(layer "F.Cu")
		(net 53)
	)
	(segment
		(start 118.5 140.18)
		(end 118.48 140.2)
		(width 0.1)
		(layer "F.Cu")
		(net 53)
	)
	(segment
		(start 127.3 139)
		(end 127.9 138.4)
		(width 0.5)
		(layer "F.Cu")
		(net 53)
	)
	(via
		(at 116.6 111.6)
		(size 0.45)
		(drill 0.2)
		(layers "F.Cu" "B.Cu")
		(remove_unused_layers yes)
		(keep_end_layers yes)
		(zone_layer_connections)
		(net 53)
	)
	(via
		(at 120.6 141.8)
		(size 0.45)
		(drill 0.2)
		(layers "F.Cu" "B.Cu")
		(remove_unused_layers yes)
		(keep_end_layers yes)
		(free yes)
		(zone_layer_connections)
		(net 53)
	)
	(via
		(at 120 141.2)
		(size 0.45)
		(drill 0.2)
		(layers "F.Cu" "B.Cu")
		(remove_unused_layers yes)
		(keep_end_layers yes)
		(free yes)
		(zone_layer_connections)
		(net 53)
	)
	(via
		(at 126.1 139.5)
		(size 0.45)
		(drill 0.2)
		(layers "F.Cu" "B.Cu")
		(remove_unused_layers yes)
		(keep_end_layers yes)
		(zone_layer_connections)
		(net 53)
	)
	(via
		(at 126.6 139)
		(size 0.45)
		(drill 0.2)
		(layers "F.Cu" "B.Cu")
		(remove_unused_layers yes)
		(keep_end_layers yes)
		(zone_layer_connections)
		(net 53)
	)
	(via
		(at 117.2 112.2)
		(size 0.45)
		(drill 0.2)
		(layers "F.Cu" "B.Cu")
		(remove_unused_layers yes)
		(keep_end_layers yes)
		(zone_layer_connections)
		(net 53)
	)
	(via
		(at 119.4 141.8)
		(size 0.45)
		(drill 0.2)
		(layers "F.Cu" "B.Cu")
		(remove_unused_layers yes)
		(keep_end_layers yes)
		(free yes)
		(zone_layer_connections)
		(net 53)
	)
	(via
		(at 133.25 62)
		(size 0.45)
		(drill 0.2)
		(layers "F.Cu" "B.Cu")
		(remove_unused_layers yes)
		(keep_end_layers yes)
		(zone_layer_connections)
		(net 53)
	)
	(via
		(at 133.25 64)
		(size 0.45)
		(drill 0.2)
		(layers "F.Cu" "B.Cu")
		(remove_unused_layers yes)
		(keep_end_layers yes)
		(zone_layer_connections)
		(net 53)
	)
	(via
		(at 133.25 63)
		(size 0.45)
		(drill 0.2)
		(layers "F.Cu" "B.Cu")
		(remove_unused_layers yes)
		(keep_end_layers yes)
		(zone_layer_connections)
		(net 53)
	)
	(via
		(at 116 111.6)
		(size 0.45)
		(drill 0.2)
		(layers "F.Cu" "B.Cu")
		(remove_unused_layers yes)
		(keep_end_layers yes)
		(zone_layer_connections)
		(net 53)
	)
	(via
		(at 120.6 141.2)
		(size 0.45)
		(drill 0.2)
		(layers "F.Cu" "B.Cu")
		(remove_unused_layers yes)
		(keep_end_layers yes)
		(free yes)
		(zone_layer_connections)
		(net 53)
	)
	(via
		(at 133.25 62.5)
		(size 0.45)
		(drill 0.2)
		(layers "F.Cu" "B.Cu")
		(remove_unused_layers yes)
		(keep_end_layers yes)
		(zone_layer_connections)
		(net 53)
	)
	(via
		(at 117.2 111.6)
		(size 0.45)
		(drill 0.2)
		(layers "F.Cu" "B.Cu")
		(remove_unused_layers yes)
		(keep_end_layers yes)
		(zone_layer_connections)
		(net 53)
	)
	(via
		(at 133.25 63.5)
		(size 0.45)
		(drill 0.2)
		(layers "F.Cu" "B.Cu")
		(remove_unused_layers yes)
		(keep_end_layers yes)
		(zone_layer_connections)
		(net 53)
	)
	(via
		(at 119.4 141.2)
		(size 0.45)
		(drill 0.2)
		(layers "F.Cu" "B.Cu")
		(remove_unused_layers yes)
		(keep_end_layers yes)
		(free yes)
		(zone_layer_connections)
		(net 53)
	)
	(via
		(at 120 141.8)
		(size 0.45)
		(drill 0.2)
		(layers "F.Cu" "B.Cu")
		(remove_unused_layers yes)
		(keep_end_layers yes)
		(free yes)
		(zone_layer_connections)
		(net 53)
	)
	(via
		(at 116.6 112.2)
		(size 0.45)
		(drill 0.2)
		(layers "F.Cu" "B.Cu")
		(remove_unused_layers yes)
		(keep_end_layers yes)
		(zone_layer_connections)
		(net 53)
	)
	(via
		(at 116 112.2)
		(size 0.45)
		(drill 0.2)
		(layers "F.Cu" "B.Cu")
		(remove_unused_layers yes)
		(keep_end_layers yes)
		(zone_layer_connections)
		(net 53)
	)
	(segment
		(start 121.75 91)
		(end 121.75 95)
		(width 1)
		(layer "B.Cu")
		(net 53)
	)
	(segment
		(start 122.25 83.75)
		(end 122.25 85.75)
		(width 1)
		(layer "B.Cu")
		(net 53)
	)
	(segment
		(start 117.2 111.6)
		(end 117.2 112.2)
		(width 1)
		(layer "B.Cu")
		(net 53)
	)
	(segment
		(start 116 137.5)
		(end 117.8 139.3)
		(width 1)
		(layer "B.Cu")
		(net 53)
	)
	(segment
		(start 117.75 127)
		(end 118.25 127.5)
		(width 1)
		(layer "B.Cu")
		(net 53)
	)
	(segment
		(start 117.75 111.05)
		(end 117.2 111.6)
		(width 1)
		(layer "B.Cu")
		(net 53)
	)
	(segment
		(start 136.25 56.75)
		(end 134.75 58.25)
		(width 0.1)
		(layer "B.Cu")
		(net 53)
	)
	(segment
		(start 117.75 106.05)
		(end 117.75 111.05)
		(width 1)
		(layer "B.Cu")
		(net 53)
	)
	(segment
		(start 121.75 95)
		(end 118.4 98.35)
		(width 1)
		(layer "B.Cu")
		(net 53)
	)
	(segment
		(start 118.4 105.4)
		(end 117.75 106.05)
		(width 1)
		(layer "B.Cu")
		(net 53)
	)
	(segment
		(start 134.75 60.5)
		(end 133.25 62)
		(width 0.1)
		(layer "B.Cu")
		(net 53)
	)
	(segment
		(start 122.25 90.5)
		(end 121.75 91)
		(width 1)
		(layer "B.Cu")
		(net 53)
	)
	(segment
		(start 133.25 62)
		(end 133.25 66.25)
		(width 1)
		(layer "B.Cu")
		(net 53)
	)
	(segment
		(start 118.25 127.5)
		(end 118.25 130.75)
		(width 1)
		(layer "B.Cu")
		(net 53)
	)
	(segment
		(start 134.75 58.25)
		(end 134.75 60.5)
		(width 0.1)
		(layer "B.Cu")
		(net 53)
	)
	(segment
		(start 117.8 139.3)
		(end 117.8 140.449)
		(width 1)
		(layer "B.Cu")
		(net 53)
	)
	(segment
		(start 122.25 85.75)
		(end 122.25 90.5)
		(width 1)
		(layer "B.Cu")
		(net 53)
	)
	(segment
		(start 122 86)
		(end 122.25 85.75)
		(width 0.1)
		(layer "B.Cu")
		(net 53)
	)
	(segment
		(start 117.75 127)
		(end 117.75 112.75)
		(width 1)
		(layer "B.Cu")
		(net 53)
	)
	(segment
		(start 120.5 86)
		(end 122 86)
		(width 0.1)
		(layer "B.Cu")
		(net 53)
	)
	(segment
		(start 123.5 82.5)
		(end 122.25 83.75)
		(width 1)
		(layer "B.Cu")
		(net 53)
	)
	(segment
		(start 123.5 72.75)
		(end 123.5 82.5)
		(width 1)
		(layer "B.Cu")
		(net 53)
	)
	(segment
		(start 118.25 130.75)
		(end 116 133)
		(width 1)
		(layer "B.Cu")
		(net 53)
	)
	(segment
		(start 118.4 98.35)
		(end 118.4 105.4)
		(width 1)
		(layer "B.Cu")
		(net 53)
	)
	(segment
		(start 138.25 57.75)
		(end 137.25 56.75)
		(width 0.1)
		(layer "B.Cu")
		(net 53)
	)
	(segment
		(start 133.25 66.25)
		(end 130.5 69)
		(width 1)
		(layer "B.Cu")
		(net 53)
	)
	(segment
		(start 130.5 69)
		(end 127.25 69)
		(width 1)
		(layer "B.Cu")
		(net 53)
	)
	(segment
		(start 116 133)
		(end 116 137.5)
		(width 1)
		(layer "B.Cu")
		(net 53)
	)
	(segment
		(start 127.25 69)
		(end 123.5 72.75)
		(width 1)
		(layer "B.Cu")
		(net 53)
	)
	(segment
		(start 117.75 112.75)
		(end 117.2 112.2)
		(width 1)
		(layer "B.Cu")
		(net 53)
	)
	(segment
		(start 137.25 56.75)
		(end 136.25 56.75)
		(width 0.1)
		(layer "B.Cu")
		(net 53)
	)
	(segment
		(start 124.4 141.2)
		(end 126.6 139)
		(width 0.5)
		(layer "In3.Cu")
		(net 53)
	)
	(segment
		(start 120.6 141.2)
		(end 124.4 141.2)
		(width 0.5)
		(layer "In3.Cu")
		(net 53)
	)
	(segment
		(start 119.4 141.2)
		(end 120.6 141.2)
		(width 0.5)
		(layer "In3.Cu")
		(net 53)
	)
	(segment
		(start 182.8 73)
		(end 181.8 73)
		(width 0.1)
		(layer "F.Cu")
		(net 54)
	)
	(via
		(at 181.8 73)
		(size 0.45)
		(drill 0.2)
		(layers "F.Cu" "B.Cu")
		(remove_unused_layers yes)
		(keep_end_layers yes)
		(zone_layer_connections)
		(net 54)
	)
	(segment
		(start 181.28 73)
		(end 181.8 73)
		(width 0.5)
		(layer "B.Cu")
		(net 54)
	)
	(segment
		(start 159.8 68.260001)
		(end 160.11 68.570001)
		(width 0.19)
		(layer "F.Cu")
		(net 55)
	)
	(segment
		(start 159.8 67.940001)
		(end 159.8 68.260001)
		(width 0.19)
		(layer "F.Cu")
		(net 55)
	)
	(segment
		(start 160.11 67.605001)
		(end 161.11 67.605001)
		(width 0.19)
		(layer "F.Cu")
		(net 55)
	)
	(segment
		(start 160.11 68.570001)
		(end 160.11 68.595001)
		(width 0.16)
		(layer "F.Cu")
		(net 55)
	)
	(segment
		(start 160.11 67.605001)
		(end 160.11 67.630001)
		(width 0.16)
		(layer "F.Cu")
		(net 55)
	)
	(segment
		(start 160.11 67.630001)
		(end 159.8 67.940001)
		(width 0.19)
		(layer "F.Cu")
		(net 55)
	)
	(segment
		(start 163.27 64.3)
		(end 163.27 65.37)
		(width 0.25)
		(layer "F.Cu")
		(net 56)
	)
	(segment
		(start 166.285 64.48)
		(end 166.665 64.1)
		(width 0.25)
		(layer "F.Cu")
		(net 56)
	)
	(segment
		(start 164.62 60.58)
		(end 164.25 60.95)
		(width 0.1)
		(layer "F.Cu")
		(net 56)
	)
	(segment
		(start 163.4 65.5)
		(end 164.3 65.5)
		(width 0.25)
		(layer "F.Cu")
		(net 56)
	)
	(segment
		(start 165.265 65.235)
		(end 165.265 64.48)
		(width 0.25)
		(layer "F.Cu")
		(net 56)
	)
	(segment
		(start 164.25 60.95)
		(end 164.25 65.45)
		(width 0.1)
		(layer "F.Cu")
		(net 56)
	)
	(segment
		(start 163.27 65.37)
		(end 163.4 65.5)
		(width 0.25)
		(layer "F.Cu")
		(net 56)
	)
	(segment
		(start 165.265 60.58)
		(end 164.62 60.58)
		(width 0.1)
		(layer "F.Cu")
		(net 56)
	)
	(segment
		(start 164.25 65.45)
		(end 164.3 65.5)
		(width 0.1)
		(layer "F.Cu")
		(net 56)
	)
	(segment
		(start 165.265 64.48)
		(end 166.285 64.48)
		(width 0.25)
		(layer "F.Cu")
		(net 56)
	)
	(segment
		(start 165 65.5)
		(end 165.265 65.235)
		(width 0.25)
		(layer "F.Cu")
		(net 56)
	)
	(segment
		(start 164.3 65.5)
		(end 165 65.5)
		(width 0.25)
		(layer "F.Cu")
		(net 56)
	)
	(segment
		(start 145.8 118.505)
		(end 145.895 118.6)
		(width 0.25)
		(layer "F.Cu")
		(net 57)
	)
	(segment
		(start 145.1 116.9)
		(end 145.12 116.88)
		(width 0.25)
		(layer "F.Cu")
		(net 57)
	)
	(segment
		(start 144.92 128.68)
		(end 144.9 128.7)
		(width 0.25)
		(layer "F.Cu")
		(net 57)
	)
	(segment
		(start 126.975 96.2)
		(end 126.975 94.995)
		(width 0.25)
		(layer "F.Cu")
		(net 57)
	)
	(segment
		(start 133.1 129.01)
		(end 132.9 129.01)
		(width 0.1)
		(layer "F.Cu")
		(net 57)
	)
	(segment
		(start 139.5 142.8)
		(end 139.5 141.7)
		(width 0.25)
		(layer "F.Cu")
		(net 57)
	)
	(segment
		(start 137 134)
		(end 137 133.624)
		(width 0.1)
		(layer "F.Cu")
		(net 57)
	)
	(segment
		(start 145.8 128.68)
		(end 144.92 128.68)
		(width 0.25)
		(layer "F.Cu")
		(net 57)
	)
	(segment
		(start 132.87 128.78)
		(end 132.87 128.98)
		(width 0.1)
		(layer "F.Cu")
		(net 57)
	)
	(segment
		(start 120.35 88.049)
		(end 121.2 88.049)
		(width 0.25)
		(layer "F.Cu")
		(net 57)
	)
	(segment
		(start 132.87 128.98)
		(end 132.9 129.01)
		(width 0.1)
		(layer "F.Cu")
		(net 57)
	)
	(segment
		(start 145 116.9)
		(end 145.1 116.9)
		(width 0.25)
		(layer "F.Cu")
		(net 57)
	)
	(segment
		(start 134 133.774)
		(end 134 134)
		(width 0.1)
		(layer "F.Cu")
		(net 57)
	)
	(segment
		(start 145.8 128.68)
		(end 148.4 128.68)
		(width 0.25)
		(layer "F.Cu")
		(net 57)
	)
	(segment
		(start 146.34 116.34)
		(end 146.78 116.34)
		(width 0.1)
		(layer "F.Cu")
		(net 57)
	)
	(segment
		(start 132.9 129.01)
		(end 132.64 129.01)
		(width 0.1)
		(layer "F.Cu")
		(net 57)
	)
	(segment
		(start 146.78 116.34)
		(end 147.2 115.92)
		(width 0.1)
		(layer "F.Cu")
		(net 57)
	)
	(segment
		(start 145.12 116.88)
		(end 145.8 116.88)
		(width 0.25)
		(layer "F.Cu")
		(net 57)
	)
	(segment
		(start 137 133.624)
		(end 136.896 133.52)
		(width 0.1)
		(layer "F.Cu")
		(net 57)
	)
	(segment
		(start 126.975 94.995)
		(end 126.88 94.9)
		(width 0.25)
		(layer "F.Cu")
		(net 57)
	)
	(segment
		(start 130.509997 116.02)
		(end 130.509997 116.009997)
		(width 0.1)
		(layer "F.Cu")
		(net 57)
	)
	(segment
		(start 145.8 116.88)
		(end 146.34 116.34)
		(width 0.1)
		(layer "F.Cu")
		(net 57)
	)
	(segment
		(start 126.5 94.52)
		(end 126.88 94.9)
		(width 0.25)
		(layer "F.Cu")
		(net 57)
	)
	(segment
		(start 145.8 116.88)
		(end 145.8 118.505)
		(width 0.25)
		(layer "F.Cu")
		(net 57)
	)
	(segment
		(start 126.5 94.2)
		(end 126.5 94.52)
		(width 0.25)
		(layer "F.Cu")
		(net 57)
	)
	(segment
		(start 129.8 125.9)
		(end 130.125 126.225)
		(width 0.1)
		(layer "F.Cu")
		(net 57)
	)
	(segment
		(start 130.45 126.55)
		(end 130.125 126.225)
		(width 0.1)
		(layer "F.Cu")
		(net 57)
	)
	(segment
		(start 130.45 126.55)
		(end 130.125 126.875)
		(width 0.1)
		(layer "F.Cu")
		(net 57)
	)
	(segment
		(start 121.948107 88.074085)
		(end 121.225085 88.074085)
		(width 0.25)
		(layer "F.Cu")
		(net 57)
	)
	(segment
		(start 132.64 128.55)
		(end 132.87 128.78)
		(width 0.1)
		(layer "F.Cu")
		(net 57)
	)
	(segment
		(start 133.913 133.687)
		(end 134 133.774)
		(width 0.1)
		(layer "F.Cu")
		(net 57)
	)
	(segment
		(start 130.509997 116.009997)
		(end 130.5 116)
		(width 0.1)
		(layer "F.Cu")
		(net 57)
	)
	(segment
		(start 121.225085 88.074085)
		(end 121.2 88.049)
		(width 0.25)
		(layer "F.Cu")
		(net 57)
	)
	(via
		(at 138.8 130.8)
		(size 0.45)
		(drill 0.2)
		(layers "F.Cu" "B.Cu")
		(remove_unused_layers yes)
		(keep_end_layers yes)
		(free yes)
		(zone_layer_connections "In2.Cu")
		(net 57)
	)
	(via
		(at 130.125 126.875)
		(size 0.45)
		(drill 0.2)
		(layers "F.Cu" "B.Cu")
		(remove_unused_layers yes)
		(keep_end_layers yes)
		(zone_layer_connections)
		(net 57)
	)
	(via
		(at 126.5 115)
		(size 0.45)
		(drill 0.2)
		(layers "F.Cu" "B.Cu")
		(remove_unused_layers yes)
		(keep_end_layers yes)
		(free yes)
		(zone_layer_connections "In2.Cu")
		(net 57)
	)
	(via
		(at 125.5 114)
		(size 0.45)
		(drill 0.2)
		(layers "F.Cu" "B.Cu")
		(remove_unused_layers yes)
		(keep_end_layers yes)
		(free yes)
		(zone_layer_connections "In2.Cu")
		(net 57)
	)
	(via
		(at 140 130.8)
		(size 0.45)
		(drill 0.2)
		(layers "F.Cu" "B.Cu")
		(remove_unused_layers yes)
		(keep_end_layers yes)
		(free yes)
		(zone_layer_connections "In2.Cu")
		(net 57)
	)
	(via
		(at 143 114.3)
		(size 0.45)
		(drill 0.2)
		(layers "F.Cu" "B.Cu")
		(remove_unused_layers yes)
		(keep_end_layers yes)
		(zone_layer_connections "In2.Cu")
		(net 57)
	)
	(via
		(at 130.5 116)
		(size 0.45)
		(drill 0.2)
		(layers "F.Cu" "B.Cu")
		(remove_unused_layers yes)
		(keep_end_layers yes)
		(zone_layer_connections "In2.Cu")
		(net 57)
	)
	(via
		(at 144.9 128.7)
		(size 0.45)
		(drill 0.2)
		(layers "F.Cu" "B.Cu")
		(remove_unused_layers yes)
		(keep_end_layers yes)
		(zone_layer_connections "In2.Cu")
		(net 57)
	)
	(via
		(at 126.025 118.225)
		(size 0.45)
		(drill 0.2)
		(layers "F.Cu" "B.Cu")
		(remove_unused_layers yes)
		(keep_end_layers yes)
		(zone_layer_connections "In2.Cu")
		(net 57)
	)
	(via
		(at 126.5 94.2)
		(size 0.45)
		(drill 0.2)
		(layers "F.Cu" "B.Cu")
		(remove_unused_layers yes)
		(keep_end_layers yes)
		(zone_layer_connections "In2.Cu")
		(net 57)
	)
	(via
		(at 121.2 88.049)
		(size 0.45)
		(drill 0.2)
		(layers "F.Cu" "B.Cu")
		(remove_unused_layers yes)
		(keep_end_layers yes)
		(zone_layer_connections "In2.Cu")
		(net 57)
	)
	(via
		(at 137 121.1)
		(size 0.45)
		(drill 0.2)
		(layers "F.Cu" "B.Cu")
		(remove_unused_layers yes)
		(keep_end_layers yes)
		(zone_layer_connections "In2.Cu")
		(net 57)
	)
	(via
		(at 126 114.5)
		(size 0.45)
		(drill 0.2)
		(layers "F.Cu" "B.Cu")
		(remove_unused_layers yes)
		(keep_end_layers yes)
		(free yes)
		(zone_layer_connections "In2.Cu")
		(net 57)
	)
	(via
		(at 136.896 133.52)
		(size 0.45)
		(drill 0.2)
		(layers "F.Cu" "B.Cu")
		(remove_unused_layers yes)
		(keep_end_layers yes)
		(zone_layer_connections "In2.Cu")
		(net 57)
	)
	(via
		(at 130.125 126.225)
		(size 0.45)
		(drill 0.2)
		(layers "F.Cu" "B.Cu")
		(remove_unused_layers yes)
		(keep_end_layers yes)
		(zone_layer_connections)
		(net 57)
	)
	(via
		(at 138.2 130.8)
		(size 0.45)
		(drill 0.2)
		(layers "F.Cu" "B.Cu")
		(remove_unused_layers yes)
		(keep_end_layers yes)
		(free yes)
		(zone_layer_connections "In2.Cu")
		(net 57)
	)
	(via
		(at 126.57 118.22)
		(size 0.45)
		(drill 0.2)
		(layers "F.Cu" "B.Cu")
		(remove_unused_layers yes)
		(keep_end_layers yes)
		(zone_layer_connections "In2.Cu")
		(net 57)
	)
	(via
		(at 138.719999 133.600001)
		(size 0.45)
		(drill 0.2)
		(layers "F.Cu" "B.Cu")
		(remove_unused_layers yes)
		(keep_end_layers yes)
		(zone_layer_connections "In2.Cu")
		(net 57)
	)
	(via
		(at 126.5 114)
		(size 0.45)
		(drill 0.2)
		(layers "F.Cu" "B.Cu")
		(remove_unused_layers yes)
		(keep_end_layers yes)
		(free yes)
		(zone_layer_connections "In2.Cu")
		(net 57)
	)
	(via
		(at 139.4 130.8)
		(size 0.45)
		(drill 0.2)
		(layers "F.Cu" "B.Cu")
		(remove_unused_layers yes)
		(keep_end_layers yes)
		(free yes)
		(zone_layer_connections "In2.Cu")
		(net 57)
	)
	(via
		(at 126.5 113)
		(size 0.45)
		(drill 0.2)
		(layers "F.Cu" "B.Cu")
		(remove_unused_layers yes)
		(keep_end_layers yes)
		(free yes)
		(zone_layer_connections "In2.Cu")
		(net 57)
	)
	(via
		(at 126 113.5)
		(size 0.45)
		(drill 0.2)
		(layers "F.Cu" "B.Cu")
		(remove_unused_layers yes)
		(keep_end_layers yes)
		(free yes)
		(zone_layer_connections "In2.Cu")
		(net 57)
	)
	(via
		(at 125.5 113)
		(size 0.45)
		(drill 0.2)
		(layers "F.Cu" "B.Cu")
		(remove_unused_layers yes)
		(keep_end_layers yes)
		(free yes)
		(zone_layer_connections "In2.Cu")
		(net 57)
	)
	(via
		(at 118.5 88.5)
		(size 0.45)
		(drill 0.2)
		(layers "F.Cu" "B.Cu")
		(remove_unused_layers yes)
		(keep_end_layers yes)
		(zone_layer_connections "In2.Cu")
		(net 57)
	)
	(via
		(at 125.5 115)
		(size 0.45)
		(drill 0.2)
		(layers "F.Cu" "B.Cu")
		(remove_unused_layers yes)
		(keep_end_layers yes)
		(free yes)
		(zone_layer_connections "In2.Cu")
		(net 57)
	)
	(via
		(at 139.5 141.7)
		(size 0.45)
		(drill 0.2)
		(layers "F.Cu" "B.Cu")
		(remove_unused_layers yes)
		(keep_end_layers yes)
		(zone_layer_connections "In2.Cu")
		(net 57)
	)
	(via
		(at 133.913 133.687)
		(size 0.45)
		(drill 0.2)
		(layers "F.Cu" "B.Cu")
		(remove_unused_layers yes)
		(keep_end_layers yes)
		(zone_layer_connections "In2.Cu")
		(net 57)
	)
	(via
		(at 137 123.15)
		(size 0.45)
		(drill 0.2)
		(layers "F.Cu" "B.Cu")
		(remove_unused_layers yes)
		(keep_end_layers yes)
		(zone_layer_connections "In2.Cu")
		(net 57)
	)
	(via
		(at 145 116.9)
		(size 0.45)
		(drill 0.2)
		(layers "F.Cu" "B.Cu")
		(remove_unused_layers yes)
		(keep_end_layers yes)
		(zone_layer_connections "In2.Cu")
		(net 57)
	)
	(via
		(at 139.05 118.3)
		(size 0.45)
		(drill 0.2)
		(layers "F.Cu" "B.Cu")
		(remove_unused_layers yes)
		(keep_end_layers yes)
		(zone_layer_connections "In2.Cu")
		(net 57)
	)
	(segment
		(start 139.45 117.9)
		(end 139.05 118.3)
		(width 0.25)
		(layer "B.Cu")
		(net 57)
	)
	(segment
		(start 138.719999 131.600001)
		(end 138.72 131.6)
		(width 0.25)
		(layer "B.Cu")
		(net 57)
	)
	(segment
		(start 142.980001 117.15)
		(end 142.980001 115.099998)
		(width 0.25)
		(layer "B.Cu")
		(net 57)
	)
	(segment
		(start 139.45 117.4)
		(end 139.700003 117.149997)
		(width 0.25)
		(layer "B.Cu")
		(net 57)
	)
	(segment
		(start 136.98 121.15)
		(end 136.98 121.12)
		(width 0.25)
		(layer "B.Cu")
		(net 57)
	)
	(segment
		(start 142.98 115.099997)
		(end 142.98 114.32)
		(width 0.25)
		(layer "B.Cu")
		(net 57)
	)
	(segment
		(start 130.45 126.55)
		(end 130.125 126.875)
		(width 0.25)
		(layer "B.Cu")
		(net 57)
	)
	(segment
		(start 138.719999 133.600001)
		(end 138.719999 131.600001)
		(width 0.25)
		(layer "B.Cu")
		(net 57)
	)
	(segment
		(start 130.449999 127.199999)
		(end 130.125 126.875)
		(width 0.25)
		(layer "B.Cu")
		(net 57)
	)
	(segment
		(start 127.209998 118.289999)
		(end 127.529999 118.61)
		(width 0.25)
		(layer "B.Cu")
		(net 57)
	)
	(segment
		(start 139.45 117.4)
		(end 139.45 117.9)
		(width 0.25)
		(layer "B.Cu")
		(net 57)
	)
	(segment
		(start 136.98 123.15)
		(end 137 123.15)
		(width 0.25)
		(layer "B.Cu")
		(net 57)
	)
	(segment
		(start 142.98 114.32)
		(end 143 114.3)
		(width 0.25)
		(layer "B.Cu")
		(net 57)
	)
	(segment
		(start 140.12 117.149997)
		(end 139.700003 117.149997)
		(width 0.25)
		(layer "B.Cu")
		(net 57)
	)
	(segment
		(start 130.294999 126.225)
		(end 130.45 126.380001)
		(width 0.25)
		(layer "B.Cu")
		(net 57)
	)
	(segment
		(start 118 88)
		(end 118.5 88.5)
		(width 0.1)
		(layer "B.Cu")
		(net 57)
	)
	(segment
		(start 130.45 126.380001)
		(end 130.45 126.55)
		(width 0.25)
		(layer "B.Cu")
		(net 57)
	)
	(segment
		(start 130.125 126.225)
		(end 130.294999 126.225)
		(width 0.25)
		(layer "B.Cu")
		(net 57)
	)
	(segment
		(start 117.25 88)
		(end 118 88)
		(width 0.1)
		(layer "B.Cu")
		(net 57)
	)
	(segment
		(start 142.980001 115.099998)
		(end 142.98 115.099997)
		(width 0.25)
		(layer "B.Cu")
		(net 57)
	)
	(segment
		(start 118.5 89.27)
		(end 118.5 88.5)
		(width 0.1)
		(layer "B.Cu")
		(net 57)
	)
	(segment
		(start 130.449999 127.37)
		(end 130.449999 127.199999)
		(width 0.25)
		(layer "B.Cu")
		(net 57)
	)
	(segment
		(start 136.98 121.12)
		(end 137 121.1)
		(width 0.25)
		(layer "B.Cu")
		(net 57)
	)
	(segment
		(start 126.309999 118.289999)
		(end 127.209998 118.289999)
		(width 0.25)
		(layer "B.Cu")
		(net 57)
	)
	(segment
		(start 133.4 134.2)
		(end 133.913 133.687)
		(width 0.1)
		(layer "In2.Cu")
		(net 57)
	)
	(segment
		(start 129.6 128.972182)
		(end 129.6 130)
		(width 0.5)
		(layer "In2.Cu")
		(net 57)
	)
	(segment
		(start 130.6 135.4)
		(end 133 135.4)
		(width 0.1)
		(layer "In2.Cu")
		(net 57)
	)
	(segment
		(start 130.125 126.875)
		(end 130.125 128.447182)
		(width 0.5)
		(layer "In2.Cu")
		(net 57)
	)
	(segment
		(start 129.6 130)
		(end 129.2 130.4)
		(width 0.5)
		(layer "In2.Cu")
		(net 57)
	)
	(segment
		(start 129.2 134)
		(end 130.6 135.4)
		(width 0.1)
		(layer "In2.Cu")
		(net 57)
	)
	(segment
		(start 129.2 132.4)
		(end 129.2 134)
		(width 0.1)
		(layer "In2.Cu")
		(net 57)
	)
	(segment
		(start 130.125 128.447182)
		(end 129.6 128.972182)
		(width 0.5)
		(layer "In2.Cu")
		(net 57)
	)
	(segment
		(start 133 135.4)
		(end 133.4 135)
		(width 0.1)
		(layer "In2.Cu")
		(net 57)
	)
	(segment
		(start 130.125 126.225)
		(end 130.125 126.875)
		(width 0.5)
		(layer "In2.Cu")
		(net 57)
	)
	(segment
		(start 129.2 130.4)
		(end 129.2 132.4)
		(width 0.5)
		(layer "In2.Cu")
		(net 57)
	)
	(segment
		(start 133.4 135)
		(end 133.4 134.2)
		(width 0.1)
		(layer "In2.Cu")
		(net 57)
	)
	(segment
		(start 140 130.8)
		(end 138.2 130.8)
		(width 0.5)
		(layer "In3.Cu")
		(net 57)
	)
	(segment
		(start 158.944999 95.644999)
		(end 158.944999 96.474999)
		(width 0.1)
		(layer "F.Cu")
		(net 58)
	)
	(segment
		(start 158.355 94.534999)
		(end 158.355 95.055)
		(width 0.1)
		(layer "F.Cu")
		(net 58)
	)
	(segment
		(start 158.839499 96.580499)
		(end 158.944999 96.474999)
		(width 0.1)
		(layer "F.Cu")
		(net 58)
	)
	(segment
		(start 157.9 96.580499)
		(end 158.839499 96.580499)
		(width 0.1)
		(layer "F.Cu")
		(net 58)
	)
	(segment
		(start 158.355 95.055)
		(end 158.944999 95.644999)
		(width 0.1)
		(layer "F.Cu")
		(net 58)
	)
	(segment
		(start 156.55 97.580499)
		(end 157.2 96.930499)
		(width 0.1)
		(layer "F.Cu")
		(net 59)
	)
	(segment
		(start 157.355 95.490499)
		(end 157.395 95.530499)
		(width 0.1)
		(layer "F.Cu")
		(net 59)
	)
	(segment
		(start 157.2 95.725499)
		(end 157.395 95.530499)
		(width 0.1)
		(layer "F.Cu")
		(net 59)
	)
	(segment
		(start 157.2 96.930499)
		(end 157.2 95.725499)
		(width 0.1)
		(layer "F.Cu")
		(net 59)
	)
	(segment
		(start 157.355 94.535)
		(end 157.355 95.490499)
		(width 0.1)
		(layer "F.Cu")
		(net 59)
	)
	(via
		(at 146.24 73.75)
		(size 0.45)
		(drill 0.2)
		(layers "F.Cu" "B.Cu")
		(remove_unused_layers yes)
		(keep_end_layers yes)
		(zone_layer_connections)
		(net 60)
	)
	(via
		(at 152.6 145.4)
		(size 0.45)
		(drill 0.2)
		(layers "F.Cu" "B.Cu")
		(remove_unused_layers yes)
		(keep_end_layers yes)
		(zone_layer_connections)
		(net 60)
	)
	(segment
		(start 152.580001 145.419999)
		(end 152.6 145.4)
		(width 0.1)
		(layer "B.Cu")
		(net 60)
	)
	(segment
		(start 152.580001 146.18)
		(end 152.580001 145.419999)
		(width 0.1)
		(layer "B.Cu")
		(net 60)
	)
	(segment
		(start 149.6 93.3)
		(end 149.6 94.3)
		(width 0.1)
		(layer "In3.Cu")
		(net 60)
	)
	(segment
		(start 150.1 92.8)
		(end 149.6 93.3)
		(width 0.1)
		(layer "In3.Cu")
		(net 60)
	)
	(segment
		(start 163 135.4)
		(end 159.8 138.6)
		(width 0.1)
		(layer "In3.Cu")
		(net 60)
	)
	(segment
		(start 149.6 94.3)
		(end 150.7 95.4)
		(width 0.1)
		(layer "In3.Cu")
		(net 60)
	)
	(segment
		(start 166.000001 103.8)
		(end 166.000001 117.168629)
		(width 0.1)
		(layer "In3.Cu")
		(net 60)
	)
	(segment
		(start 147.5 81.7)
		(end 150.1 84.3)
		(width 0.1)
		(layer "In3.Cu")
		(net 60)
	)
	(segment
		(start 146.24 73.75)
		(end 146.65 73.75)
		(width 0.1)
		(layer "In3.Cu")
		(net 60)
	)
	(segment
		(start 152.6 140.8)
		(end 152.6 145.4)
		(width 0.1)
		(layer "In3.Cu")
		(net 60)
	)
	(segment
		(start 150.7 95.4)
		(end 150.7 99.1)
		(width 0.1)
		(layer "In3.Cu")
		(net 60)
	)
	(segment
		(start 163 132.262742)
		(end 163 135.4)
		(width 0.1)
		(layer "In3.Cu")
		(net 60)
	)
	(segment
		(start 147.5 74.6)
		(end 147.5 81.7)
		(width 0.1)
		(layer "In3.Cu")
		(net 60)
	)
	(segment
		(start 165.600001 103.4)
		(end 166.000001 103.8)
		(width 0.1)
		(layer "In3.Cu")
		(net 60)
	)
	(segment
		(start 159.8 138.6)
		(end 154.8 138.6)
		(width 0.1)
		(layer "In3.Cu")
		(net 60)
	)
	(segment
		(start 146.65 73.75)
		(end 147.5 74.6)
		(width 0.1)
		(layer "In3.Cu")
		(net 60)
	)
	(segment
		(start 150.7 99.1)
		(end 150 99.8)
		(width 0.1)
		(layer "In3.Cu")
		(net 60)
	)
	(segment
		(start 160.5 122.66863)
		(end 160.5 129.762742)
		(width 0.1)
		(layer "In3.Cu")
		(net 60)
	)
	(segment
		(start 150 99.8)
		(end 150 102.6)
		(width 0.1)
		(layer "In3.Cu")
		(net 60)
	)
	(segment
		(start 160.5 129.762742)
		(end 163 132.262742)
		(width 0.1)
		(layer "In3.Cu")
		(net 60)
	)
	(segment
		(start 150.8 103.4)
		(end 165.600001 103.4)
		(width 0.1)
		(layer "In3.Cu")
		(net 60)
	)
	(segment
		(start 150 102.6)
		(end 150.8 103.4)
		(width 0.1)
		(layer "In3.Cu")
		(net 60)
	)
	(segment
		(start 150.1 84.3)
		(end 150.1 92.8)
		(width 0.1)
		(layer "In3.Cu")
		(net 60)
	)
	(segment
		(start 154.8 138.6)
		(end 152.6 140.8)
		(width 0.1)
		(layer "In3.Cu")
		(net 60)
	)
	(segment
		(start 166.000001 117.168629)
		(end 160.5 122.66863)
		(width 0.1)
		(layer "In3.Cu")
		(net 60)
	)
	(via
		(at 150.6 145.4)
		(size 0.45)
		(drill 0.2)
		(layers "F.Cu" "B.Cu")
		(remove_unused_layers yes)
		(keep_end_layers yes)
		(zone_layer_connections)
		(net 61)
	)
	(via
		(at 146.24 72.75)
		(size 0.45)
		(drill 0.2)
		(layers "F.Cu" "B.Cu")
		(remove_unused_layers yes)
		(keep_end_layers yes)
		(zone_layer_connections)
		(net 61)
	)
	(segment
		(start 150.58 146.18)
		(end 150.58 145.42)
		(width 0.1)
		(layer "B.Cu")
		(net 61)
	)
	(segment
		(start 150.58 145.42)
		(end 150.6 145.4)
		(width 0.1)
		(layer "B.Cu")
		(net 61)
	)
	(segment
		(start 145.8 74.03137)
		(end 145.8 73.19)
		(width 0.1)
		(layer "In3.Cu")
		(net 61)
	)
	(segment
		(start 146.700001 74.931371)
		(end 145.8 74.03137)
		(width 0.1)
		(layer "In3.Cu")
		(net 61)
	)
	(segment
		(start 150.4 96.6)
		(end 149.4 95.6)
		(width 0.1)
		(layer "In3.Cu")
		(net 61)
	)
	(segment
		(start 162.6 132.428428)
		(end 160.099999 129.928427)
		(width 0.1)
		(layer "In3.Cu")
		(net 61)
	)
	(segment
		(start 160.099999 122.502943)
		(end 165.599999 117.002943)
		(width 0.1)
		(layer "In3.Cu")
		(net 61)
	)
	(segment
		(start 150.4 98.834314)
		(end 150.4 96.6)
		(width 0.1)
		(layer "In3.Cu")
		(net 61)
	)
	(segment
		(start 165.599999 104.05)
		(end 165.199999 103.65)
		(width 0.1)
		(layer "In3.Cu")
		(net 61)
	)
	(segment
		(start 149.417157 99.817157)
		(end 150.4 98.834314)
		(width 0.1)
		(layer "In3.Cu")
		(net 61)
	)
	(segment
		(start 150.6 145.4)
		(end 150.6 142)
		(width 0.1)
		(layer "In3.Cu")
		(net 61)
	)
	(segment
		(start 149.417157 102.467157)
		(end 149.417157 99.817157)
		(width 0.1)
		(layer "In3.Cu")
		(net 61)
	)
	(segment
		(start 159.8 138.2)
		(end 162.6 135.4)
		(width 0.1)
		(layer "In3.Cu")
		(net 61)
	)
	(segment
		(start 149.4 95.6)
		(end 149.4 92.4)
		(width 0.1)
		(layer "In3.Cu")
		(net 61)
	)
	(segment
		(start 149.3 92.3)
		(end 149.3 84.63137)
		(width 0.1)
		(layer "In3.Cu")
		(net 61)
	)
	(segment
		(start 149.4 92.4)
		(end 149.3 92.3)
		(width 0.1)
		(layer "In3.Cu")
		(net 61)
	)
	(segment
		(start 165.199999 103.65)
		(end 150.6 103.65)
		(width 0.1)
		(layer "In3.Cu")
		(net 61)
	)
	(segment
		(start 145.8 73.19)
		(end 146.24 72.75)
		(width 0.1)
		(layer "In3.Cu")
		(net 61)
	)
	(segment
		(start 162.6 135.4)
		(end 162.6 132.428428)
		(width 0.1)
		(layer "In3.Cu")
		(net 61)
	)
	(segment
		(start 154.4 138.2)
		(end 159.8 138.2)
		(width 0.1)
		(layer "In3.Cu")
		(net 61)
	)
	(segment
		(start 160.099999 129.928427)
		(end 160.099999 122.502943)
		(width 0.1)
		(layer "In3.Cu")
		(net 61)
	)
	(segment
		(start 146.700001 82.031371)
		(end 146.700001 74.931371)
		(width 0.1)
		(layer "In3.Cu")
		(net 61)
	)
	(segment
		(start 150.6 103.65)
		(end 149.417157 102.467157)
		(width 0.1)
		(layer "In3.Cu")
		(net 61)
	)
	(segment
		(start 149.3 84.63137)
		(end 146.700001 82.031371)
		(width 0.1)
		(layer "In3.Cu")
		(net 61)
	)
	(segment
		(start 150.6 142)
		(end 154.4 138.2)
		(width 0.1)
		(layer "In3.Cu")
		(net 61)
	)
	(segment
		(start 165.599999 117.002943)
		(end 165.599999 104.05)
		(width 0.1)
		(layer "In3.Cu")
		(net 61)
	)
	(via
		(at 154.025 89.25)
		(size 0.45)
		(drill 0.2)
		(layers "F.Cu" "B.Cu")
		(remove_unused_layers yes)
		(keep_end_layers yes)
		(zone_layer_connections)
		(net 62)
	)
	(segment
		(start 153.8 89.195)
		(end 153.975 89.195)
		(width 0.15)
		(layer "B.Cu")
		(net 62)
	)
	(segment
		(start 153.975 89.195)
		(end 154.03 89.25)
		(width 0.15)
		(layer "B.Cu")
		(net 62)
	)
	(via
		(at 157.485 90.25)
		(size 0.45)
		(drill 0.2)
		(layers "F.Cu" "B.Cu")
		(remove_unused_layers yes)
		(keep_end_layers yes)
		(zone_layer_connections)
		(net 63)
	)
	(segment
		(start 157.49 90.25)
		(end 157.49 89.975)
		(width 0.1)
		(layer "B.Cu")
		(net 63)
	)
	(segment
		(start 154.145 75.25)
		(end 154.025 75.25)
		(width 0.15)
		(layer "F.Cu")
		(net 64)
	)
	(via
		(at 154.145 75.25)
		(size 0.45)
		(drill 0.2)
		(layers "F.Cu" "B.Cu")
		(remove_unused_layers yes)
		(keep_end_layers yes)
		(zone_layer_connections)
		(net 64)
	)
	(segment
		(start 154.155 75.255)
		(end 154.15 75.25)
		(width 0.15)
		(layer "B.Cu")
		(net 64)
	)
	(segment
		(start 154.45 75.255)
		(end 154.155 75.255)
		(width 0.15)
		(layer "B.Cu")
		(net 64)
	)
	(segment
		(start 154.23 75.475)
		(end 154.45 75.255)
		(width 0.15)
		(layer "B.Cu")
		(net 64)
	)
	(segment
		(start 155.45 75.255)
		(end 154.45 75.255)
		(width 0.15)
		(layer "B.Cu")
		(net 64)
	)
	(via
		(at 176.6 145.4)
		(size 0.45)
		(drill 0.2)
		(layers "F.Cu" "B.Cu")
		(remove_unused_layers yes)
		(keep_end_layers yes)
		(zone_layer_connections)
		(net 65)
	)
	(via
		(at 151.3 100.65)
		(size 0.45)
		(drill 0.2)
		(layers "F.Cu" "B.Cu")
		(remove_unused_layers yes)
		(keep_end_layers yes)
		(zone_layer_connections)
		(net 65)
	)
	(via
		(at 144.51 91.75)
		(size 0.45)
		(drill 0.2)
		(layers "F.Cu" "B.Cu")
		(remove_unused_layers yes)
		(keep_end_layers yes)
		(zone_layer_connections)
		(net 65)
	)
	(segment
		(start 176.58 146.18)
		(end 176.6 146.16)
		(width 0.1)
		(layer "B.Cu")
		(net 65)
	)
	(segment
		(start 176.6 146.16)
		(end 176.6 145.4)
		(width 0.1)
		(layer "B.Cu")
		(net 65)
	)
	(segment
		(start 162.099999 129.099999)
		(end 162.099999 123.331371)
		(width 0.1)
		(layer "In3.Cu")
		(net 65)
	)
	(segment
		(start 152.398527 99.551473)
		(end 154.848527 99.551473)
		(width 0.1)
		(layer "In3.Cu")
		(net 65)
	)
	(segment
		(start 176.6 145.4)
		(end 176.6 144.6)
		(width 0.1)
		(layer "In3.Cu")
		(net 65)
	)
	(segment
		(start 167.599999 102.268629)
		(end 166.231371 100.900001)
		(width 0.1)
		(layer "In3.Cu")
		(net 65)
	)
	(segment
		(start 164.6 136.4)
		(end 164.6 131.6)
		(width 0.1)
		(layer "In3.Cu")
		(net 65)
	)
	(segment
		(start 170 138)
		(end 166.2 138)
		(width 0.1)
		(layer "In3.Cu")
		(net 65)
	)
	(segment
		(start 164.6 131.6)
		(end 162.099999 129.099999)
		(width 0.1)
		(layer "In3.Cu")
		(net 65)
	)
	(segment
		(start 167.599999 117.831371)
		(end 167.599999 102.268629)
		(width 0.1)
		(layer "In3.Cu")
		(net 65)
	)
	(segment
		(start 151.3 100.65)
		(end 152.398527 99.551473)
		(width 0.1)
		(layer "In3.Cu")
		(net 65)
	)
	(segment
		(start 176.6 144.6)
		(end 170 138)
		(width 0.1)
		(layer "In3.Cu")
		(net 65)
	)
	(segment
		(start 166.231371 100.900001)
		(end 156.197055 100.900001)
		(width 0.1)
		(layer "In3.Cu")
		(net 65)
	)
	(segment
		(start 162.099999 123.331371)
		(end 167.599999 117.831371)
		(width 0.1)
		(layer "In3.Cu")
		(net 65)
	)
	(segment
		(start 166.2 138)
		(end 164.6 136.4)
		(width 0.1)
		(layer "In3.Cu")
		(net 65)
	)
	(segment
		(start 156.197055 100.900001)
		(end 154.848527 99.551473)
		(width 0.1)
		(layer "In3.Cu")
		(net 65)
	)
	(segment
		(start 144.51 92.26)
		(end 145.4 93.15)
		(width 0.1)
		(layer "In5.Cu")
		(net 65)
	)
	(segment
		(start 144.51 91.75)
		(end 144.51 92.26)
		(width 0.1)
		(layer "In5.Cu")
		(net 65)
	)
	(segment
		(start 145.4 93.15)
		(end 145.4 93.55)
		(width 0.1)
		(layer "In5.Cu")
		(net 65)
	)
	(segment
		(start 151.3 99.45)
		(end 151.3 100.65)
		(width 0.1)
		(layer "In5.Cu")
		(net 65)
	)
	(segment
		(start 145.4 93.55)
		(end 151.3 99.45)
		(width 0.1)
		(layer "In5.Cu")
		(net 65)
	)
	(via
		(at 174.6 145.4)
		(size 0.45)
		(drill 0.2)
		(layers "F.Cu" "B.Cu")
		(remove_unused_layers yes)
		(keep_end_layers yes)
		(zone_layer_connections)
		(net 66)
	)
	(via
		(at 147.97 73.75)
		(size 0.45)
		(drill 0.2)
		(layers "F.Cu" "B.Cu")
		(remove_unused_layers yes)
		(keep_end_layers yes)
		(zone_layer_connections)
		(net 66)
	)
	(segment
		(start 174.58 145.42)
		(end 174.6 145.4)
		(width 0.1)
		(layer "B.Cu")
		(net 66)
	)
	(segment
		(start 174.58 146.18)
		(end 174.58 145.42)
		(width 0.1)
		(layer "B.Cu")
		(net 66)
	)
	(segment
		(start 150.775 94.275)
		(end 150.775 90.825)
		(width 0.1)
		(layer "In3.Cu")
		(net 66)
	)
	(segment
		(start 151.6 90.2)
		(end 151.85 89.95)
		(width 0.1)
		(layer "In3.Cu")
		(net 66)
	)
	(segment
		(start 150.8 100.7)
		(end 150.8 100.2)
		(width 0.1)
		(layer "In3.Cu")
		(net 66)
	)
	(segment
		(start 150.8 100.2)
		(end 152.2 98.8)
		(width 0.1)
		(layer "In3.Cu")
		(net 66)
	)
	(segment
		(start 152.2 98.8)
		(end 152.2 95.7)
		(width 0.1)
		(layer "In3.Cu")
		(net 66)
	)
	(segment
		(start 167.199997 117.665685)
		(end 167.199997 102.434315)
		(width 0.1)
		(layer "In3.Cu")
		(net 66)
	)
	(segment
		(start 151.4 90.2)
		(end 151.6 90.2)
		(width 0.1)
		(layer "In3.Cu")
		(net 66)
	)
	(segment
		(start 169.4 138.4)
		(end 166 138.4)
		(width 0.1)
		(layer "In3.Cu")
		(net 66)
	)
	(segment
		(start 150.775 90.825)
		(end 151.4 90.2)
		(width 0.1)
		(layer "In3.Cu")
		(net 66)
	)
	(segment
		(start 161.699998 129.265684)
		(end 161.699998 123.165684)
		(width 0.1)
		(layer "In3.Cu")
		(net 66)
	)
	(segment
		(start 148.9 72.3)
		(end 147.8 72.3)
		(width 0.1)
		(layer "In3.Cu")
		(net 66)
	)
	(segment
		(start 161.699998 123.165684)
		(end 167.199997 117.665685)
		(width 0.1)
		(layer "In3.Cu")
		(net 66)
	)
	(segment
		(start 152.2 95.7)
		(end 150.775 94.275)
		(width 0.1)
		(layer "In3.Cu")
		(net 66)
	)
	(segment
		(start 151.8 101.1)
		(end 151.2 101.1)
		(width 0.1)
		(layer "In3.Cu")
		(net 66)
	)
	(segment
		(start 166.065685 101.300003)
		(end 155.700003 101.300003)
		(width 0.1)
		(layer "In3.Cu")
		(net 66)
	)
	(segment
		(start 174.6 143.6)
		(end 169.4 138.4)
		(width 0.1)
		(layer "In3.Cu")
		(net 66)
	)
	(segment
		(start 147.8 72.3)
		(end 147.5 72.6)
		(width 0.1)
		(layer "In3.Cu")
		(net 66)
	)
	(segment
		(start 155.1 100.7)
		(end 152.2 100.7)
		(width 0.1)
		(layer "In3.Cu")
		(net 66)
	)
	(segment
		(start 166 138.4)
		(end 164.2 136.6)
		(width 0.1)
		(layer "In3.Cu")
		(net 66)
	)
	(segment
		(start 167.199997 102.434315)
		(end 166.065685 101.300003)
		(width 0.1)
		(layer "In3.Cu")
		(net 66)
	)
	(segment
		(start 164.2 136.6)
		(end 164.2 131.765686)
		(width 0.1)
		(layer "In3.Cu")
		(net 66)
	)
	(segment
		(start 150.1 81.825126)
		(end 150.1 73.5)
		(width 0.1)
		(layer "In3.Cu")
		(net 66)
	)
	(segment
		(start 174.6 145.4)
		(end 174.6 143.6)
		(width 0.1)
		(layer "In3.Cu")
		(net 66)
	)
	(segment
		(start 151.85 83.575126)
		(end 150.1 81.825126)
		(width 0.1)
		(layer "In3.Cu")
		(net 66)
	)
	(segment
		(start 151.85 89.95)
		(end 151.85 83.575126)
		(width 0.1)
		(layer "In3.Cu")
		(net 66)
	)
	(segment
		(start 151.2 101.1)
		(end 150.8 100.7)
		(width 0.1)
		(layer "In3.Cu")
		(net 66)
	)
	(segment
		(start 155.700003 101.300003)
		(end 155.1 100.7)
		(width 0.1)
		(layer "In3.Cu")
		(net 66)
	)
	(segment
		(start 150.1 73.5)
		(end 148.9 72.3)
		(width 0.1)
		(layer "In3.Cu")
		(net 66)
	)
	(segment
		(start 147.5 72.6)
		(end 147.5 73.28)
		(width 0.1)
		(layer "In3.Cu")
		(net 66)
	)
	(segment
		(start 152.2 100.7)
		(end 151.8 101.1)
		(width 0.1)
		(layer "In3.Cu")
		(net 66)
	)
	(segment
		(start 147.5 73.28)
		(end 147.97 73.75)
		(width 0.1)
		(layer "In3.Cu")
		(net 66)
	)
	(segment
		(start 164.2 131.765686)
		(end 161.699998 129.265684)
		(width 0.1)
		(layer "In3.Cu")
		(net 66)
	)
	(via
		(at 172.6 145.4)
		(size 0.45)
		(drill 0.2)
		(layers "F.Cu" "B.Cu")
		(remove_unused_layers yes)
		(keep_end_layers yes)
		(zone_layer_connections)
		(net 67)
	)
	(via
		(at 147.97 72.75)
		(size 0.45)
		(drill 0.2)
		(layers "F.Cu" "B.Cu")
		(remove_unused_layers yes)
		(keep_end_layers yes)
		(zone_layer_connections)
		(net 67)
	)
	(segment
		(start 172.58 146.18)
		(end 172.58 145.42)
		(width 0.1)
		(layer "B.Cu")
		(net 67)
	)
	(segment
		(start 172.58 145.42)
		(end 172.6 145.4)
		(width 0.1)
		(layer "B.Cu")
		(net 67)
	)
	(segment
		(start 151.3 89.25)
		(end 151.3 83.802944)
		(width 0.1)
		(layer "In3.Cu")
		(net 67)
	)
	(segment
		(start 150.548528 83.051472)
		(end 149.751472 83.051472)
		(width 0.1)
		(layer "In3.Cu")
		(net 67)
	)
	(segment
		(start 155.7 101.7)
		(end 155.5 101.5)
		(width 0.1)
		(layer "In3.Cu")
		(net 67)
	)
	(segment
		(start 172.6 142.2)
		(end 169.2 138.8)
		(width 0.1)
		(layer "In3.Cu")
		(net 67)
	)
	(segment
		(start 151.4 97.8)
		(end 151.4 95.5)
		(width 0.1)
		(layer "In3.Cu")
		(net 67)
	)
	(segment
		(start 161.3 129.43137)
		(end 161.3 123)
		(width 0.1)
		(layer "In3.Cu")
		(net 67)
	)
	(segment
		(start 151 101.5)
		(end 150.4 100.9)
		(width 0.1)
		(layer "In3.Cu")
		(net 67)
	)
	(segment
		(start 163.8 131.93137)
		(end 161.3 129.43137)
		(width 0.1)
		(layer "In3.Cu")
		(net 67)
	)
	(segment
		(start 149.3 74.08)
		(end 147.97 72.75)
		(width 0.1)
		(layer "In3.Cu")
		(net 67)
	)
	(segment
		(start 150.4 100.9)
		(end 150.4 100)
		(width 0.1)
		(layer "In3.Cu")
		(net 67)
	)
	(segment
		(start 172.6 145.4)
		(end 172.6 142.2)
		(width 0.1)
		(layer "In3.Cu")
		(net 67)
	)
	(segment
		(start 150.5 90.05)
		(end 151.3 89.25)
		(width 0.1)
		(layer "In3.Cu")
		(net 67)
	)
	(segment
		(start 166.8 117.5)
		(end 166.8 102.6)
		(width 0.1)
		(layer "In3.Cu")
		(net 67)
	)
	(segment
		(start 169.2 138.8)
		(end 165.6 138.8)
		(width 0.1)
		(layer "In3.Cu")
		(net 67)
	)
	(segment
		(start 151 98.2)
		(end 151.4 97.8)
		(width 0.1)
		(layer "In3.Cu")
		(net 67)
	)
	(segment
		(start 149.751472 83.051472)
		(end 149.3 82.6)
		(width 0.1)
		(layer "In3.Cu")
		(net 67)
	)
	(segment
		(start 166.8 102.6)
		(end 165.9 101.7)
		(width 0.1)
		(layer "In3.Cu")
		(net 67)
	)
	(segment
		(start 161.3 123)
		(end 166.8 117.5)
		(width 0.1)
		(layer "In3.Cu")
		(net 67)
	)
	(segment
		(start 165.6 138.8)
		(end 163.8 137)
		(width 0.1)
		(layer "In3.Cu")
		(net 67)
	)
	(segment
		(start 163.8 137)
		(end 163.8 131.93137)
		(width 0.1)
		(layer "In3.Cu")
		(net 67)
	)
	(segment
		(start 150.4 100)
		(end 151 99.4)
		(width 0.1)
		(layer "In3.Cu")
		(net 67)
	)
	(segment
		(start 149.3 82.6)
		(end 149.3 74.08)
		(width 0.1)
		(layer "In3.Cu")
		(net 67)
	)
	(segment
		(start 155.5 101.5)
		(end 151 101.5)
		(width 0.1)
		(layer "In3.Cu")
		(net 67)
	)
	(segment
		(start 150.5 94.6)
		(end 150.5 90.05)
		(width 0.1)
		(layer "In3.Cu")
		(net 67)
	)
	(segment
		(start 151 99.4)
		(end 151 98.2)
		(width 0.1)
		(layer "In3.Cu")
		(net 67)
	)
	(segment
		(start 151.3 83.802944)
		(end 150.548528 83.051472)
		(width 0.1)
		(layer "In3.Cu")
		(net 67)
	)
	(segment
		(start 165.9 101.7)
		(end 155.7 101.7)
		(width 0.1)
		(layer "In3.Cu")
		(net 67)
	)
	(segment
		(start 151.4 95.5)
		(end 150.5 94.6)
		(width 0.1)
		(layer "In3.Cu")
		(net 67)
	)
	(segment
		(start 143.15 120.85)
		(end 143.2 120.8)
		(width 0.1)
		(layer "F.Cu")
		(net 68)
	)
	(segment
		(start 129.47 126.23)
		(end 129.47 125.596796)
		(width 0.1)
		(layer "F.Cu")
		(net 68)
	)
	(segment
		(start 141.49142 120.85)
		(end 143.15 120.85)
		(width 0.1)
		(layer "F.Cu")
		(net 68)
	)
	(segment
		(start 129.15 126.55)
		(end 129.47 126.23)
		(width 0.1)
		(layer "F.Cu")
		(net 68)
	)
	(segment
		(start 127.85 126.55)
		(end 127.525 126.225)
		(width 0.1)
		(layer "F.Cu")
		(net 68)
	)
	(segment
		(start 129.5245 125.5255)
		(end 129.5245 125.542296)
		(width 0.1)
		(layer "F.Cu")
		(net 68)
	)
	(segment
		(start 127.85 126.55)
		(end 128.5 127.2)
		(width 0.1)
		(layer "F.Cu")
		(net 68)
	)
	(segment
		(start 129.8 125.25)
		(end 129.475 124.925)
		(width 0.1)
		(layer "F.Cu")
		(net 68)
	)
	(segment
		(start 127.2 126.55)
		(end 127.525 126.875)
		(width 0.1)
		(layer "F.Cu")
		(net 68)
	)
	(segment
		(start 127.85 127.2)
		(end 128.5 126.55)
		(width 0.1)
		(layer "F.Cu")
		(net 68)
	)
	(segment
		(start 127.85 126.55)
		(end 127.525 126.875)
		(width 0.1)
		(layer "F.Cu")
		(net 68)
	)
	(segment
		(start 129.8 124.6)
		(end 129.475 124.925)
		(width 0.1)
		(layer "F.Cu")
		(net 68)
	)
	(segment
		(start 127.2 126.55)
		(end 127.525 126.225)
		(width 0.1)
		(layer "F.Cu")
		(net 68)
	)
	(segment
		(start 129.475 124.275)
		(end 129.8 124.6)
		(width 0.1)
		(layer "F.Cu")
		(net 68)
	)
	(segment
		(start 127.85 127.2)
		(end 127.525 127.525)
		(width 0.1)
		(layer "F.Cu")
		(net 68)
	)
	(segment
		(start 127.525 126.875)
		(end 127.85 127.2)
		(width 0.1)
		(layer "F.Cu")
		(net 68)
	)
	(segment
		(start 129.8 125.25)
		(end 129.5245 125.5255)
		(width 0.1)
		(layer "F.Cu")
		(net 68)
	)
	(segment
		(start 128.5 127.2)
		(end 129.15 126.55)
		(width 0.1)
		(layer "F.Cu")
		(net 68)
	)
	(segment
		(start 128.5 126.55)
		(end 128.825 126.875)
		(width 0.1)
		(layer "F.Cu")
		(net 68)
	)
	(segment
		(start 129.8 123.95)
		(end 129.475 124.275)
		(width 0.1)
		(layer "F.Cu")
		(net 68)
	)
	(segment
		(start 129.47 125.596796)
		(end 129.5245 125.542296)
		(width 0.1)
		(layer "F.Cu")
		(net 68)
	)
	(via
		(at 129.5245 125.542296)
		(size 0.45)
		(drill 0.2)
		(layers "F.Cu" "B.Cu")
		(remove_unused_layers yes)
		(keep_end_layers yes)
		(zone_layer_connections "In2.Cu")
		(net 68)
	)
	(via
		(at 140 121.5)
		(size 0.45)
		(drill 0.2)
		(layers "F.Cu" "B.Cu")
		(remove_unused_layers yes)
		(keep_end_layers yes)
		(free yes)
		(zone_layer_connections "In2.Cu")
		(net 68)
	)
	(via
		(at 140 122.5)
		(size 0.45)
		(drill 0.2)
		(layers "F.Cu" "B.Cu")
		(remove_unused_layers yes)
		(keep_end_layers yes)
		(free yes)
		(zone_layer_connections "In2.Cu")
		(net 68)
	)
	(via
		(at 127.525 127.525)
		(size 0.45)
		(drill 0.2)
		(layers "F.Cu" "B.Cu")
		(remove_unused_layers yes)
		(keep_end_layers yes)
		(zone_layer_connections "In2.Cu")
		(net 68)
	)
	(via
		(at 140.75 122)
		(size 0.45)
		(drill 0.2)
		(layers "F.Cu" "B.Cu")
		(remove_unused_layers yes)
		(keep_end_layers yes)
		(free yes)
		(zone_layer_connections "In2.Cu")
		(net 68)
	)
	(via
		(at 129.475 124.275)
		(size 0.45)
		(drill 0.2)
		(layers "F.Cu" "B.Cu")
		(remove_unused_layers yes)
		(keep_end_layers yes)
		(zone_layer_connections "In2.Cu")
		(net 68)
	)
	(via
		(at 140.75 121.5)
		(size 0.45)
		(drill 0.2)
		(layers "F.Cu" "B.Cu")
		(remove_unused_layers yes)
		(keep_end_layers yes)
		(free yes)
		(zone_layer_connections "In2.Cu")
		(net 68)
	)
	(via
		(at 143.2 120.8)
		(size 0.45)
		(drill 0.2)
		(layers "F.Cu" "B.Cu")
		(remove_unused_layers yes)
		(keep_end_layers yes)
		(zone_layer_connections)
		(net 68)
	)
	(via
		(at 116.5 99.5)
		(size 0.45)
		(drill 0.2)
		(layers "F.Cu" "B.Cu")
		(remove_unused_layers yes)
		(keep_end_layers yes)
		(zone_layer_connections)
		(net 68)
	)
	(via
		(at 119.3 88)
		(size 0.45)
		(drill 0.2)
		(layers "F.Cu" "B.Cu")
		(remove_unused_layers yes)
		(keep_end_layers yes)
		(zone_layer_connections)
		(net 68)
	)
	(via
		(at 127.525 126.875)
		(size 0.45)
		(drill 0.2)
		(layers "F.Cu" "B.Cu")
		(remove_unused_layers yes)
		(keep_end_layers yes)
		(zone_layer_connections "In2.Cu")
		(net 68)
	)
	(via
		(at 140.75 122.5)
		(size 0.45)
		(drill 0.2)
		(layers "F.Cu" "B.Cu")
		(remove_unused_layers yes)
		(keep_end_layers yes)
		(free yes)
		(zone_layer_connections "In2.Cu")
		(net 68)
	)
	(via
		(at 127.525 126.225)
		(size 0.45)
		(drill 0.2)
		(layers "F.Cu" "B.Cu")
		(remove_unused_layers yes)
		(keep_end_layers yes)
		(zone_layer_connections "In2.Cu")
		(net 68)
	)
	(via
		(at 129.475 124.925)
		(size 0.45)
		(drill 0.2)
		(layers "F.Cu" "B.Cu")
		(remove_unused_layers yes)
		(keep_end_layers yes)
		(zone_layer_connections "In2.Cu")
		(net 68)
	)
	(via
		(at 130.8 113.9)
		(size 0.45)
		(drill 0.2)
		(layers "F.Cu" "B.Cu")
		(remove_unused_layers yes)
		(keep_end_layers yes)
		(zone_layer_connections)
		(net 68)
	)
	(via
		(at 140 122)
		(size 0.45)
		(drill 0.2)
		(layers "F.Cu" "B.Cu")
		(remove_unused_layers yes)
		(keep_end_layers yes)
		(free yes)
		(zone_layer_connections "In2.Cu")
		(net 68)
	)
	(segment
		(start 129.475 125.492796)
		(end 129.5245 125.542296)
		(width 0.25)
		(layer "B.Cu")
		(net 68)
	)
	(segment
		(start 119.3 88)
		(end 119.3 89.07)
		(width 0.1)
		(layer "B.Cu")
		(net 68)
	)
	(segment
		(start 127.525 127.525)
		(end 127.525 128.32)
		(width 0.25)
		(layer "B.Cu")
		(net 68)
	)
	(segment
		(start 127.525 128.32)
		(end 127.529999 128.324999)
		(width 0.25)
		(layer "B.Cu")
		(net 68)
	)
	(segment
		(start 129.475 124.275)
		(end 129.475 125.492796)
		(width 0.25)
		(layer "B.Cu")
		(net 68)
	)
	(segment
		(start 127.525 126.225)
		(end 127.525 126.875)
		(width 0.25)
		(layer "B.Cu")
		(net 68)
	)
	(segment
		(start 127.525 126.875)
		(end 127.525 127.525)
		(width 0.25)
		(layer "B.Cu")
		(net 68)
	)
	(segment
		(start 129.474999 124.430001)
		(end 129.474999 125.492795)
		(width 0.25)
		(layer "B.Cu")
		(net 68)
	)
	(segment
		(start 119.3 89.07)
		(end 119.5 89.27)
		(width 0.1)
		(layer "B.Cu")
		(net 68)
	)
	(segment
		(start 129.474999 125.492795)
		(end 129.5245 125.542296)
		(width 0.25)
		(layer "B.Cu")
		(net 68)
	)
	(segment
		(start 122.175 107.625)
		(end 122.175 109.375)
		(width 0.1)
		(layer "In3.Cu")
		(net 68)
	)
	(segment
		(start 116.5 101.95)
		(end 122.175 107.625)
		(width 0.1)
		(layer "In3.Cu")
		(net 68)
	)
	(segment
		(start 124.95 112.15)
		(end 129.65 112.15)
		(width 0.1)
		(layer "In3.Cu")
		(net 68)
	)
	(segment
		(start 129.65 112.15)
		(end 130.8 113.3)
		(width 0.1)
		(layer "In3.Cu")
		(net 68)
	)
	(segment
		(start 116.5 99.5)
		(end 116.5 101.95)
		(width 0.1)
		(layer "In3.Cu")
		(net 68)
	)
	(segment
		(start 130.8 113.3)
		(end 130.8 113.9)
		(width 0.1)
		(layer "In3.Cu")
		(net 68)
	)
	(segment
		(start 122.175 109.375)
		(end 124.95 112.15)
		(width 0.1)
		(layer "In3.Cu")
		(net 68)
	)
	(segment
		(start 116 91)
		(end 116.5 91.5)
		(width 0.1)
		(layer "In5.Cu")
		(net 68)
	)
	(segment
		(start 138.2 110.6)
		(end 140.9 110.6)
		(width 0.1)
		(layer "In5.Cu")
		(net 68)
	)
	(segment
		(start 116.5 91.5)
		(end 116.5 99.5)
		(width 0.1)
		(layer "In5.Cu")
		(net 68)
	)
	(segment
		(start 130.8 113.9)
		(end 130.8 113.7)
		(width 0.1)
		(layer "In5.Cu")
		(net 68)
	)
	(segment
		(start 142.1 111.8)
		(end 142.1 114)
		(width 0.1)
		(layer "In5.Cu")
		(net 68)
	)
	(segment
		(start 116 88.5)
		(end 116 91)
		(width 0.1)
		(layer "In5.Cu")
		(net 68)
	)
	(segment
		(start 142.1 114)
		(end 143.2 115.1)
		(width 0.1)
		(layer "In5.Cu")
		(net 68)
	)
	(segment
		(start 130.8 113.7)
		(end 133.1 111.4)
		(width 0.1)
		(layer "In5.Cu")
		(net 68)
	)
	(segment
		(start 137.4 111.4)
		(end 138.2 110.6)
		(width 0.1)
		(layer "In5.Cu")
		(net 68)
	)
	(segment
		(start 116.5 88)
		(end 116 88.5)
		(width 0.1)
		(layer "In5.Cu")
		(net 68)
	)
	(segment
		(start 119.3 88)
		(end 116.5 88)
		(width 0.1)
		(layer "In5.Cu")
		(net 68)
	)
	(segment
		(start 133.1 111.4)
		(end 137.4 111.4)
		(width 0.1)
		(layer "In5.Cu")
		(net 68)
	)
	(segment
		(start 140.9 110.6)
		(end 142.1 111.8)
		(width 0.1)
		(layer "In5.Cu")
		(net 68)
	)
	(segment
		(start 143.2 115.1)
		(end 143.2 120.8)
		(width 0.1)
		(layer "In5.Cu")
		(net 68)
	)
	(segment
		(start 133.538595 133.4)
		(end 133.5 133.438595)
		(width 0.1)
		(layer "F.Cu")
		(net 69)
	)
	(segment
		(start 133.688595 131.899101)
		(end 133.538595 132.049101)
		(width 0.19)
		(layer "F.Cu")
		(net 69)
	)
	(segment
		(start 133.5 133.438595)
		(end 133.5 134)
		(width 0.1)
		(layer "F.Cu")
		(net 69)
	)
	(segment
		(start 133.538595 132.049101)
		(end 133.538595 133.4)
		(width 0.19)
		(layer "F.Cu")
		(net 69)
	)
	(via
		(at 134.989999 116.175)
		(size 0.45)
		(drill 0.2)
		(layers "F.Cu" "B.Cu")
		(remove_unused_layers yes)
		(keep_end_layers yes)
		(zone_layer_connections)
		(net 69)
	)
	(via
		(at 133.688595 131.899101)
		(size 0.45)
		(drill 0.2)
		(layers "F.Cu" "B.Cu")
		(remove_unused_layers yes)
		(keep_end_layers yes)
		(zone_layer_connections)
		(net 69)
	)
	(segment
		(start 134.839999 116.325)
		(end 134.989999 116.175)
		(width 0.15)
		(layer "B.Cu")
		(net 69)
	)
	(segment
		(start 133.85 131.58)
		(end 133.85 131.737696)
		(width 0.25)
		(layer "B.Cu")
		(net 69)
	)
	(segment
		(start 134.244999 116)
		(end 134.569999 116.325)
		(width 0.15)
		(layer "B.Cu")
		(net 69)
	)
	(segment
		(start 133.85 131.737696)
		(end 133.688595 131.899101)
		(width 0.25)
		(layer "B.Cu")
		(net 69)
	)
	(segment
		(start 134.569999 116.325)
		(end 134.839999 116.325)
		(width 0.15)
		(layer "B.Cu")
		(net 69)
	)
	(segment
		(start 134.219999 116)
		(end 134.244999 116)
		(width 0.15)
		(layer "B.Cu")
		(net 69)
	)
	(segment
		(start 137.425 117.477512)
		(end 137.425 119.677512)
		(width 0.15)
		(layer "In5.Cu")
		(net 69)
	)
	(segment
		(start 133.543595 130.960965)
		(end 133.543595 131.754101)
		(width 0.15)
		(layer "In5.Cu")
		(net 69)
	)
	(segment
		(start 136.472488 116.525)
		(end 137.425 117.477512)
		(width 0.15)
		(layer "In5.Cu")
		(net 69)
	)
	(segment
		(start 135.9 116.325)
		(end 136.1 116.525)
		(width 0.15)
		(layer "In5.Cu")
		(net 69)
	)
	(segment
		(start 134.62956 129.875)
		(end 133.543595 130.960965)
		(width 0.15)
		(layer "In5.Cu")
		(net 69)
	)
	(segment
		(start 135.139999 116.325)
		(end 135.9 116.325)
		(width 0.15)
		(layer "In5.Cu")
		(net 69)
	)
	(segment
		(start 138.275 120.527512)
		(end 138.275 128.572488)
		(width 0.15)
		(layer "In5.Cu")
		(net 69)
	)
	(segment
		(start 134.989999 116.175)
		(end 135.139999 116.325)
		(width 0.15)
		(layer "In5.Cu")
		(net 69)
	)
	(segment
		(start 138.275 128.572488)
		(end 136.972488 129.875)
		(width 0.15)
		(layer "In5.Cu")
		(net 69)
	)
	(segment
		(start 136.1 116.525)
		(end 136.472488 116.525)
		(width 0.15)
		(layer "In5.Cu")
		(net 69)
	)
	(segment
		(start 136.972488 129.875)
		(end 134.62956 129.875)
		(width 0.15)
		(layer "In5.Cu")
		(net 69)
	)
	(segment
		(start 133.543595 131.754101)
		(end 133.688595 131.899101)
		(width 0.15)
		(layer "In5.Cu")
		(net 69)
	)
	(segment
		(start 137.425 119.677512)
		(end 138.275 120.527512)
		(width 0.15)
		(layer "In5.Cu")
		(net 69)
	)
	(via
		(at 153.16 72.75)
		(size 0.45)
		(drill 0.2)
		(layers "F.Cu" "B.Cu")
		(remove_unused_layers yes)
		(keep_end_layers yes)
		(zone_layer_connections)
		(net 70)
	)
	(segment
		(start 153.165 72.75)
		(end 153.165 72.46)
		(width 0.1)
		(layer "B.Cu")
		(net 70)
	)
	(segment
		(start 153.55 71.055)
		(end 154.1 70.505)
		(width 0.1)
		(layer "B.Cu")
		(net 70)
	)
	(segment
		(start 153.165 72.46)
		(end 153.7 71.925)
		(width 0.1)
		(layer "B.Cu")
		(net 70)
	)
	(segment
		(start 153.7 71.540133)
		(end 153.55 71.390133)
		(width 0.1)
		(layer "B.Cu")
		(net 70)
	)
	(segment
		(start 153.55 71.390133)
		(end 153.55 71.055)
		(width 0.1)
		(layer "B.Cu")
		(net 70)
	)
	(segment
		(start 153.7 71.925)
		(end 153.7 71.540133)
		(width 0.1)
		(layer "B.Cu")
		(net 70)
	)
	(via
		(at 153.16 71.75)
		(size 0.45)
		(drill 0.2)
		(layers "F.Cu" "B.Cu")
		(remove_unused_layers yes)
		(keep_end_layers yes)
		(zone_layer_connections)
		(net 71)
	)
	(segment
		(start 153.165 71.75)
		(end 153.165 71.24)
		(width 0.1)
		(layer "B.Cu")
		(net 71)
	)
	(segment
		(start 153.1 70.505)
		(end 153.1 71.175)
		(width 0.1)
		(layer "B.Cu")
		(net 71)
	)
	(segment
		(start 153.165 71.24)
		(end 153.1 71.175)
		(width 0.1)
		(layer "B.Cu")
		(net 71)
	)
	(via
		(at 152.295 72.25)
		(size 0.45)
		(drill 0.2)
		(layers "F.Cu" "B.Cu")
		(remove_unused_layers yes)
		(keep_end_layers yes)
		(zone_layer_connections)
		(net 72)
	)
	(segment
		(start 151.1 70.975)
		(end 151.1 70.505)
		(width 0.1)
		(layer "B.Cu")
		(net 72)
	)
	(segment
		(start 152.3 71.887811)
		(end 151.637189 71.225)
		(width 0.1)
		(layer "B.Cu")
		(net 72)
	)
	(segment
		(start 151.637189 71.225)
		(end 151.35 71.225)
		(width 0.1)
		(layer "B.Cu")
		(net 72)
	)
	(segment
		(start 152.3 72.25)
		(end 152.3 71.887811)
		(width 0.1)
		(layer "B.Cu")
		(net 72)
	)
	(segment
		(start 151.35 71.225)
		(end 151.1 70.975)
		(width 0.1)
		(layer "B.Cu")
		(net 72)
	)
	(via
		(at 147.105 91.25)
		(size 0.45)
		(drill 0.2)
		(layers "F.Cu" "B.Cu")
		(remove_unused_layers yes)
		(keep_end_layers yes)
		(zone_layer_connections)
		(net 73)
	)
	(segment
		(start 147.105 91.25)
		(end 147.105 91.581984)
		(width 0.1)
		(layer "B.Cu")
		(net 73)
	)
	(segment
		(start 147.105 91.581984)
		(end 146.681866 92.005118)
		(width 0.1)
		(layer "B.Cu")
		(net 73)
	)
	(segment
		(start 140.3 88.6)
		(end 140.3 85.5)
		(width 0.1)
		(layer "F.Cu")
		(net 74)
	)
	(segment
		(start 138.304 84.771)
		(end 138.3 84.775)
		(width 0.1)
		(layer "F.Cu")
		(net 74)
	)
	(segment
		(start 138.304 83.823999)
		(end 138.304 84.771)
		(width 0.1)
		(layer "F.Cu")
		(net 74)
	)
	(segment
		(start 136.275 84.775)
		(end 138.3 84.775)
		(width 0.1)
		(layer "F.Cu")
		(net 74)
	)
	(segment
		(start 142.13 89.8)
		(end 141.8 89.8)
		(width 0.1)
		(layer "F.Cu")
		(net 74)
	)
	(segment
		(start 134 83.72)
		(end 134.48 84.2)
		(width 0.1)
		(layer "F.Cu")
		(net 74)
	)
	(segment
		(start 142.79 91.749999)
		(end 142.79 93.674998)
		(width 0.1)
		(layer "F.Cu")
		(net 74)
	)
	(segment
		(start 142.355 90.025)
		(end 142.13 89.8)
		(width 0.1)
		(layer "F.Cu")
		(net 74)
	)
	(segment
		(start 142.79 93.674998)
		(end 142.789999 93.674999)
		(width 0.1)
		(layer "F.Cu")
		(net 74)
	)
	(segment
		(start 141.8 89.8)
		(end 141.2 89.2)
		(width 0.1)
		(layer "F.Cu")
		(net 74)
	)
	(segment
		(start 140.3 85.5)
		(end 139.575 84.775)
		(width 0.1)
		(layer "F.Cu")
		(net 74)
	)
	(segment
		(start 135.7 84.2)
		(end 136.275 84.775)
		(width 0.1)
		(layer "F.Cu")
		(net 74)
	)
	(segment
		(start 142.79 91.749999)
		(end 142.355 91.314999)
		(width 0.1)
		(layer "F.Cu")
		(net 74)
	)
	(segment
		(start 139.575 84.775)
		(end 138.3 84.775)
		(width 0.1)
		(layer "F.Cu")
		(net 74)
	)
	(segment
		(start 141.2 89.2)
		(end 140.9 89.2)
		(width 0.1)
		(layer "F.Cu")
		(net 74)
	)
	(segment
		(start 142.355 91.314999)
		(end 142.355 90.025)
		(width 0.1)
		(layer "F.Cu")
		(net 74)
	)
	(segment
		(start 140.9 89.2)
		(end 140.3 88.6)
		(width 0.1)
		(layer "F.Cu")
		(net 74)
	)
	(segment
		(start 134.48 84.2)
		(end 135.7 84.2)
		(width 0.1)
		(layer "F.Cu")
		(net 74)
	)
	(segment
		(start 155.26 69.555)
		(end 154.31 69.555)
		(width 0.15)
		(layer "F.Cu")
		(net 75)
	)
	(segment
		(start 155.26 69.975)
		(end 155.26 69.555)
		(width 0.15)
		(layer "F.Cu")
		(net 75)
	)
	(segment
		(start 156.875 70.625)
		(end 155.91 70.625)
		(width 0.15)
		(layer "F.Cu")
		(net 75)
	)
	(segment
		(start 157.5 71.25)
		(end 156.875 70.625)
		(width 0.15)
		(layer "F.Cu")
		(net 75)
	)
	(segment
		(start 155.91 70.625)
		(end 155.26 69.975)
		(width 0.15)
		(layer "F.Cu")
		(net 75)
	)
	(via
		(at 152.295 71.25)
		(size 0.45)
		(drill 0.2)
		(layers "F.Cu" "B.Cu")
		(remove_unused_layers yes)
		(keep_end_layers yes)
		(zone_layer_connections)
		(net 76)
	)
	(segment
		(start 152.1 70.505)
		(end 152.1 71.05)
		(width 0.1)
		(layer "B.Cu")
		(net 76)
	)
	(segment
		(start 152.1 71.05)
		(end 152.3 71.25)
		(width 0.1)
		(layer "B.Cu")
		(net 76)
	)
	(via
		(at 151.43 72.75)
		(size 0.45)
		(drill 0.2)
		(layers "F.Cu" "B.Cu")
		(remove_unused_layers yes)
		(keep_end_layers yes)
		(zone_layer_connections)
		(net 77)
	)
	(segment
		(start 149.254 72.479)
		(end 149.525 72.75)
		(width 0.1)
		(layer "B.Cu")
		(net 77)
	)
	(segment
		(start 149.3 70.705)
		(end 149.3 71.517189)
		(width 0.1)
		(layer "B.Cu")
		(net 77)
	)
	(segment
		(start 149.525 72.75)
		(end 151.435 72.75)
		(width 0.1)
		(layer "B.Cu")
		(net 77)
	)
	(segment
		(start 149.254 71.563189)
		(end 149.254 72.479)
		(width 0.1)
		(layer "B.Cu")
		(net 77)
	)
	(segment
		(start 149.1 70.505)
		(end 149.3 70.705)
		(width 0.1)
		(layer "B.Cu")
		(net 77)
	)
	(segment
		(start 149.3 71.517189)
		(end 149.254 71.563189)
		(width 0.1)
		(layer "B.Cu")
		(net 77)
	)
	(via
		(at 151.43 71.75)
		(size 0.45)
		(drill 0.2)
		(layers "F.Cu" "B.Cu")
		(remove_unused_layers yes)
		(keep_end_layers yes)
		(zone_layer_connections)
		(net 78)
	)
	(segment
		(start 150.1 70.505)
		(end 150.1 71.507189)
		(width 0.1)
		(layer "B.Cu")
		(net 78)
	)
	(segment
		(start 150.342811 71.75)
		(end 151.435 71.75)
		(width 0.1)
		(layer "B.Cu")
		(net 78)
	)
	(segment
		(start 150.1 71.507189)
		(end 150.342811 71.75)
		(width 0.1)
		(layer "B.Cu")
		(net 78)
	)
	(segment
		(start 133.25 133.461405)
		(end 133.188595 133.4)
		(width 0.1)
		(layer "F.Cu")
		(net 79)
	)
	(segment
		(start 133.038595 131.899101)
		(end 133.188595 132.049101)
		(width 0.19)
		(layer "F.Cu")
		(net 79)
	)
	(segment
		(start 133.5 134.5)
		(end 133.375 134.375)
		(width 0.1)
		(layer "F.Cu")
		(net 79)
	)
	(segment
		(start 133.188595 132.049101)
		(end 133.188595 133.4)
		(width 0.19)
		(layer "F.Cu")
		(net 79)
	)
	(segment
		(start 133.25 134.073223)
		(end 133.25 133.461405)
		(width 0.1)
		(layer "F.Cu")
		(net 79)
	)
	(via
		(at 133.038595 131.899101)
		(size 0.45)
		(drill 0.2)
		(layers "F.Cu" "B.Cu")
		(remove_unused_layers yes)
		(keep_end_layers yes)
		(zone_layer_connections)
		(net 79)
	)
	(via
		(at 134.989999 116.825)
		(size 0.45)
		(drill 0.2)
		(layers "F.Cu" "B.Cu")
		(remove_unused_layers yes)
		(keep_end_layers yes)
		(zone_layer_connections)
		(net 79)
	)
	(arc
		(start 133.375 134.375)
		(mid 133.282487 134.236543)
		(end 133.25 134.073223)
		(width 0.1)
		(layer "F.Cu")
		(net 79)
	)
	(segment
		(start 132.875002 131.579998)
		(end 132.875002 131.735508)
		(width 0.25)
		(layer "B.Cu")
		(net 79)
	)
	(segment
		(start 132.875002 131.735508)
		(end 133.038595 131.899101)
		(width 0.25)
		(layer "B.Cu")
		(net 79)
	)
	(segment
		(start 134.219999 117)
		(end 134.244999 117)
		(width 0.15)
		(layer "B.Cu")
		(net 79)
	)
	(segment
		(start 134.244999 117)
		(end 134.569999 116.675)
		(width 0.15)
		(layer "B.Cu")
		(net 79)
	)
	(segment
		(start 134.569999 116.675)
		(end 134.839999 116.675)
		(width 0.15)
		(layer "B.Cu")
		(net 79)
	)
	(segment
		(start 134.839999 116.675)
		(end 134.989999 116.825)
		(width 0.15)
		(layer "B.Cu")
		(net 79)
	)
	(segment
		(start 137.075 117.622488)
		(end 137.075 119.822488)
		(width 0.15)
		(layer "In5.Cu")
		(net 79)
	)
	(segment
		(start 137.075 119.822488)
		(end 137.925 120.672488)
		(width 0.15)
		(layer "In5.Cu")
		(net 79)
	)
	(segment
		(start 135.8 116.675)
		(end 136 116.875)
		(width 0.15)
		(layer "In5.Cu")
		(net 79)
	)
	(segment
		(start 136.327512 116.875)
		(end 137.075 117.622488)
		(width 0.15)
		(layer "In5.Cu")
		(net 79)
	)
	(segment
		(start 133.183595 130.811845)
		(end 133.183595 131.754101)
		(width 0.15)
		(layer "In5.Cu")
		(net 79)
	)
	(segment
		(start 133.183595 131.754101)
		(end 133.038595 131.899101)
		(width 0.15)
		(layer "In5.Cu")
		(net 79)
	)
	(segment
		(start 137.925 128.427512)
		(end 136.827512 129.525)
		(width 0.15)
		(layer "In5.Cu")
		(net 79)
	)
	(segment
		(start 137.925 120.672488)
		(end 137.925 128.427512)
		(width 0.15)
		(layer "In5.Cu")
		(net 79)
	)
	(segment
		(start 134.47044 129.525)
		(end 133.183595 130.811845)
		(width 0.15)
		(layer "In5.Cu")
		(net 79)
	)
	(segment
		(start 135.139999 116.675)
		(end 135.8 116.675)
		(width 0.15)
		(layer "In5.Cu")
		(net 79)
	)
	(segment
		(start 134.989999 116.825)
		(end 135.139999 116.675)
		(width 0.15)
		(layer "In5.Cu")
		(net 79)
	)
	(segment
		(start 136.827512 129.525)
		(end 134.47044 129.525)
		(width 0.15)
		(layer "In5.Cu")
		(net 79)
	)
	(segment
		(start 136 116.875)
		(end 136.327512 116.875)
		(width 0.15)
		(layer "In5.Cu")
		(net 79)
	)
	(segment
		(start 134.450001 94.874998)
		(end 134.450001 93.779999)
		(width 0.25)
		(layer "F.Cu")
		(net 80)
	)
	(segment
		(start 134.450001 93.779999)
		(end 134.48 93.75)
		(width 0.25)
		(layer "F.Cu")
		(net 80)
	)
	(via
		(at 134.3 93.7)
		(size 0.45)
		(drill 0.2)
		(layers "F.Cu" "B.Cu")
		(remove_unused_layers yes)
		(keep_end_layers yes)
		(zone_layer_connections)
		(net 80)
	)
	(segment
		(start 134.48 92.92)
		(end 135 92.92)
		(width 0.1)
		(layer "B.Cu")
		(net 80)
	)
	(segment
		(start 134.3 93.7)
		(end 134.3 93.1)
		(width 0.1)
		(layer "B.Cu")
		(net 80)
	)
	(segment
		(start 134.3 93.1)
		(end 134.48 92.92)
		(width 0.1)
		(layer "B.Cu")
		(net 80)
	)
	(segment
		(start 149 92)
		(end 149 91.8)
		(width 0.1)
		(layer "F.Cu")
		(net 81)
	)
	(segment
		(start 149.71 91.09)
		(end 149.71 90.749999)
		(width 0.1)
		(layer "F.Cu")
		(net 81)
	)
	(segment
		(start 145.325001 95.674999)
		(end 149 92)
		(width 0.1)
		(layer "F.Cu")
		(net 81)
	)
	(segment
		(start 142.79 95.674999)
		(end 145.325001 95.674999)
		(width 0.1)
		(layer "F.Cu")
		(net 81)
	)
	(segment
		(start 149 91.8)
		(end 149.71 91.09)
		(width 0.1)
		(layer "F.Cu")
		(net 81)
	)
	(segment
		(start 151.845 74.25)
		(end 152.295 74.25)
		(width 0.3)
		(layer "F.Cu")
		(net 82)
	)
	(via
		(at 151.845 74.25)
		(size 0.45)
		(drill 0.2)
		(layers "F.Cu" "B.Cu")
		(remove_unused_layers yes)
		(keep_end_layers yes)
		(zone_layer_connections)
		(net 82)
	)
	(segment
		(start 144.3 74.3)
		(end 143.8 74.8)
		(width 0.1)
		(layer "B.Cu")
		(net 82)
	)
	(segment
		(start 145.6 73.8)
		(end 145.2 73.8)
		(width 0.1)
		(layer "B.Cu")
		(net 82)
	)
	(segment
		(start 144.7 74.3)
		(end 144.3 74.3)
		(width 0.1)
		(layer "B.Cu")
		(net 82)
	)
	(segment
		(start 143.6 94)
		(end 148.2 94)
		(width 0.1)
		(layer "B.Cu")
		(net 82)
	)
	(segment
		(start 145.2 73.8)
		(end 144.7 74.3)
		(width 0.1)
		(layer "B.Cu")
		(net 82)
	)
	(segment
		(start 143 75.2)
		(end 142.6 75.2)
		(width 0.1)
		(layer "B.Cu")
		(net 82)
	)
	(segment
		(start 142.35 75.45)
		(end 142.35 92.75)
		(width 0.1)
		(layer "B.Cu")
		(net 82)
	)
	(segment
		(start 151.845 74.25)
		(end 146.05 74.25)
		(width 0.1)
		(layer "B.Cu")
		(net 82)
	)
	(segment
		(start 142.6 75.2)
		(end 142.35 75.45)
		(width 0.1)
		(layer "B.Cu")
		(net 82)
	)
	(segment
		(start 143.4 74.8)
		(end 143 75.2)
		(width 0.1)
		(layer "B.Cu")
		(net 82)
	)
	(segment
		(start 146.05 74.25)
		(end 145.6 73.8)
		(width 0.1)
		(layer "B.Cu")
		(net 82)
	)
	(segment
		(start 148.2 94)
		(end 148.681866 93.518134)
		(width 0.1)
		(layer "B.Cu")
		(net 82)
	)
	(segment
		(start 143.8 74.8)
		(end 143.4 74.8)
		(width 0.1)
		(layer "B.Cu")
		(net 82)
	)
	(segment
		(start 142.35 92.75)
		(end 143.6 94)
		(width 0.1)
		(layer "B.Cu")
		(net 82)
	)
	(segment
		(start 148.681866 93.518134)
		(end 148.681866 92.965117)
		(width 0.1)
		(layer "B.Cu")
		(net 82)
	)
	(segment
		(start 136.629999 109.149998)
		(end 136.63 109.109998)
		(width 0.15)
		(layer "F.Cu")
		(net 83)
	)
	(segment
		(start 136.629999 109.149998)
		(end 137.129999 109.649997)
		(width 0.15)
		(layer "F.Cu")
		(net 83)
	)
	(segment
		(start 137.129999 109.649997)
		(end 138.125 109.649997)
		(width 0.15)
		(layer "F.Cu")
		(net 83)
	)
	(segment
		(start 136.63 109.109998)
		(end 135.67 108.149998)
		(width 0.15)
		(layer "F.Cu")
		(net 83)
	)
	(via
		(at 152.295 87.25)
		(size 0.45)
		(drill 0.2)
		(layers "F.Cu" "B.Cu")
		(remove_unused_layers yes)
		(keep_end_layers yes)
		(zone_layer_connections)
		(net 84)
	)
	(segment
		(start 152.545 87.25)
		(end 152.65 87.145)
		(width 0.15)
		(layer "B.Cu")
		(net 84)
	)
	(segment
		(start 152.3 87.25)
		(end 152.545 87.25)
		(width 0.15)
		(layer "B.Cu")
		(net 84)
	)
	(via
		(at 153.16 90.75)
		(size 0.45)
		(drill 0.2)
		(layers "F.Cu" "B.Cu")
		(remove_unused_layers yes)
		(keep_end_layers yes)
		(zone_layer_connections)
		(net 85)
	)
	(segment
		(start 154.2 91.045)
		(end 153.46 91.045)
		(width 0.15)
		(layer "B.Cu")
		(net 85)
	)
	(segment
		(start 153.46 91.045)
		(end 153.165 90.75)
		(width 0.15)
		(layer "B.Cu")
		(net 85)
	)
	(segment
		(start 116.52 60.08)
		(end 118 58.6)
		(width 0.1)
		(layer "F.Cu")
		(net 86)
	)
	(segment
		(start 116.52 65.5)
		(end 116.52 60.08)
		(width 0.1)
		(layer "F.Cu")
		(net 86)
	)
	(segment
		(start 118 58.6)
		(end 117.962 58.562)
		(width 0.1)
		(layer "F.Cu")
		(net 86)
	)
	(segment
		(start 117.962 58.562)
		(end 117.962 55.028)
		(width 0.1)
		(layer "F.Cu")
		(net 86)
	)
	(segment
		(start 116.52 67.5)
		(end 116.52 65.5)
		(width 0.1)
		(layer "F.Cu")
		(net 86)
	)
	(segment
		(start 154.025 76.25)
		(end 154.145 76.25)
		(width 0.15)
		(layer "F.Cu")
		(net 87)
	)
	(via
		(at 154.145 76.25)
		(size 0.45)
		(drill 0.2)
		(layers "F.Cu" "B.Cu")
		(remove_unused_layers yes)
		(keep_end_layers yes)
		(zone_layer_connections)
		(net 87)
	)
	(segment
		(start 154.43 76.25)
		(end 154.45 76.27)
		(width 0.15)
		(layer "B.Cu")
		(net 87)
	)
	(segment
		(start 154.15 76.25)
		(end 154.43 76.25)
		(width 0.15)
		(layer "B.Cu")
		(net 87)
	)
	(via
		(at 158.35 79.75)
		(size 0.45)
		(drill 0.2)
		(layers "F.Cu" "B.Cu")
		(remove_unused_layers yes)
		(keep_end_layers yes)
		(zone_layer_connections)
		(net 88)
	)
	(segment
		(start 158 80.7)
		(end 158.35 80.35)
		(width 0.1)
		(layer "B.Cu")
		(net 88)
	)
	(segment
		(start 157.3 80.7)
		(end 158 80.7)
		(width 0.1)
		(layer "B.Cu")
		(net 88)
	)
	(segment
		(start 154.6 82.3)
		(end 154.9 82.3)
		(width 0.1)
		(layer "B.Cu")
		(net 88)
	)
	(segment
		(start 156.7 81.3)
		(end 157.3 80.7)
		(width 0.1)
		(layer "B.Cu")
		(net 88)
	)
	(segment
		(start 153.511867 83.185117)
		(end 153.714883 83.185117)
		(width 0.1)
		(layer "B.Cu")
		(net 88)
	)
	(segment
		(start 156.3 81.3)
		(end 156.7 81.3)
		(width 0.1)
		(layer "B.Cu")
		(net 88)
	)
	(segment
		(start 155.5 81.7)
		(end 155.9 81.7)
		(width 0.1)
		(layer "B.Cu")
		(net 88)
	)
	(segment
		(start 154.9 82.3)
		(end 155.5 81.7)
		(width 0.1)
		(layer "B.Cu")
		(net 88)
	)
	(segment
		(start 153.714883 83.185117)
		(end 154.6 82.3)
		(width 0.1)
		(layer "B.Cu")
		(net 88)
	)
	(segment
		(start 158.35 80.35)
		(end 158.35 79.75)
		(width 0.1)
		(layer "B.Cu")
		(net 88)
	)
	(segment
		(start 155.9 81.7)
		(end 156.3 81.3)
		(width 0.1)
		(layer "B.Cu")
		(net 88)
	)
	(segment
		(start 118.77 65.5)
		(end 118.1 65.5)
		(width 0.1)
		(layer "F.Cu")
		(net 89)
	)
	(segment
		(start 117.48 65.5)
		(end 118.1 65.5)
		(width 0.1)
		(layer "F.Cu")
		(net 89)
	)
	(via
		(at 127.4 76)
		(size 0.45)
		(drill 0.2)
		(layers "F.Cu" "B.Cu")
		(remove_unused_layers yes)
		(keep_end_layers yes)
		(zone_layer_connections)
		(net 89)
	)
	(via
		(at 144.51 80.75)
		(size 0.45)
		(drill 0.2)
		(layers "F.Cu" "B.Cu")
		(remove_unused_layers yes)
		(keep_end_layers yes)
		(zone_layer_connections)
		(net 89)
	)
	(via
		(at 118.1 65.5)
		(size 0.45)
		(drill 0.2)
		(layers "F.Cu" "B.Cu")
		(remove_unused_layers yes)
		(keep_end_layers yes)
		(zone_layer_connections)
		(net 89)
	)
	(segment
		(start 144.51 80.75)
		(end 144.51 80.51)
		(width 0.1)
		(layer "In3.Cu")
		(net 89)
	)
	(segment
		(start 134.8 76.4)
		(end 134.8 75.2)
		(width 0.1)
		(layer "In3.Cu")
		(net 89)
	)
	(segment
		(start 138.8 76.8)
		(end 135.2 76.8)
		(width 0.1)
		(layer "In3.Cu")
		(net 89)
	)
	(segment
		(start 130.8 74.6)
		(end 129.4 76)
		(width 0.1)
		(layer "In3.Cu")
		(net 89)
	)
	(segment
		(start 144.51 80.51)
		(end 143.8 79.8)
		(width 0.1)
		(layer "In3.Cu")
		(net 89)
	)
	(segment
		(start 143.6 79.8)
		(end 143 79.2)
		(width 0.1)
		(layer "In3.Cu")
		(net 89)
	)
	(segment
		(start 134.8 75.2)
		(end 134.2 74.6)
		(width 0.1)
		(layer "In3.Cu")
		(net 89)
	)
	(segment
		(start 129.4 76)
		(end 127.4 76)
		(width 0.1)
		(layer "In3.Cu")
		(net 89)
	)
	(segment
		(start 134.2 74.6)
		(end 130.8 74.6)
		(width 0.1)
		(layer "In3.Cu")
		(net 89)
	)
	(segment
		(start 141.2 79.2)
		(end 138.8 76.8)
		(width 0.1)
		(layer "In3.Cu")
		(net 89)
	)
	(segment
		(start 135.2 76.8)
		(end 134.8 76.4)
		(width 0.1)
		(layer "In3.Cu")
		(net 89)
	)
	(segment
		(start 143.8 79.8)
		(end 143.6 79.8)
		(width 0.1)
		(layer "In3.Cu")
		(net 89)
	)
	(segment
		(start 143 79.2)
		(end 141.2 79.2)
		(width 0.1)
		(layer "In3.Cu")
		(net 89)
	)
	(segment
		(start 128.6 70)
		(end 128.6 75.8)
		(width 0.1)
		(layer "In5.Cu")
		(net 89)
	)
	(segment
		(start 124.1 65.5)
		(end 128.6 70)
		(width 0.1)
		(layer "In5.Cu")
		(net 89)
	)
	(segment
		(start 118.1 65.5)
		(end 124.1 65.5)
		(width 0.1)
		(layer "In5.Cu")
		(net 89)
	)
	(segment
		(start 128.4 76)
		(end 127.4 76)
		(width 0.1)
		(layer "In5.Cu")
		(net 89)
	)
	(segment
		(start 128.6 75.8)
		(end 128.4 76)
		(width 0.1)
		(layer "In5.Cu")
		(net 89)
	)
	(segment
		(start 117.48 66.495)
		(end 118.095 66.495)
		(width 0.1)
		(layer "F.Cu")
		(net 90)
	)
	(segment
		(start 118.095 66.495)
		(end 118.1 66.5)
		(width 0.1)
		(layer "F.Cu")
		(net 90)
	)
	(segment
		(start 118.1 66.5)
		(end 118.77 66.5)
		(width 0.1)
		(layer "F.Cu")
		(net 90)
	)
	(via
		(at 127.6 75)
		(size 0.45)
		(drill 0.2)
		(layers "F.Cu" "B.Cu")
		(remove_unused_layers yes)
		(keep_end_layers yes)
		(zone_layer_connections)
		(net 90)
	)
	(via
		(at 118.1 66.5)
		(size 0.45)
		(drill 0.2)
		(layers "F.Cu" "B.Cu")
		(remove_unused_layers yes)
		(keep_end_layers yes)
		(zone_layer_connections)
		(net 90)
	)
	(via
		(at 145.375 74.25)
		(size 0.45)
		(drill 0.2)
		(layers "F.Cu" "B.Cu")
		(remove_unused_layers yes)
		(keep_end_layers yes)
		(zone_layer_connections)
		(net 90)
	)
	(segment
		(start 140.15 72.8)
		(end 139.15 73.8)
		(width 0.1)
		(layer "In3.Cu")
		(net 90)
	)
	(segment
		(start 144.25 74.25)
		(end 143.8 73.8)
		(width 0.1)
		(layer "In3.Cu")
		(net 90)
	)
	(segment
		(start 128.2 75)
		(end 127.6 75)
		(width 0.1)
		(layer "In3.Cu")
		(net 90)
	)
	(segment
		(start 143.8 73.8)
		(end 142.2 73.8)
		(width 0.1)
		(layer "In3.Cu")
		(net 90)
	)
	(segment
		(start 142.2 73.8)
		(end 141.2 72.8)
		(width 0.1)
		(layer "In3.Cu")
		(net 90)
	)
	(segment
		(start 129.4 73.8)
		(end 128.2 75)
		(width 0.1)
		(layer "In3.Cu")
		(net 90)
	)
	(segment
		(start 139.15 73.8)
		(end 129.4 73.8)
		(width 0.1)
		(layer "In3.Cu")
		(net 90)
	)
	(segment
		(start 145.375 74.25)
		(end 144.25 74.25)
		(width 0.1)
		(layer "In3.Cu")
		(net 90)
	)
	(segment
		(start 141.2 72.8)
		(end 140.15 72.8)
		(width 0.1)
		(layer "In3.Cu")
		(net 90)
	)
	(segment
		(start 127.6 70)
		(end 124.1 66.5)
		(width 0.1)
		(layer "In5.Cu")
		(net 90)
	)
	(segment
		(start 127.6 75)
		(end 127.6 70)
		(width 0.1)
		(layer "In5.Cu")
		(net 90)
	)
	(segment
		(start 124.1 66.5)
		(end 118.1 66.5)
		(width 0.1)
		(layer "In5.Cu")
		(net 90)
	)
	(segment
		(start 117.48 67.5)
		(end 118.1 67.5)
		(width 0.1)
		(layer "F.Cu")
		(net 91)
	)
	(segment
		(start 118.77 67.5)
		(end 118.1 67.5)
		(width 0.1)
		(layer "F.Cu")
		(net 91)
	)
	(via
		(at 144.51 78.75)
		(size 0.45)
		(drill 0.2)
		(layers "F.Cu" "B.Cu")
		(remove_unused_layers yes)
		(keep_end_layers yes)
		(zone_layer_connections)
		(net 91)
	)
	(via
		(at 118.1 67.5)
		(size 0.45)
		(drill 0.2)
		(layers "F.Cu" "B.Cu")
		(remove_unused_layers yes)
		(keep_end_layers yes)
		(zone_layer_connections)
		(net 91)
	)
	(via
		(at 128 75.6)
		(size 0.45)
		(drill 0.2)
		(layers "F.Cu" "B.Cu")
		(remove_unused_layers yes)
		(keep_end_layers yes)
		(zone_layer_connections)
		(net 91)
	)
	(segment
		(start 139.2 76.4)
		(end 135.4 76.4)
		(width 0.1)
		(layer "In3.Cu")
		(net 91)
	)
	(segment
		(start 135.4 76.4)
		(end 135.2 76.2)
		(width 0.1)
		(layer "In3.Cu")
		(net 91)
	)
	(segment
		(start 135.2 76.2)
		(end 135.2 75)
		(width 0.1)
		(layer "In3.Cu")
		(net 91)
	)
	(segment
		(start 142.8 78.2)
		(end 142.6 78.2)
		(width 0.1)
		(layer "In3.Cu")
		(net 91)
	)
	(segment
		(start 143.35 78.75)
		(end 142.8 78.2)
		(width 0.1)
		(layer "In3.Cu")
		(net 91)
	)
	(segment
		(start 141.6 78.8)
		(end 139.2 76.4)
		(width 0.1)
		(layer "In3.Cu")
		(net 91)
	)
	(segment
		(start 142 78.8)
		(end 141.6 78.8)
		(width 0.1)
		(layer "In3.Cu")
		(net 91)
	)
	(segment
		(start 135.2 75)
		(end 134.4 74.2)
		(width 0.1)
		(layer "In3.Cu")
		(net 91)
	)
	(segment
		(start 130.4 74.2)
		(end 129 75.6)
		(width 0.1)
		(layer "In3.Cu")
		(net 91)
	)
	(segment
		(start 129 75.6)
		(end 128 75.6)
		(width 0.1)
		(layer "In3.Cu")
		(net 91)
	)
	(segment
		(start 134.4 74.2)
		(end 130.4 74.2)
		(width 0.1)
		(layer "In3.Cu")
		(net 91)
	)
	(segment
		(start 142.6 78.2)
		(end 142 78.8)
		(width 0.1)
		(layer "In3.Cu")
		(net 91)
	)
	(segment
		(start 144.51 78.75)
		(end 143.35 78.75)
		(width 0.1)
		(layer "In3.Cu")
		(net 91)
	)
	(segment
		(start 125 73.8)
		(end 125 70.8)
		(width 0.1)
		(layer "In5.Cu")
		(net 91)
	)
	(segment
		(start 126.2 75)
		(end 125 73.8)
		(width 0.1)
		(layer "In5.Cu")
		(net 91)
	)
	(segment
		(start 127.4 75.6)
		(end 126.8 75)
		(width 0.1)
		(layer "In5.Cu")
		(net 91)
	)
	(segment
		(start 125 70.8)
		(end 121.7 67.5)
		(width 0.1)
		(layer "In5.Cu")
		(net 91)
	)
	(segment
		(start 121.7 67.5)
		(end 118.1 67.5)
		(width 0.1)
		(layer "In5.Cu")
		(net 91)
	)
	(segment
		(start 128 75.6)
		(end 127.4 75.6)
		(width 0.1)
		(layer "In5.Cu")
		(net 91)
	)
	(segment
		(start 126.8 75)
		(end 126.2 75)
		(width 0.1)
		(layer "In5.Cu")
		(net 91)
	)
	(via
		(at 144.51 82.75)
		(size 0.45)
		(drill 0.2)
		(layers "F.Cu" "B.Cu")
		(remove_unused_layers yes)
		(keep_end_layers yes)
		(zone_layer_connections)
		(net 92)
	)
	(segment
		(start 145.015 83.25)
		(end 144.515 82.75)
		(width 0.15)
		(layer "B.Cu")
		(net 92)
	)
	(segment
		(start 145.12 83.25)
		(end 145.015 83.25)
		(width 0.15)
		(layer "B.Cu")
		(net 92)
	)
	(via
		(at 144.51 81.75)
		(size 0.45)
		(drill 0.2)
		(layers "F.Cu" "B.Cu")
		(remove_unused_layers yes)
		(keep_end_layers yes)
		(zone_layer_connections)
		(net 93)
	)
	(segment
		(start 145.12 82.25)
		(end 145.015 82.25)
		(width 0.15)
		(layer "B.Cu")
		(net 93)
	)
	(segment
		(start 145.015 82.25)
		(end 144.515 81.75)
		(width 0.15)
		(layer "B.Cu")
		(net 93)
	)
	(via
		(at 145.375 73.25)
		(size 0.45)
		(drill 0.2)
		(layers "F.Cu" "B.Cu")
		(remove_unused_layers yes)
		(keep_end_layers yes)
		(zone_layer_connections)
		(net 94)
	)
	(segment
		(start 145.38 73.25)
		(end 145.48 73.25)
		(width 0.15)
		(layer "B.Cu")
		(net 94)
	)
	(via
		(at 150.565 75.25)
		(size 0.45)
		(drill 0.2)
		(layers "F.Cu" "B.Cu")
		(remove_unused_layers yes)
		(keep_end_layers yes)
		(zone_layer_connections)
		(net 95)
	)
	(segment
		(start 150.645 75.25)
		(end 150.67 75.275)
		(width 0.15)
		(layer "B.Cu")
		(net 95)
	)
	(segment
		(start 150.57 75.25)
		(end 150.645 75.25)
		(width 0.15)
		(layer "B.Cu")
		(net 95)
	)
	(via
		(at 145.375 71.25)
		(size 0.45)
		(drill 0.2)
		(layers "F.Cu" "B.Cu")
		(remove_unused_layers yes)
		(keep_end_layers yes)
		(zone_layer_connections)
		(net 96)
	)
	(segment
		(start 145.38 71.25)
		(end 145.48 71.25)
		(width 0.15)
		(layer "B.Cu")
		(net 96)
	)
	(segment
		(start 149.7 81.75)
		(end 149.7 81.98)
		(width 0.5)
		(layer "F.Cu")
		(net 97)
	)
	(segment
		(start 149.7 81.98)
		(end 149.72 82)
		(width 0.5)
		(layer "F.Cu")
		(net 97)
	)
	(via
		(at 149.72 82)
		(size 0.45)
		(drill 0.2)
		(layers "F.Cu" "B.Cu")
		(remove_unused_layers yes)
		(keep_end_layers yes)
		(zone_layer_connections)
		(net 97)
	)
	(segment
		(start 149.725 82.195)
		(end 149.78 82.25)
		(width 0.15)
		(layer "B.Cu")
		(net 97)
	)
	(segment
		(start 149.725 82)
		(end 149.725 82.195)
		(width 0.15)
		(layer "B.Cu")
		(net 97)
	)
	(via
		(at 144.51 79.75)
		(size 0.45)
		(drill 0.2)
		(layers "F.Cu" "B.Cu")
		(remove_unused_layers yes)
		(keep_end_layers yes)
		(zone_layer_connections)
		(net 98)
	)
	(segment
		(start 144 82.962189)
		(end 144.15 83.112189)
		(width 0.15)
		(layer "B.Cu")
		(net 98)
	)
	(segment
		(start 144 80.55)
		(end 144 80.925)
		(width 0.15)
		(layer "B.Cu")
		(net 98)
	)
	(segment
		(start 144.15 83.477189)
		(end 144 83.627189)
		(width 0.15)
		(layer "B.Cu")
		(net 98)
	)
	(segment
		(start 144 83.627189)
		(end 144 84)
		(width 0.15)
		(layer "B.Cu")
		(net 98)
	)
	(segment
		(start 144.15 83.112189)
		(end 144.15 83.477189)
		(width 0.15)
		(layer "B.Cu")
		(net 98)
	)
	(segment
		(start 144.15 82.112189)
		(end 144.15 82.387811)
		(width 0.15)
		(layer "B.Cu")
		(net 98)
	)
	(segment
		(start 144.15 82.387811)
		(end 144 82.537811)
		(width 0.15)
		(layer "B.Cu")
		(net 98)
	)
	(segment
		(start 144 80.925)
		(end 144.15 81.075)
		(width 0.15)
		(layer "B.Cu")
		(net 98)
	)
	(segment
		(start 144.15 81.075)
		(end 144.15 81.45)
		(width 0.15)
		(layer "B.Cu")
		(net 98)
	)
	(segment
		(start 144.515 79.75)
		(end 144.515 80.035)
		(width 0.15)
		(layer "B.Cu")
		(net 98)
	)
	(segment
		(start 144.25 84.25)
		(end 145.12 84.25)
		(width 0.15)
		(layer "B.Cu")
		(net 98)
	)
	(segment
		(start 144 84)
		(end 144.25 84.25)
		(width 0.15)
		(layer "B.Cu")
		(net 98)
	)
	(segment
		(start 144.15 81.45)
		(end 144 81.6)
		(width 0.15)
		(layer "B.Cu")
		(net 98)
	)
	(segment
		(start 144 81.962189)
		(end 144.15 82.112189)
		(width 0.15)
		(layer "B.Cu")
		(net 98)
	)
	(segment
		(start 144 82.537811)
		(end 144 82.962189)
		(width 0.15)
		(layer "B.Cu")
		(net 98)
	)
	(segment
		(start 144 81.6)
		(end 144 81.962189)
		(width 0.15)
		(layer "B.Cu")
		(net 98)
	)
	(segment
		(start 144.515 80.035)
		(end 144 80.55)
		(width 0.15)
		(layer "B.Cu")
		(net 98)
	)
	(via
		(at 149.7 74.75)
		(size 0.45)
		(drill 0.2)
		(layers "F.Cu" "B.Cu")
		(remove_unused_layers yes)
		(keep_end_layers yes)
		(zone_layer_connections)
		(net 99)
	)
	(segment
		(start 149.78 74.825)
		(end 149.705 74.75)
		(width 0.5)
		(layer "B.Cu")
		(net 99)
	)
	(segment
		(start 149.78 75.275)
		(end 149.78 74.825)
		(width 0.5)
		(layer "B.Cu")
		(net 99)
	)
	(segment
		(start 172.6 71.62)
		(end 173.6 71.62)
		(width 0.1)
		(layer "F.Cu")
		(net 100)
	)
	(segment
		(start 172.6 71.62)
		(end 172.6 70.6)
		(width 0.1)
		(layer "F.Cu")
		(net 100)
	)
	(via
		(at 172.6 70.6)
		(size 0.45)
		(drill 0.2)
		(layers "F.Cu" "B.Cu")
		(remove_unused_layers yes)
		(keep_end_layers yes)
		(zone_layer_connections)
		(net 100)
	)
	(via
		(at 150.565 72.25)
		(size 0.45)
		(drill 0.2)
		(layers "F.Cu" "B.Cu")
		(remove_unused_layers yes)
		(keep_end_layers yes)
		(zone_layer_connections)
		(net 100)
	)
	(segment
		(start 171.2 71)
		(end 172.2 71)
		(width 0.1)
		(layer "In3.Cu")
		(net 100)
	)
	(segment
		(start 151 70.4)
		(end 151.2 70.2)
		(width 0.1)
		(layer "In3.Cu")
		(net 100)
	)
	(segment
		(start 170.4 70.2)
		(end 171.2 71)
		(width 0.1)
		(layer "In3.Cu")
		(net 100)
	)
	(segment
		(start 151 71.815)
		(end 151 70.4)
		(width 0.1)
		(layer "In3.Cu")
		(net 100)
	)
	(segment
		(start 151.2 70.2)
		(end 170.4 70.2)
		(width 0.1)
		(layer "In3.Cu")
		(net 100)
	)
	(segment
		(start 172.2 71)
		(end 172.6 70.6)
		(width 0.1)
		(layer "In3.Cu")
		(net 100)
	)
	(segment
		(start 150.565 72.25)
		(end 151 71.815)
		(width 0.1)
		(layer "In3.Cu")
		(net 100)
	)
	(via
		(at 158.35 74.75)
		(size 0.45)
		(drill 0.2)
		(layers "F.Cu" "B.Cu")
		(remove_unused_layers yes)
		(keep_end_layers yes)
		(zone_layer_connections)
		(net 101)
	)
	(segment
		(start 161.67 76.975)
		(end 161.054866 76.975)
		(width 0.1)
		(layer "B.Cu")
		(net 101)
	)
	(segment
		(start 161.054866 76.975)
		(end 160.45 76.370134)
		(width 0.1)
		(layer "B.Cu")
		(net 101)
	)
	(segment
		(start 160.45 76.370134)
		(end 160.45 75.775)
		(width 0.1)
		(layer "B.Cu")
		(net 101)
	)
	(segment
		(start 160.45 75.775)
		(end 159.425 74.75)
		(width 0.1)
		(layer "B.Cu")
		(net 101)
	)
	(segment
		(start 159.425 74.75)
		(end 158.355 74.75)
		(width 0.1)
		(layer "B.Cu")
		(net 101)
	)
	(segment
		(start 170.6 71.62)
		(end 171.6 71.62)
		(width 0.1)
		(layer "F.Cu")
		(net 102)
	)
	(segment
		(start 171.6 71.62)
		(end 171.6 70.6)
		(width 0.1)
		(layer "F.Cu")
		(net 102)
	)
	(via
		(at 150.565 71.25)
		(size 0.45)
		(drill 0.2)
		(layers "F.Cu" "B.Cu")
		(remove_unused_layers yes)
		(keep_end_layers yes)
		(zone_layer_connections)
		(net 102)
	)
	(via
		(at 171.6 70.6)
		(size 0.45)
		(drill 0.2)
		(layers "F.Cu" "B.Cu")
		(remove_unused_layers yes)
		(keep_end_layers yes)
		(zone_layer_connections)
		(net 102)
	)
	(segment
		(start 150.565 71.25)
		(end 150.565 70.235)
		(width 0.1)
		(layer "In3.Cu")
		(net 102)
	)
	(segment
		(start 151 69.8)
		(end 170.8 69.8)
		(width 0.1)
		(layer "In3.Cu")
		(net 102)
	)
	(segment
		(start 150.565 70.235)
		(end 151 69.8)
		(width 0.1)
		(layer "In3.Cu")
		(net 102)
	)
	(segment
		(start 170.8 69.8)
		(end 171.6 70.6)
		(width 0.1)
		(layer "In3.Cu")
		(net 102)
	)
	(segment
		(start 157.976 70.641)
		(end 157.51 70.175)
		(width 0.15)
		(layer "F.Cu")
		(net 103)
	)
	(segment
		(start 157.976 71.447166)
		(end 157.976 70.641)
		(width 0.15)
		(layer "F.Cu")
		(net 103)
	)
	(segment
		(start 157.5 71.923166)
		(end 157.976 71.447166)
		(width 0.15)
		(layer "F.Cu")
		(net 103)
	)
	(segment
		(start 156.21 69.975)
		(end 156.21 69.555)
		(width 0.15)
		(layer "F.Cu")
		(net 103)
	)
	(segment
		(start 157.5 72.25)
		(end 157.5 71.923166)
		(width 0.15)
		(layer "F.Cu")
		(net 103)
	)
	(segment
		(start 156.41 70.175)
		(end 156.21 69.975)
		(width 0.15)
		(layer "F.Cu")
		(net 103)
	)
	(segment
		(start 157.51 70.175)
		(end 156.41 70.175)
		(width 0.15)
		(layer "F.Cu")
		(net 103)
	)
	(via
		(at 157.485 79.25)
		(size 0.45)
		(drill 0.2)
		(layers "F.Cu" "B.Cu")
		(remove_unused_layers yes)
		(keep_end_layers yes)
		(zone_layer_connections)
		(net 104)
	)
	(segment
		(start 157.49 79.25)
		(end 157.49 79.335)
		(width 0.15)
		(layer "B.Cu")
		(net 104)
	)
	(segment
		(start 157.49 79.335)
		(end 157.35 79.475)
		(width 0.15)
		(layer "B.Cu")
		(net 104)
	)
	(via
		(at 158.35 78.75)
		(size 0.45)
		(drill 0.2)
		(layers "F.Cu" "B.Cu")
		(remove_unused_layers yes)
		(keep_end_layers yes)
		(zone_layer_connections)
		(net 105)
	)
	(segment
		(start 158.355 78.75)
		(end 158.65 78.75)
		(width 0.15)
		(layer "B.Cu")
		(net 105)
	)
	(via
		(at 157.485 78.25)
		(size 0.45)
		(drill 0.2)
		(layers "F.Cu" "B.Cu")
		(remove_unused_layers yes)
		(keep_end_layers yes)
		(zone_layer_connections)
		(net 106)
	)
	(segment
		(start 157.49 77.175)
		(end 157.49 78.25)
		(width 0.15)
		(layer "B.Cu")
		(net 106)
	)
	(via
		(at 156.62 78.75)
		(size 0.45)
		(drill 0.2)
		(layers "F.Cu" "B.Cu")
		(remove_unused_layers yes)
		(keep_end_layers yes)
		(zone_layer_connections)
		(net 107)
	)
	(segment
		(start 155.85 78.75)
		(end 156.625 78.75)
		(width 0.15)
		(layer "B.Cu")
		(net 107)
	)
	(segment
		(start 152.030001 109.149998)
		(end 152.530001 109.649998)
		(width 0.15)
		(layer "F.Cu")
		(net 108)
	)
	(segment
		(start 152.030002 109.11)
		(end 151.070002 108.15)
		(width 0.15)
		(layer "F.Cu")
		(net 108)
	)
	(segment
		(start 152.030001 109.149998)
		(end 152.030002 109.11)
		(width 0.15)
		(layer "F.Cu")
		(net 108)
	)
	(segment
		(start 152.530001 109.649998)
		(end 153.525002 109.649998)
		(width 0.15)
		(layer "F.Cu")
		(net 108)
	)
	(segment
		(start 159.729997 109.149998)
		(end 159.729999 109.109998)
		(width 0.15)
		(layer "F.Cu")
		(net 109)
	)
	(segment
		(start 160.229998 109.649997)
		(end 161.224999 109.649997)
		(width 0.15)
		(layer "F.Cu")
		(net 109)
	)
	(segment
		(start 159.729999 109.109998)
		(end 158.769999 108.149998)
		(width 0.15)
		(layer "F.Cu")
		(net 109)
	)
	(segment
		(start 159.729997 109.149998)
		(end 160.229998 109.649997)
		(width 0.15)
		(layer "F.Cu")
		(net 109)
	)
	(segment
		(start 157.952256 75.007744)
		(end 157.865 74.920488)
		(width 0.1)
		(layer "F.Cu")
		(net 110)
	)
	(segment
		(start 162.965002 76.374998)
		(end 162.965 76.375)
		(width 0.1)
		(layer "F.Cu")
		(net 110)
	)
	(segment
		(start 158.541988 77.2135)
		(end 158.158012 77.2135)
		(width 0.1)
		(layer "F.Cu")
		(net 110)
	)
	(segment
		(start 163.52 76.4)
		(end 163.494998 76.374998)
		(width 0.1)
		(layer "F.Cu")
		(net 110)
	)
	(segment
		(start 158.158012 77.2135)
		(end 157.8865 76.941988)
		(width 0.1)
		(layer "F.Cu")
		(net 110)
	)
	(segment
		(start 157.8865 76.558012)
		(end 157.9485 76.496012)
		(width 0.1)
		(layer "F.Cu")
		(net 110)
	)
	(segment
		(start 158.980488 76.775)
		(end 158.541988 77.2135)
		(width 0.1)
		(layer "F.Cu")
		(net 110)
	)
	(segment
		(start 159.345488 76.775)
		(end 158.980488 76.775)
		(width 0.1)
		(layer "F.Cu")
		(net 110)
	)
	(segment
		(start 159.845488 76.275)
		(end 159.345488 76.775)
		(width 0.1)
		(layer "F.Cu")
		(net 110)
	)
	(segment
		(start 157.865 74.920488)
		(end 157.865 74.575)
		(width 0.1)
		(layer "F.Cu")
		(net 110)
	)
	(segment
		(start 163.494998 76.374998)
		(end 162.965002 76.374998)
		(width 0.1)
		(layer "F.Cu")
		(net 110)
	)
	(segment
		(start 157.865 74.575)
		(end 157.965 74.475)
		(width 0.1)
		(layer "F.Cu")
		(net 110)
	)
	(segment
		(start 157.8865 76.941988)
		(end 157.8865 76.558012)
		(width 0.1)
		(layer "F.Cu")
		(net 110)
	)
	(segment
		(start 162.355 75.765)
		(end 160.720488 75.765)
		(width 0.1)
		(layer "F.Cu")
		(net 110)
	)
	(segment
		(start 162.965 76.375)
		(end 162.355 75.765)
		(width 0.1)
		(layer "F.Cu")
		(net 110)
	)
	(segment
		(start 157.485 73.545)
		(end 157.485 73.25)
		(width 0.1)
		(layer "F.Cu")
		(net 110)
	)
	(segment
		(start 157.965 74.475)
		(end 157.965 74.025)
		(width 0.1)
		(layer "F.Cu")
		(net 110)
	)
	(segment
		(start 157.8865 75.996012)
		(end 157.8865 75.558012)
		(width 0.1)
		(layer "F.Cu")
		(net 110)
	)
	(segment
		(start 157.8865 75.558012)
		(end 157.952256 75.492256)
		(width 0.1)
		(layer "F.Cu")
		(net 110)
	)
	(segment
		(start 157.952256 75.492256)
		(end 157.952256 75.007744)
		(width 0.1)
		(layer "F.Cu")
		(net 110)
	)
	(segment
		(start 157.9485 76.058012)
		(end 157.8865 75.996012)
		(width 0.1)
		(layer "F.Cu")
		(net 110)
	)
	(segment
		(start 157.965 74.025)
		(end 157.485 73.545)
		(width 0.1)
		(layer "F.Cu")
		(net 110)
	)
	(segment
		(start 157.9485 76.496012)
		(end 157.9485 76.058012)
		(width 0.1)
		(layer "F.Cu")
		(net 110)
	)
	(segment
		(start 160.720488 75.765)
		(end 160.210488 76.275)
		(width 0.1)
		(layer "F.Cu")
		(net 110)
	)
	(segment
		(start 160.210488 76.275)
		(end 159.845488 76.275)
		(width 0.1)
		(layer "F.Cu")
		(net 110)
	)
	(via
		(at 151.43 90.75)
		(size 0.45)
		(drill 0.2)
		(layers "F.Cu" "B.Cu")
		(remove_unused_layers yes)
		(keep_end_layers yes)
		(zone_layer_connections)
		(net 111)
	)
	(via
		(at 161.865 76.225)
		(size 0.45)
		(drill 0.2)
		(layers "F.Cu" "B.Cu")
		(remove_unused_layers yes)
		(keep_end_layers yes)
		(zone_layer_connections)
		(net 111)
	)
	(segment
		(start 161.865 76.225)
		(end 161.865 74.521983)
		(width 0.1)
		(layer "B.Cu")
		(net 111)
	)
	(segment
		(start 161.865 74.521983)
		(end 161.901866 74.485117)
		(width 0.1)
		(layer "B.Cu")
		(net 111)
	)
	(segment
		(start 151.43 90.75)
		(end 152.45 90.75)
		(width 0.1)
		(layer "In3.Cu")
		(net 111)
	)
	(segment
		(start 161.865 90.935)
		(end 161.865 76.225)
		(width 0.1)
		(layer "In3.Cu")
		(net 111)
	)
	(segment
		(start 153.8 90.3)
		(end 155.7 92.2)
		(width 0.1)
		(layer "In3.Cu")
		(net 111)
	)
	(segment
		(start 155.7 92.2)
		(end 160.6 92.2)
		(width 0.1)
		(layer "In3.Cu")
		(net 111)
	)
	(segment
		(start 152.45 90.75)
		(end 152.9 90.3)
		(width 0.1)
		(layer "In3.Cu")
		(net 111)
	)
	(segment
		(start 152.9 90.3)
		(end 153.8 90.3)
		(width 0.1)
		(layer "In3.Cu")
		(net 111)
	)
	(segment
		(start 160.6 92.2)
		(end 161.865 90.935)
		(width 0.1)
		(layer "In3.Cu")
		(net 111)
	)
	(segment
		(start 160.977512 65.525)
		(end 160.027512 65.525)
		(width 0.19)
		(layer "F.Cu")
		(net 112)
	)
	(segment
		(start 160.73 64.75)
		(end 161.19 65.21)
		(width 0.19)
		(layer "F.Cu")
		(net 112)
	)
	(segment
		(start 159.105 66.62)
		(end 159.105 66.645)
		(width 0.19)
		(layer "F.Cu")
		(net 112)
	)
	(segment
		(start 160.73 64.3)
		(end 160.73 64.75)
		(width 0.19)
		(layer "F.Cu")
		(net 112)
	)
	(segment
		(start 161.19 65.21)
		(end 161.19 65.312512)
		(width 0.19)
		(layer "F.Cu")
		(net 112)
	)
	(segment
		(start 159.43 66.295)
		(end 159.105 66.62)
		(width 0.19)
		(layer "F.Cu")
		(net 112)
	)
	(segment
		(start 160.027512 65.525)
		(end 159.43 66.122512)
		(width 0.19)
		(layer "F.Cu")
		(net 112)
	)
	(segment
		(start 159.43 66.122512)
		(end 159.43 66.295)
		(width 0.19)
		(layer "F.Cu")
		(net 112)
	)
	(segment
		(start 161.19 65.312512)
		(end 160.977512 65.525)
		(width 0.19)
		(layer "F.Cu")
		(net 112)
	)
	(segment
		(start 163.27 60.13)
		(end 163.78 59.62)
		(width 0.1)
		(layer "F.Cu")
		(net 113)
	)
	(segment
		(start 163.27 61.7)
		(end 163.27 60.13)
		(width 0.1)
		(layer "F.Cu")
		(net 113)
	)
	(segment
		(start 163.78 59.62)
		(end 165.265 59.62)
		(width 0.1)
		(layer "F.Cu")
		(net 113)
	)
	(segment
		(start 161.54 65.457488)
		(end 161.122488 65.875)
		(width 0.19)
		(layer "F.Cu")
		(net 114)
	)
	(segment
		(start 159.78 66.295)
		(end 160.105 66.62)
		(width 0.19)
		(layer "F.Cu")
		(net 114)
	)
	(segment
		(start 162 64.3)
		(end 162 64.75)
		(width 0.19)
		(layer "F.Cu")
		(net 114)
	)
	(segment
		(start 159.78 66.267488)
		(end 159.78 66.295)
		(width 0.19)
		(layer "F.Cu")
		(net 114)
	)
	(segment
		(start 161.122488 65.875)
		(end 160.172488 65.875)
		(width 0.19)
		(layer "F.Cu")
		(net 114)
	)
	(segment
		(start 160.105 66.62)
		(end 160.105 66.645)
		(width 0.19)
		(layer "F.Cu")
		(net 114)
	)
	(segment
		(start 162 64.75)
		(end 161.54 65.21)
		(width 0.19)
		(layer "F.Cu")
		(net 114)
	)
	(segment
		(start 160.172488 65.875)
		(end 159.78 66.267488)
		(width 0.19)
		(layer "F.Cu")
		(net 114)
	)
	(segment
		(start 161.54 65.21)
		(end 161.54 65.457488)
		(width 0.19)
		(layer "F.Cu")
		(net 114)
	)
	(segment
		(start 158.355 93.574999)
		(end 158.355 91.754999)
		(width 0.1)
		(layer "F.Cu")
		(net 115)
	)
	(segment
		(start 158.355 91.754999)
		(end 158.36 91.749999)
		(width 0.1)
		(layer "F.Cu")
		(net 115)
	)
	(segment
		(start 144.329999 109.149999)
		(end 144.33 109.109998)
		(width 0.15)
		(layer "F.Cu")
		(net 116)
	)
	(segment
		(start 144.33 109.109998)
		(end 143.37 108.149999)
		(width 0.15)
		(layer "F.Cu")
		(net 116)
	)
	(segment
		(start 144.329999 109.149999)
		(end 144.829999 109.649998)
		(width 0.15)
		(layer "F.Cu")
		(net 116)
	)
	(segment
		(start 144.829999 109.649998)
		(end 145.825 109.649998)
		(width 0.15)
		(layer "F.Cu")
		(net 116)
	)
	(segment
		(start 136 96.274999)
		(end 136 97.7)
		(width 0.25)
		(layer "F.Cu")
		(net 117)
	)
	(segment
		(start 134.779997 97.8)
		(end 134.729999 97.849998)
		(width 0.25)
		(layer "F.Cu")
		(net 117)
	)
	(segment
		(start 136 97.7)
		(end 135.9 97.8)
		(width 0.25)
		(layer "F.Cu")
		(net 117)
	)
	(segment
		(start 135.9 97.8)
		(end 134.779997 97.8)
		(width 0.25)
		(layer "F.Cu")
		(net 117)
	)
	(segment
		(start 134.450001 96.724998)
		(end 134.450001 97.169996)
		(width 0.25)
		(layer "F.Cu")
		(net 118)
	)
	(segment
		(start 134.450001 97.169996)
		(end 133.769999 97.849998)
		(width 0.25)
		(layer "F.Cu")
		(net 118)
	)
	(segment
		(start 141.099999 110.329999)
		(end 140.419999 109.649997)
		(width 0.15)
		(layer "F.Cu")
		(net 119)
	)
	(segment
		(start 140.419999 109.649997)
		(end 139.975 109.649997)
		(width 0.15)
		(layer "F.Cu")
		(net 119)
	)
	(segment
		(start 157.495 91.249999)
		(end 157.495 93.435)
		(width 0.1)
		(layer "F.Cu")
		(net 120)
	)
	(segment
		(start 157.495 93.435)
		(end 157.355 93.575)
		(width 0.1)
		(layer "F.Cu")
		(net 120)
	)
	(via
		(at 155.755 73.25)
		(size 0.45)
		(drill 0.2)
		(layers "F.Cu" "B.Cu")
		(remove_unused_layers yes)
		(keep_end_layers yes)
		(zone_layer_connections)
		(net 121)
	)
	(via
		(at 162.9 73.7)
		(size 0.45)
		(drill 0.2)
		(layers "F.Cu" "B.Cu")
		(remove_unused_layers yes)
		(keep_end_layers yes)
		(zone_layer_connections)
		(net 121)
	)
	(segment
		(start 162.861866 73.738134)
		(end 162.9 73.7)
		(width 0.1)
		(layer "B.Cu")
		(net 121)
	)
	(segment
		(start 162.861866 74.485117)
		(end 162.861866 73.738134)
		(width 0.1)
		(layer "B.Cu")
		(net 121)
	)
	(segment
		(start 155.755 73.25)
		(end 158.55 73.25)
		(width 0.1)
		(layer "In3.Cu")
		(net 121)
	)
	(segment
		(start 158.55 73.25)
		(end 159 73.7)
		(width 0.1)
		(layer "In3.Cu")
		(net 121)
	)
	(segment
		(start 159 73.7)
		(end 162.9 73.7)
		(width 0.1)
		(layer "In3.Cu")
		(net 121)
	)
	(segment
		(start 170.9 75.8)
		(end 170.9 73.7)
		(width 0.1)
		(layer "F.Cu")
		(net 122)
	)
	(segment
		(start 170.9 73.7)
		(end 171.08 73.52)
		(width 0.1)
		(layer "F.Cu")
		(net 122)
	)
	(segment
		(start 169.852 76.038)
		(end 170.662 76.038)
		(width 0.1)
		(layer "F.Cu")
		(net 122)
	)
	(segment
		(start 171.08 73.52)
		(end 171.6 73.52)
		(width 0.1)
		(layer "F.Cu")
		(net 122)
	)
	(segment
		(start 170.662 76.038)
		(end 170.9 75.8)
		(width 0.1)
		(layer "F.Cu")
		(net 122)
	)
	(segment
		(start 171.6 72.58)
		(end 171.6 73.52)
		(width 0.1)
		(layer "F.Cu")
		(net 122)
	)
	(segment
		(start 153.055199 73.645199)
		(end 153.16 73.75)
		(width 0.15)
		(layer "F.Cu")
		(net 123)
	)
	(segment
		(start 152.992559 73.645199)
		(end 153.055199 73.645199)
		(width 0.15)
		(layer "F.Cu")
		(net 123)
	)
	(via
		(at 161 68.3)
		(size 0.45)
		(drill 0.2)
		(layers "F.Cu" "B.Cu")
		(remove_unused_layers yes)
		(keep_end_layers yes)
		(zone_layer_connections)
		(net 123)
	)
	(via
		(at 152.992559 73.645199)
		(size 0.45)
		(drill 0.2)
		(layers "F.Cu" "B.Cu")
		(remove_unused_layers yes)
		(keep_end_layers yes)
		(zone_layer_connections)
		(net 123)
	)
	(segment
		(start 161 69.02)
		(end 161 68.3)
		(width 0.1)
		(layer "B.Cu")
		(net 123)
	)
	(segment
		(start 153.54736 74.2)
		(end 152.992559 73.645199)
		(width 0.1)
		(layer "In5.Cu")
		(net 123)
	)
	(segment
		(start 161 69.1)
		(end 155.9 74.2)
		(width 0.1)
		(layer "In5.Cu")
		(net 123)
	)
	(segment
		(start 155.9 74.2)
		(end 153.54736 74.2)
		(width 0.1)
		(layer "In5.Cu")
		(net 123)
	)
	(segment
		(start 161 68.3)
		(end 161 69.1)
		(width 0.1)
		(layer "In5.Cu")
		(net 123)
	)
	(via
		(at 156.62 77.75)
		(size 0.45)
		(drill 0.2)
		(layers "F.Cu" "B.Cu")
		(remove_unused_layers yes)
		(keep_end_layers yes)
		(zone_layer_connections)
		(net 124)
	)
	(segment
		(start 161.981866 69.98)
		(end 160.245 69.98)
		(width 0.1)
		(layer "B.Cu")
		(net 124)
	)
	(segment
		(start 156.625 73.6)
		(end 156.625 77.75)
		(width 0.1)
		(layer "B.Cu")
		(net 124)
	)
	(segment
		(start 160.245 69.98)
		(end 156.625 73.6)
		(width 0.1)
		(layer "B.Cu")
		(net 124)
	)
	(segment
		(start 172.6 72.58)
		(end 172.6 73.52)
		(width 0.1)
		(layer "F.Cu")
		(net 125)
	)
	(segment
		(start 173.1 75.9)
		(end 173.1 75.6)
		(width 0.1)
		(layer "F.Cu")
		(net 125)
	)
	(segment
		(start 173.4 73.7)
		(end 173.22 73.52)
		(width 0.1)
		(layer "F.Cu")
		(net 125)
	)
	(segment
		(start 173.238 76.038)
		(end 173.1 75.9)
		(width 0.1)
		(layer "F.Cu")
		(net 125)
	)
	(segment
		(start 173.22 73.52)
		(end 172.6 73.52)
		(width 0.1)
		(layer "F.Cu")
		(net 125)
	)
	(segment
		(start 173.1 75.6)
		(end 173.4 75.3)
		(width 0.1)
		(layer "F.Cu")
		(net 125)
	)
	(segment
		(start 173.4 75.3)
		(end 173.4 73.7)
		(width 0.1)
		(layer "F.Cu")
		(net 125)
	)
	(segment
		(start 174.151 76.038)
		(end 173.238 76.038)
		(width 0.1)
		(layer "F.Cu")
		(net 125)
	)
	(via
		(at 147.105 72.25)
		(size 0.45)
		(drill 0.2)
		(layers "F.Cu" "B.Cu")
		(remove_unused_layers yes)
		(keep_end_layers yes)
		(zone_layer_connections)
		(net 126)
	)
	(segment
		(start 146.6 70.525)
		(end 147.02 70.525)
		(width 0.1)
		(layer "B.Cu")
		(net 126)
	)
	(segment
		(start 147.11 72.25)
		(end 146.625 72.25)
		(width 0.1)
		(layer "B.Cu")
		(net 126)
	)
	(segment
		(start 146.35 70.775)
		(end 146.6 70.525)
		(width 0.1)
		(layer "B.Cu")
		(net 126)
	)
	(segment
		(start 146.35 71.975)
		(end 146.35 70.775)
		(width 0.1)
		(layer "B.Cu")
		(net 126)
	)
	(segment
		(start 146.625 72.25)
		(end 146.35 71.975)
		(width 0.1)
		(layer "B.Cu")
		(net 126)
	)
	(segment
		(start 147.02 69.525)
		(end 147.02 70.525)
		(width 0.1)
		(layer "B.Cu")
		(net 126)
	)
	(segment
		(start 158.11 69.975)
		(end 158.11 69.555)
		(width 0.15)
		(layer "F.Cu")
		(net 127)
	)
	(segment
		(start 157.16 69.555)
		(end 158.11 69.555)
		(width 0.15)
		(layer "F.Cu")
		(net 127)
	)
	(segment
		(start 158.365 71.75)
		(end 158.365 70.23)
		(width 0.15)
		(layer "F.Cu")
		(net 127)
	)
	(segment
		(start 158.365 70.23)
		(end 158.11 69.975)
		(width 0.15)
		(layer "F.Cu")
		(net 127)
	)
	(via
		(at 146.24 90.75)
		(size 0.45)
		(drill 0.2)
		(layers "F.Cu" "B.Cu")
		(remove_unused_layers yes)
		(keep_end_layers yes)
		(zone_layer_connections)
		(net 128)
	)
	(via
		(at 154.6 145.4)
		(size 0.45)
		(drill 0.2)
		(layers "F.Cu" "B.Cu")
		(remove_unused_layers yes)
		(keep_end_layers yes)
		(zone_layer_connections)
		(net 128)
	)
	(via
		(at 154.4 102.1)
		(size 0.45)
		(drill 0.2)
		(layers "F.Cu" "B.Cu")
		(remove_unused_layers yes)
		(keep_end_layers yes)
		(zone_layer_connections)
		(net 128)
	)
	(segment
		(start 154.58 145.42)
		(end 154.6 145.4)
		(width 0.1)
		(layer "B.Cu")
		(net 128)
	)
	(segment
		(start 154.58 146.18)
		(end 154.58 145.42)
		(width 0.1)
		(layer "B.Cu")
		(net 128)
	)
	(segment
		(start 155.8 139)
		(end 160 139)
		(width 0.1)
		(layer "In3.Cu")
		(net 128)
	)
	(segment
		(start 160 139)
		(end 163.4 135.6)
		(width 0.1)
		(layer "In3.Cu")
		(net 128)
	)
	(segment
		(start 163.4 132.097056)
		(end 160.9 129.597056)
		(width 0.1)
		(layer "In3.Cu")
		(net 128)
	)
	(segment
		(start 154.6 140.2)
		(end 155.8 139)
		(width 0.1)
		(layer "In3.Cu")
		(net 128)
	)
	(segment
		(start 160.9 122.834314)
		(end 166.4 117.334314)
		(width 0.1)
		(layer "In3.Cu")
		(net 128)
	)
	(segment
		(start 166.4 117.334314)
		(end 166.4 102.765686)
		(width 0.1)
		(layer "In3.Cu")
		(net 128)
	)
	(segment
		(start 160.9 129.597056)
		(end 160.9 122.834314)
		(width 0.1)
		(layer "In3.Cu")
		(net 128)
	)
	(segment
		(start 165.734314 102.1)
		(end 154.4 102.1)
		(width 0.1)
		(layer "In3.Cu")
		(net 128)
	)
	(segment
		(start 166.4 102.765686)
		(end 165.734314 102.1)
		(width 0.1)
		(layer "In3.Cu")
		(net 128)
	)
	(segment
		(start 163.4 135.6)
		(end 163.4 132.097056)
		(width 0.1)
		(layer "In3.Cu")
		(net 128)
	)
	(segment
		(start 154.6 145.4)
		(end 154.6 140.2)
		(width 0.1)
		(layer "In3.Cu")
		(net 128)
	)
	(segment
		(start 146.24 90.75)
		(end 146.24 93.94)
		(width 0.1)
		(layer "In5.Cu")
		(net 128)
	)
	(segment
		(start 146.24 93.94)
		(end 154.4 102.1)
		(width 0.1)
		(layer "In5.Cu")
		(net 128)
	)
	(via
		(at 157.485 80.25)
		(size 0.45)
		(drill 0.2)
		(layers "F.Cu" "B.Cu")
		(remove_unused_layers yes)
		(keep_end_layers yes)
		(zone_layer_connections)
		(net 129)
	)
	(segment
		(start 155.526 79.799)
		(end 154.55 80.775)
		(width 0.15)
		(layer "B.Cu")
		(net 129)
	)
	(segment
		(start 153.782189 82.225)
		(end 153.48 82.225)
		(width 0.15)
		(layer "B.Cu")
		(net 129)
	)
	(segment
		(start 156.487189 80.25)
		(end 156.036189 79.799)
		(width 0.15)
		(layer "B.Cu")
		(net 129)
	)
	(segment
		(start 154.55 80.775)
		(end 154.55 81.457189)
		(width 0.15)
		(layer "B.Cu")
		(net 129)
	)
	(segment
		(start 156.036189 79.799)
		(end 155.526 79.799)
		(width 0.15)
		(layer "B.Cu")
		(net 129)
	)
	(segment
		(start 157.49 80.25)
		(end 156.487189 80.25)
		(width 0.15)
		(layer "B.Cu")
		(net 129)
	)
	(segment
		(start 154.55 81.457189)
		(end 153.782189 82.225)
		(width 0.15)
		(layer "B.Cu")
		(net 129)
	)
	(segment
		(start 163.52 80.4)
		(end 163.52 79.4)
		(width 0.1)
		(layer "F.Cu")
		(net 130)
	)
	(segment
		(start 163.519999 80.375)
		(end 163.52 80.375001)
		(width 0.1)
		(layer "F.Cu")
		(net 130)
	)
	(segment
		(start 159.864166 80.274)
		(end 160.295834 80.274)
		(width 0.1)
		(layer "F.Cu")
		(net 130)
	)
	(segment
		(start 156.404166 80.274)
		(end 156.835834 80.274)
		(width 0.1)
		(layer "F.Cu")
		(net 130)
	)
	(segment
		(start 161.645 80.375)
		(end 163.519999 80.375)
		(width 0.1)
		(layer "F.Cu")
		(net 130)
	)
	(segment
		(start 158.565834 80.274)
		(end 159.017834 80.726)
		(width 0.1)
		(layer "F.Cu")
		(net 130)
	)
	(segment
		(start 155.928166 80.75)
		(end 156.404166 80.274)
		(width 0.1)
		(layer "F.Cu")
		(net 130)
	)
	(segment
		(start 160.295834 80.274)
		(end 160.747834 80.726)
		(width 0.1)
		(layer "F.Cu")
		(net 130)
	)
	(segment
		(start 163.52 80.375001)
		(end 163.52 80.4)
		(width 0.1)
		(layer "F.Cu")
		(net 130)
	)
	(segment
		(start 157.287834 80.726)
		(end 157.700834 80.726)
		(width 0.1)
		(layer "F.Cu")
		(net 130)
	)
	(segment
		(start 154.89 80.75)
		(end 155.928166 80.75)
		(width 0.1)
		(layer "F.Cu")
		(net 130)
	)
	(segment
		(start 160.747834 80.726)
		(end 161.294 80.726)
		(width 0.1)
		(layer "F.Cu")
		(net 130)
	)
	(segment
		(start 161.294 80.726)
		(end 161.645 80.375)
		(width 0.1)
		(layer "F.Cu")
		(net 130)
	)
	(segment
		(start 158.152834 80.274)
		(end 158.565834 80.274)
		(width 0.1)
		(layer "F.Cu")
		(net 130)
	)
	(segment
		(start 156.835834 80.274)
		(end 157.287834 80.726)
		(width 0.1)
		(layer "F.Cu")
		(net 130)
	)
	(segment
		(start 159.412166 80.726)
		(end 159.864166 80.274)
		(width 0.1)
		(layer "F.Cu")
		(net 130)
	)
	(segment
		(start 157.700834 80.726)
		(end 158.152834 80.274)
		(width 0.1)
		(layer "F.Cu")
		(net 130)
	)
	(segment
		(start 159.017834 80.726)
		(end 159.412166 80.726)
		(width 0.1)
		(layer "F.Cu")
		(net 130)
	)
	(segment
		(start 158.134166 79.274)
		(end 157.682166 79.726)
		(width 0.1)
		(layer "F.Cu")
		(net 131)
	)
	(segment
		(start 160.247834 79.274)
		(end 159.882834 79.274)
		(width 0.1)
		(layer "F.Cu")
		(net 131)
	)
	(segment
		(start 161.346 78.774)
		(end 160.747834 78.774)
		(width 0.1)
		(layer "F.Cu")
		(net 131)
	)
	(segment
		(start 156.793166 79.25)
		(end 155.755 79.25)
		(width 0.1)
		(layer "F.Cu")
		(net 131)
	)
	(segment
		(start 161.745 78.375)
		(end 163.494999 78.374999)
		(width 0.1)
		(layer "F.Cu")
		(net 131)
	)
	(segment
		(start 163.52 78.4)
		(end 163.52 77.4)
		(width 0.1)
		(layer "F.Cu")
		(net 131)
	)
	(segment
		(start 159.882834 79.274)
		(end 159.431834 79.725)
		(width 0.1)
		(layer "F.Cu")
		(net 131)
	)
	(segment
		(start 159.431834 79.725)
		(end 158.998166 79.725)
		(width 0.1)
		(layer "F.Cu")
		(net 131)
	)
	(segment
		(start 158.998166 79.725)
		(end 158.547166 79.274)
		(width 0.1)
		(layer "F.Cu")
		(net 131)
	)
	(segment
		(start 163.52 78.4)
		(end 163.494999 78.374999)
		(width 0.1)
		(layer "F.Cu")
		(net 131)
	)
	(segment
		(start 158.547166 79.274)
		(end 158.134166 79.274)
		(width 0.1)
		(layer "F.Cu")
		(net 131)
	)
	(segment
		(start 157.682166 79.726)
		(end 157.269166 79.726)
		(width 0.1)
		(layer "F.Cu")
		(net 131)
	)
	(segment
		(start 157.269166 79.726)
		(end 156.793166 79.25)
		(width 0.1)
		(layer "F.Cu")
		(net 131)
	)
	(segment
		(start 160.747834 78.774)
		(end 160.247834 79.274)
		(width 0.1)
		(layer "F.Cu")
		(net 131)
	)
	(segment
		(start 161.745 78.375)
		(end 161.346 78.774)
		(width 0.1)
		(layer "F.Cu")
		(net 131)
	)
	(via
		(at 158.35 75.75)
		(size 0.45)
		(drill 0.2)
		(layers "F.Cu" "B.Cu")
		(remove_unused_layers yes)
		(keep_end_layers yes)
		(zone_layer_connections)
		(net 132)
	)
	(segment
		(start 144.48 133.25)
		(end 144.48 133.98)
		(width 0.25)
		(layer "B.Cu")
		(net 133)
	)
	(segment
		(start 159.57 133.25)
		(end 159.57 133.93)
		(width 0.25)
		(layer "B.Cu")
		(net 133)
	)
	(segment
		(start 158.385 135.865)
		(end 158.52 136)
		(width 0.25)
		(layer "B.Cu")
		(net 133)
	)
	(segment
		(start 158.4 139.25)
		(end 147.25 139.25)
		(width 0.25)
		(layer "B.Cu")
		(net 133)
	)
	(segment
		(start 158.17 133.325)
		(end 159.495 133.325)
		(width 0.25)
		(layer "B.Cu")
		(net 133)
	)
	(segment
		(start 144.48 133.25)
		(end 145.905 133.25)
		(width 0.25)
		(layer "B.Cu")
		(net 133)
	)
	(segment
		(start 158.52 139.13)
		(end 158.4 139.25)
		(width 0.25)
		(layer "B.Cu")
		(net 133)
	)
	(segment
		(start 158.52 134.98)
		(end 158.52 136)
		(width 0.25)
		(layer "B.Cu")
		(net 133)
	)
	(segment
		(start 158.52 136)
		(end 158.52 137.5)
		(width 0.25)
		(layer "B.Cu")
		(net 133)
	)
	(segment
		(start 157.15 135.865)
		(end 158.385 135.865)
		(width 0.25)
		(layer "B.Cu")
		(net 133)
	)
	(segment
		(start 145.48 134.98)
		(end 145.48 136)
		(width 0.25)
		(layer "B.Cu")
		(net 133)
	)
	(segment
		(start 145.48 137.48)
		(end 145.48 136)
		(width 0.25)
		(layer "B.Cu")
		(net 133)
	)
	(segment
		(start 147.25 139.25)
		(end 145.48 137.48)
		(width 0.25)
		(layer "B.Cu")
		(net 133)
	)
	(segment
		(start 144.48 133.98)
		(end 145.48 134.98)
		(width 0.25)
		(layer "B.Cu")
		(net 133)
	)
	(segment
		(start 158.52 137.5)
		(end 158.52 139.13)
		(width 0.25)
		(layer "B.Cu")
		(net 133)
	)
	(segment
		(start 146.865 136)
		(end 147 135.865)
		(width 0.25)
		(layer "B.Cu")
		(net 133)
	)
	(segment
		(start 159.495 133.325)
		(end 159.57 133.25)
		(width 0.25)
		(layer "B.Cu")
		(net 133)
	)
	(segment
		(start 159.57 133.93)
		(end 158.52 134.98)
		(width 0.25)
		(layer "B.Cu")
		(net 133)
	)
	(segment
		(start 145.48 136)
		(end 146.865 136)
		(width 0.25)
		(layer "B.Cu")
		(net 133)
	)
	(segment
		(start 145.905 133.25)
		(end 145.98 133.325)
		(width 0.25)
		(layer "B.Cu")
		(net 133)
	)
	(segment
		(start 166.58 133.25)
		(end 166.58 134.08)
		(width 0.25)
		(layer "B.Cu")
		(net 134)
	)
	(segment
		(start 166.58 134.08)
		(end 167.48 134.98)
		(width 0.25)
		(layer "B.Cu")
		(net 134)
	)
	(segment
		(start 181.57 133.25)
		(end 180.245 133.25)
		(width 0.25)
		(layer "B.Cu")
		(net 134)
	)
	(segment
		(start 180.245 133.25)
		(end 180.17 133.325)
		(width 0.25)
		(layer "B.Cu")
		(net 134)
	)
	(segment
		(start 180.77 136)
		(end 180.77 137.73)
		(width 0.25)
		(layer "B.Cu")
		(net 134)
	)
	(segment
		(start 166.58 133.25)
		(end 167.905 133.25)
		(width 0.25)
		(layer "B.Cu")
		(net 134)
	)
	(segment
		(start 180.77 135.23)
		(end 180.77 136)
		(width 0.25)
		(layer "B.Cu")
		(net 134)
	)
	(segment
		(start 181.57 134.43)
		(end 180.77 135.23)
		(width 0.25)
		(layer "B.Cu")
		(net 134)
	)
	(segment
		(start 167.48 136)
		(end 168.865 136)
		(width 0.25)
		(layer "B.Cu")
		(net 134)
	)
	(segment
		(start 167.48 136)
		(end 167.48 139.03)
		(width 0.25)
		(layer "B.Cu")
		(net 134)
	)
	(segment
		(start 168.865 136)
		(end 169 135.865)
		(width 0.25)
		(layer "B.Cu")
		(net 134)
	)
	(segment
		(start 167.905 133.25)
		(end 167.98 133.325)
		(width 0.25)
		(layer "B.Cu")
		(net 134)
	)
	(segment
		(start 167.48 139.03)
		(end 167.7 139.25)
		(width 0.25)
		(layer "B.Cu")
		(net 134)
	)
	(segment
		(start 180.77 136)
		(end 179.285 136)
		(width 0.25)
		(layer "B.Cu")
		(net 134)
	)
	(segment
		(start 179.25 139.25)
		(end 167.7 139.25)
		(width 0.25)
		(layer "B.Cu")
		(net 134)
	)
	(segment
		(start 179.285 136)
		(end 179.15 135.865)
		(width 0.25)
		(layer "B.Cu")
		(net 134)
	)
	(segment
		(start 181.57 133.25)
		(end 181.57 134.43)
		(width 0.25)
		(layer "B.Cu")
		(net 134)
	)
	(segment
		(start 167.48 134.98)
		(end 167.48 136)
		(width 0.25)
		(layer "B.Cu")
		(net 134)
	)
	(segment
		(start 180.77 137.73)
		(end 179.25 139.25)
		(width 0.25)
		(layer "B.Cu")
		(net 134)
	)
	(segment
		(start 163.73 133.25)
		(end 163.9 133.08)
		(width 0.75)
		(layer "B.Cu")
		(net 135)
	)
	(segment
		(start 162 134.75)
		(end 163.249 134.75)
		(width 0.5)
		(layer "B.Cu")
		(net 135)
	)
	(segment
		(start 163.73 134.269)
		(end 163.249 134.75)
		(width 0.75)
		(layer "B.Cu")
		(net 135)
	)
	(segment
		(start 163.73 133.25)
		(end 163.73 134.269)
		(width 0.75)
		(layer "B.Cu")
		(net 135)
	)
	(segment
		(start 159.48 137.5)
		(end 160.75 137.5)
		(width 0.5)
		(layer "B.Cu")
		(net 135)
	)
	(segment
		(start 161.25 137)
		(end 161.25 135.5)
		(width 0.5)
		(layer "B.Cu")
		(net 135)
	)
	(segment
		(start 161.25 135.5)
		(end 162 134.75)
		(width 0.5)
		(layer "B.Cu")
		(net 135)
	)
	(segment
		(start 166.52 137.5)
		(end 165.5 137.5)
		(width 0.5)
		(layer "B.Cu")
		(net 135)
	)
	(segment
		(start 164.75 135.1)
		(end 164.75 136.75)
		(width 0.5)
		(layer "B.Cu")
		(net 135)
	)
	(segment
		(start 163.5 134.75)
		(end 163.249 134.75)
		(width 0.25)
		(layer "B.Cu")
		(net 135)
	)
	(segment
		(start 165.5 137.5)
		(end 164.75 136.75)
		(width 0.5)
		(layer "B.Cu")
		(net 135)
	)
	(segment
		(start 163.249 134.75)
		(end 164.4 134.75)
		(width 0.5)
		(layer "B.Cu")
		(net 135)
	)
	(segment
		(start 160.75 137.5)
		(end 161.25 137)
		(width 0.5)
		(layer "B.Cu")
		(net 135)
	)
	(segment
		(start 164.4 134.75)
		(end 164.75 135.1)
		(width 0.5)
		(layer "B.Cu")
		(net 135)
	)
	(segment
		(start 163.9 132.05)
		(end 163.95 132)
		(width 0.75)
		(layer "B.Cu")
		(net 135)
	)
	(segment
		(start 163.9 133.08)
		(end 163.9 132.05)
		(width 0.75)
		(layer "B.Cu")
		(net 135)
	)
	(segment
		(start 163.95 134.3)
		(end 163.5 134.75)
		(width 0.25)
		(layer "B.Cu")
		(net 135)
	)
	(via
		(at 157.8 99.6)
		(size 0.45)
		(drill 0.2)
		(layers "F.Cu" "B.Cu")
		(remove_unused_layers yes)
		(keep_end_layers yes)
		(zone_layer_connections)
		(net 136)
	)
	(via
		(at 174.25 83.25)
		(size 0.45)
		(drill 0.2)
		(layers "F.Cu" "B.Cu")
		(remove_unused_layers yes)
		(keep_end_layers yes)
		(zone_layer_connections)
		(net 136)
	)
	(via
		(at 156.8 99.6)
		(size 0.45)
		(drill 0.2)
		(layers "F.Cu" "B.Cu")
		(remove_unused_layers yes)
		(keep_end_layers yes)
		(zone_layer_connections)
		(net 136)
	)
	(via
		(at 156.8 100.2)
		(size 0.45)
		(drill 0.2)
		(layers "F.Cu" "B.Cu")
		(remove_unused_layers yes)
		(keep_end_layers yes)
		(zone_layer_connections)
		(net 136)
	)
	(via
		(at 157.8 100.2)
		(size 0.45)
		(drill 0.2)
		(layers "F.Cu" "B.Cu")
		(remove_unused_layers yes)
		(keep_end_layers yes)
		(zone_layer_connections)
		(net 136)
	)
	(via
		(at 158.8 100.2)
		(size 0.45)
		(drill 0.2)
		(layers "F.Cu" "B.Cu")
		(remove_unused_layers yes)
		(keep_end_layers yes)
		(zone_layer_connections)
		(net 136)
	)
	(via
		(at 158.8 99.6)
		(size 0.45)
		(drill 0.2)
		(layers "F.Cu" "B.Cu")
		(remove_unused_layers yes)
		(keep_end_layers yes)
		(zone_layer_connections)
		(net 136)
	)
	(segment
		(start 183.75 83.25)
		(end 174.25 83.25)
		(width 0.1)
		(layer "B.Cu")
		(net 136)
	)
	(segment
		(start 174.25 83.25)
		(end 174.25 93.5)
		(width 0.1)
		(layer "In5.Cu")
		(net 136)
	)
	(segment
		(start 174.25 93.5)
		(end 168.15 99.6)
		(width 0.1)
		(layer "In5.Cu")
		(net 136)
	)
	(segment
		(start 168.15 99.6)
		(end 158.8 99.6)
		(width 0.1)
		(layer "In5.Cu")
		(net 136)
	)
	(via
		(at 155.26 66.645)
		(size 0.45)
		(drill 0.2)
		(layers "F.Cu" "B.Cu")
		(remove_unused_layers yes)
		(keep_end_layers yes)
		(zone_layer_connections)
		(net 137)
	)
	(segment
		(start 158.75 65.225)
		(end 159 64.975)
		(width 0.1)
		(layer "B.Cu")
		(net 137)
	)
	(segment
		(start 156.55 66.075)
		(end 156.675 65.95)
		(width 0.1)
		(layer "B.Cu")
		(net 137)
	)
	(segment
		(start 155.7 69.123251)
		(end 156.131866 69.555117)
		(width 0.1)
		(layer "B.Cu")
		(net 137)
	)
	(segment
		(start 155.26 66.645)
		(end 155.83 66.075)
		(width 0.1)
		(layer "B.Cu")
		(net 137)
	)
	(segment
		(start 155.26 66.645)
		(end 155.7 67.085)
		(width 0.1)
		(layer "B.Cu")
		(net 137)
	)
	(segment
		(start 155.7 67.085)
		(end 155.7 69.123251)
		(width 0.1)
		(layer "B.Cu")
		(net 137)
	)
	(segment
		(start 156.675 65.4)
		(end 156.85 65.225)
		(width 0.1)
		(layer "B.Cu")
		(net 137)
	)
	(segment
		(start 159 64.6)
		(end 159.164883 64.435117)
		(width 0.1)
		(layer "B.Cu")
		(net 137)
	)
	(segment
		(start 156.85 65.225)
		(end 158.75 65.225)
		(width 0.1)
		(layer "B.Cu")
		(net 137)
	)
	(segment
		(start 159.164883 64.435117)
		(end 159.731866 64.435117)
		(width 0.1)
		(layer "B.Cu")
		(net 137)
	)
	(segment
		(start 159 64.975)
		(end 159 64.6)
		(width 0.1)
		(layer "B.Cu")
		(net 137)
	)
	(segment
		(start 156.675 65.95)
		(end 156.675 65.4)
		(width 0.1)
		(layer "B.Cu")
		(net 137)
	)
	(segment
		(start 155.83 66.075)
		(end 156.55 66.075)
		(width 0.1)
		(layer "B.Cu")
		(net 137)
	)
	(via
		(at 155.755 71.25)
		(size 0.45)
		(drill 0.2)
		(layers "F.Cu" "B.Cu")
		(remove_unused_layers yes)
		(keep_end_layers yes)
		(zone_layer_connections)
		(net 138)
	)
	(via
		(at 157.16 64.695)
		(size 0.45)
		(drill 0.2)
		(layers "F.Cu" "B.Cu")
		(remove_unused_layers yes)
		(keep_end_layers yes)
		(zone_layer_connections)
		(net 138)
	)
	(segment
		(start 156.731866 62.935117)
		(end 156.731866 64.266866)
		(width 0.1)
		(layer "B.Cu")
		(net 138)
	)
	(segment
		(start 156.731866 64.266866)
		(end 157.16 64.695)
		(width 0.1)
		(layer "B.Cu")
		(net 138)
	)
	(segment
		(start 157.6 65.15)
		(end 157.6 69.415)
		(width 0.1)
		(layer "In5.Cu")
		(net 138)
	)
	(segment
		(start 157.6 69.415)
		(end 155.76 71.255)
		(width 0.1)
		(layer "In5.Cu")
		(net 138)
	)
	(segment
		(start 157.15 64.7)
		(end 157.6 65.15)
		(width 0.1)
		(layer "In5.Cu")
		(net 138)
	)
	(via
		(at 154.31 66.645)
		(size 0.45)
		(drill 0.2)
		(layers "F.Cu" "B.Cu")
		(remove_unused_layers yes)
		(keep_end_layers yes)
		(zone_layer_connections)
		(net 139)
	)
	(segment
		(start 154.9 65.2)
		(end 156.4 65.2)
		(width 0.1)
		(layer "B.Cu")
		(net 139)
	)
	(segment
		(start 156.4 62.05)
		(end 158.846748 62.05)
		(width 0.1)
		(layer "B.Cu")
		(net 139)
	)
	(segment
		(start 156.61 64.99)
		(end 156.61 64.51)
		(width 0.1)
		(layer "B.Cu")
		(net 139)
	)
	(segment
		(start 155.131866 68.431866)
		(end 155.131866 69.555117)
		(width 0.1)
		(layer "B.Cu")
		(net 139)
	)
	(segment
		(start 154.8 65.3)
		(end 154.9 65.2)
		(width 0.1)
		(layer "B.Cu")
		(net 139)
	)
	(segment
		(start 156 63.9)
		(end 156 62.45)
		(width 0.1)
		(layer "B.Cu")
		(net 139)
	)
	(segment
		(start 156.4 65.2)
		(end 156.61 64.99)
		(width 0.1)
		(layer "B.Cu")
		(net 139)
	)
	(segment
		(start 154.31 66.645)
		(end 154.8 67.135)
		(width 0.1)
		(layer "B.Cu")
		(net 139)
	)
	(segment
		(start 156 62.45)
		(end 156.4 62.05)
		(width 0.1)
		(layer "B.Cu")
		(net 139)
	)
	(segment
		(start 154.31 66.645)
		(end 154.8 66.155)
		(width 0.1)
		(layer "B.Cu")
		(net 139)
	)
	(segment
		(start 156.61 64.51)
		(end 156 63.9)
		(width 0.1)
		(layer "B.Cu")
		(net 139)
	)
	(segment
		(start 158.846748 62.05)
		(end 159.731865 62.935117)
		(width 0.1)
		(layer "B.Cu")
		(net 139)
	)
	(segment
		(start 154.8 67.135)
		(end 154.8 68.1)
		(width 0.1)
		(layer "B.Cu")
		(net 139)
	)
	(segment
		(start 154.8 66.155)
		(end 154.8 65.3)
		(width 0.1)
		(layer "B.Cu")
		(net 139)
	)
	(segment
		(start 154.8 68.1)
		(end 155.131866 68.431866)
		(width 0.1)
		(layer "B.Cu")
		(net 139)
	)
	(via
		(at 156.62 71.75)
		(size 0.45)
		(drill 0.2)
		(layers "F.Cu" "B.Cu")
		(remove_unused_layers yes)
		(keep_end_layers yes)
		(zone_layer_connections)
		(net 140)
	)
	(via
		(at 158.11 64.695)
		(size 0.45)
		(drill 0.2)
		(layers "F.Cu" "B.Cu")
		(remove_unused_layers yes)
		(keep_end_layers yes)
		(zone_layer_connections)
		(net 140)
	)
	(segment
		(start 158.231866 64.573134)
		(end 158.11 64.695)
		(width 0.1)
		(layer "B.Cu")
		(net 140)
	)
	(segment
		(start 158.231866 62.935117)
		(end 158.231866 64.573134)
		(width 0.1)
		(layer "B.Cu")
		(net 140)
	)
	(segment
		(start 158.6 69.78)
		(end 158.6 65.2)
		(width 0.1)
		(layer "In5.Cu")
		(net 140)
	)
	(segment
		(start 158.6 65.2)
		(end 158.1 64.7)
		(width 0.1)
		(layer "In5.Cu")
		(net 140)
	)
	(segment
		(start 156.625 71.755)
		(end 158.6 69.78)
		(width 0.1)
		(layer "In5.Cu")
		(net 140)
	)
	(via
		(at 157.16 66.645)
		(size 0.45)
		(drill 0.2)
		(layers "F.Cu" "B.Cu")
		(remove_unused_layers yes)
		(keep_end_layers yes)
		(zone_layer_connections)
		(net 141)
	)
	(segment
		(start 157.7 67.4)
		(end 157.7 69.123252)
		(width 0.1)
		(layer "B.Cu")
		(net 141)
	)
	(segment
		(start 159.696748 67.4)
		(end 159.731866 67.435118)
		(width 0.1)
		(layer "B.Cu")
		(net 141)
	)
	(segment
		(start 157.7 69.123252)
		(end 158.131866 69.555118)
		(width 0.1)
		(layer "B.Cu")
		(net 141)
	)
	(segment
		(start 157.7 67.185)
		(end 157.7 67.4)
		(width 0.1)
		(layer "B.Cu")
		(net 141)
	)
	(segment
		(start 157.7 67.4)
		(end 159.696748 67.4)
		(width 0.1)
		(layer "B.Cu")
		(net 141)
	)
	(segment
		(start 157.16 66.645)
		(end 157.7 67.185)
		(width 0.1)
		(layer "B.Cu")
		(net 141)
	)
	(via
		(at 156.21 66.645)
		(size 0.45)
		(drill 0.2)
		(layers "F.Cu" "B.Cu")
		(remove_unused_layers yes)
		(keep_end_layers yes)
		(zone_layer_connections)
		(net 142)
	)
	(segment
		(start 158.764883 65.935117)
		(end 158.55 66.15)
		(width 0.1)
		(layer "B.Cu")
		(net 142)
	)
	(segment
		(start 156.555 66.645)
		(end 156.21 66.645)
		(width 0.1)
		(layer "B.Cu")
		(net 142)
	)
	(segment
		(start 156.7 69.123251)
		(end 157.131866 69.555117)
		(width 0.1)
		(layer "B.Cu")
		(net 142)
	)
	(segment
		(start 159.731866 65.935117)
		(end 158.764883 65.935117)
		(width 0.1)
		(layer "B.Cu")
		(net 142)
	)
	(segment
		(start 156.7 67.5)
		(end 156.7 69.123251)
		(width 0.1)
		(layer "B.Cu")
		(net 142)
	)
	(segment
		(start 156.21 67.01)
		(end 156.7 67.5)
		(width 0.1)
		(layer "B.Cu")
		(net 142)
	)
	(segment
		(start 156.21 66.645)
		(end 156.21 67.01)
		(width 0.1)
		(layer "B.Cu")
		(net 142)
	)
	(segment
		(start 157.05 66.15)
		(end 156.555 66.645)
		(width 0.1)
		(layer "B.Cu")
		(net 142)
	)
	(segment
		(start 158.55 66.15)
		(end 157.05 66.15)
		(width 0.1)
		(layer "B.Cu")
		(net 142)
	)
	(via
		(at 154.89 72.75)
		(size 0.45)
		(drill 0.2)
		(layers "F.Cu" "B.Cu")
		(remove_unused_layers yes)
		(keep_end_layers yes)
		(zone_layer_connections)
		(net 143)
	)
	(via
		(at 154.31 64.695)
		(size 0.45)
		(drill 0.2)
		(layers "F.Cu" "B.Cu")
		(remove_unused_layers yes)
		(keep_end_layers yes)
		(zone_layer_connections)
		(net 143)
	)
	(segment
		(start 152.2 62.935117)
		(end 153.959883 64.695)
		(width 0.1)
		(layer "B.Cu")
		(net 143)
	)
	(segment
		(start 153.959883 64.695)
		(end 154.31 64.695)
		(width 0.1)
		(layer "B.Cu")
		(net 143)
	)
	(segment
		(start 154.3 64.7)
		(end 154.78 65.18)
		(width 0.1)
		(layer "In5.Cu")
		(net 143)
	)
	(segment
		(start 154.423197 69.196286)
		(end 154.423197 72.283197)
		(width 0.1)
		(layer "In5.Cu")
		(net 143)
	)
	(segment
		(start 154.78 68.839483)
		(end 154.423197 69.196286)
		(width 0.1)
		(layer "In5.Cu")
		(net 143)
	)
	(segment
		(start 154.78 65.18)
		(end 154.78 68.839483)
		(width 0.1)
		(layer "In5.Cu")
		(net 143)
	)
	(segment
		(start 154.423197 72.283197)
		(end 154.895 72.755)
		(width 0.1)
		(layer "In5.Cu")
		(net 143)
	)
	(via
		(at 155.26 64.695)
		(size 0.45)
		(drill 0.2)
		(layers "F.Cu" "B.Cu")
		(remove_unused_layers yes)
		(keep_end_layers yes)
		(zone_layer_connections)
		(net 144)
	)
	(via
		(at 154.89 71.75)
		(size 0.45)
		(drill 0.2)
		(layers "F.Cu" "B.Cu")
		(remove_unused_layers yes)
		(keep_end_layers yes)
		(zone_layer_connections)
		(net 144)
	)
	(segment
		(start 153.7 62.935117)
		(end 153.7 63.135)
		(width 0.1)
		(layer "B.Cu")
		(net 144)
	)
	(segment
		(start 153.7 63.135)
		(end 155.26 64.695)
		(width 0.1)
		(layer "B.Cu")
		(net 144)
	)
	(segment
		(start 154.895 69.625)
		(end 155.65 68.87)
		(width 0.1)
		(layer "In5.Cu")
		(net 144)
	)
	(segment
		(start 154.895 71.755)
		(end 154.895 69.625)
		(width 0.1)
		(layer "In5.Cu")
		(net 144)
	)
	(segment
		(start 155.65 68.87)
		(end 155.65 65.1)
		(width 0.1)
		(layer "In5.Cu")
		(net 144)
	)
	(segment
		(start 155.65 65.1)
		(end 155.25 64.7)
		(width 0.1)
		(layer "In5.Cu")
		(net 144)
	)
	(via
		(at 156.21 64.694999)
		(size 0.45)
		(drill 0.2)
		(layers "F.Cu" "B.Cu")
		(remove_unused_layers yes)
		(keep_end_layers yes)
		(zone_layer_connections)
		(net 145)
	)
	(via
		(at 155.755 72.25)
		(size 0.45)
		(drill 0.2)
		(layers "F.Cu" "B.Cu")
		(remove_unused_layers yes)
		(keep_end_layers yes)
		(zone_layer_connections)
		(net 145)
	)
	(segment
		(start 155.231866 63.716865)
		(end 156.21 64.694999)
		(width 0.1)
		(layer "B.Cu")
		(net 145)
	)
	(segment
		(start 155.231866 62.935117)
		(end 155.231866 63.716865)
		(width 0.1)
		(layer "B.Cu")
		(net 145)
	)
	(segment
		(start 155.76 72.255)
		(end 155.76 71.94)
		(width 0.1)
		(layer "In5.Cu")
		(net 145)
	)
	(segment
		(start 155.76 71.94)
		(end 155.3 71.48)
		(width 0.1)
		(layer "In5.Cu")
		(net 145)
	)
	(segment
		(start 155.3 70.18)
		(end 156.65 68.83)
		(width 0.1)
		(layer "In5.Cu")
		(net 145)
	)
	(segment
		(start 156.65 65.149999)
		(end 156.2 64.699999)
		(width 0.1)
		(layer "In5.Cu")
		(net 145)
	)
	(segment
		(start 155.3 71.48)
		(end 155.3 70.18)
		(width 0.1)
		(layer "In5.Cu")
		(net 145)
	)
	(segment
		(start 156.65 68.83)
		(end 156.65 65.149999)
		(width 0.1)
		(layer "In5.Cu")
		(net 145)
	)
	(segment
		(start 166.9 74.8)
		(end 167.4 74.8)
		(width 0.1)
		(layer "F.Cu")
		(net 146)
	)
	(segment
		(start 163.52 75.414998)
		(end 164.48 76.374998)
		(width 0.1)
		(layer "F.Cu")
		(net 146)
	)
	(segment
		(start 167.4 74.8)
		(end 167.6 75)
		(width 0.1)
		(layer "F.Cu")
		(net 146)
	)
	(segment
		(start 167 76.4)
		(end 167.6 75.8)
		(width 0.1)
		(layer "F.Cu")
		(net 146)
	)
	(segment
		(start 167.6 75)
		(end 167.6 75.8)
		(width 0.1)
		(layer "F.Cu")
		(net 146)
	)
	(segment
		(start 164.48 76.374998)
		(end 164.48 76.4)
		(width 0.1)
		(layer "F.Cu")
		(net 146)
	)
	(segment
		(start 166.462 74.362)
		(end 166.9 74.8)
		(width 0.1)
		(layer "F.Cu")
		(net 146)
	)
	(segment
		(start 164.48 76.4)
		(end 167 76.4)
		(width 0.1)
		(layer "F.Cu")
		(net 146)
	)
	(segment
		(start 166.462 73.825999)
		(end 166.462 74.362)
		(width 0.1)
		(layer "F.Cu")
		(net 146)
	)
	(segment
		(start 163.52 75.4)
		(end 163.52 75.414998)
		(width 0.1)
		(layer "F.Cu")
		(net 146)
	)
	(segment
		(start 171.087 77.987)
		(end 171.335 78.235)
		(width 0.1)
		(layer "F.Cu")
		(net 147)
	)
	(segment
		(start 169.852 77.987)
		(end 171.087 77.987)
		(width 0.1)
		(layer "F.Cu")
		(net 147)
	)
	(segment
		(start 171.335 79.361)
		(end 171.335 80.135)
		(width 0.1)
		(layer "F.Cu")
		(net 147)
	)
	(segment
		(start 171.335 78.235)
		(end 171.335 79.361)
		(width 0.1)
		(layer "F.Cu")
		(net 147)
	)
	(segment
		(start 171.335 80.135)
		(end 171.4 80.2)
		(width 0.1)
		(layer "F.Cu")
		(net 147)
	)
	(via
		(at 151.43 91.75)
		(size 0.45)
		(drill 0.2)
		(layers "F.Cu" "B.Cu")
		(remove_unused_layers yes)
		(keep_end_layers yes)
		(zone_layer_connections)
		(net 147)
	)
	(via
		(at 171.4 80.2)
		(size 0.45)
		(drill 0.2)
		(layers "F.Cu" "B.Cu")
		(remove_unused_layers yes)
		(keep_end_layers yes)
		(zone_layer_connections)
		(net 147)
	)
	(segment
		(start 172.299999 81.300001)
		(end 173.2 80.4)
		(width 0.1)
		(layer "In3.Cu")
		(net 147)
	)
	(segment
		(start 151.8 94.7)
		(end 152.5 95.4)
		(width 0.1)
		(layer "In3.Cu")
		(net 147)
	)
	(segment
		(start 161.2 94.9)
		(end 163.1 94.9)
		(width 0.1)
		(layer "In3.Cu")
		(net 147)
	)
	(segment
		(start 172.299999 84.207107)
		(end 172.299999 81.300001)
		(width 0.1)
		(layer "In3.Cu")
		(net 147)
	)
	(segment
		(start 163.1 94.9)
		(end 163.353553 94.646447)
		(width 0.1)
		(layer "In3.Cu")
		(net 147)
	)
	(segment
		(start 173 79.6)
		(end 172 79.6)
		(width 0.1)
		(layer "In3.Cu")
		(net 147)
	)
	(segment
		(start 160.7 95.4)
		(end 161.2 94.9)
		(width 0.1)
		(layer "In3.Cu")
		(net 147)
	)
	(segment
		(start 173.2 79.8)
		(end 173 79.6)
		(width 0.1)
		(layer "In3.Cu")
		(net 147)
	)
	(segment
		(start 163.353553 94.646447)
		(end 163.353553 93.153553)
		(width 0.1)
		(layer "In3.Cu")
		(net 147)
	)
	(segment
		(start 151.8 93.6)
		(end 151.8 94.7)
		(width 0.1)
		(layer "In3.Cu")
		(net 147)
	)
	(segment
		(start 151.43 93.23)
		(end 151.8 93.6)
		(width 0.1)
		(layer "In3.Cu")
		(net 147)
	)
	(segment
		(start 173.2 80.4)
		(end 173.2 79.8)
		(width 0.1)
		(layer "In3.Cu")
		(net 147)
	)
	(segment
		(start 163.353553 93.153553)
		(end 172.299999 84.207107)
		(width 0.1)
		(layer "In3.Cu")
		(net 147)
	)
	(segment
		(start 172 79.6)
		(end 171.4 80.2)
		(width 0.1)
		(layer "In3.Cu")
		(net 147)
	)
	(segment
		(start 151.43 91.75)
		(end 151.43 93.23)
		(width 0.1)
		(layer "In3.Cu")
		(net 147)
	)
	(segment
		(start 152.5 95.4)
		(end 160.7 95.4)
		(width 0.1)
		(layer "In3.Cu")
		(net 147)
	)
	(segment
		(start 172.625 79.341)
		(end 172.625 78.275)
		(width 0.1)
		(layer "F.Cu")
		(net 148)
	)
	(segment
		(start 172.9 78)
		(end 174.138 78)
		(width 0.1)
		(layer "F.Cu")
		(net 148)
	)
	(segment
		(start 172.625 79.341)
		(end 172.625 80.175)
		(width 0.1)
		(layer "F.Cu")
		(net 148)
	)
	(segment
		(start 172.625 78.275)
		(end 172.9 78)
		(width 0.1)
		(layer "F.Cu")
		(net 148)
	)
	(segment
		(start 174.138 78)
		(end 174.151 77.987)
		(width 0.1)
		(layer "F.Cu")
		(net 148)
	)
	(segment
		(start 172.625 80.175)
		(end 172.6 80.2)
		(width 0.1)
		(layer "F.Cu")
		(net 148)
	)
	(via
		(at 172.6 80.2)
		(size 0.45)
		(drill 0.2)
		(layers "F.Cu" "B.Cu")
		(remove_unused_layers yes)
		(keep_end_layers yes)
		(zone_layer_connections)
		(net 148)
	)
	(via
		(at 152.295 91.25)
		(size 0.45)
		(drill 0.2)
		(layers "F.Cu" "B.Cu")
		(remove_unused_layers yes)
		(keep_end_layers yes)
		(zone_layer_connections)
		(net 148)
	)
	(segment
		(start 155.3 92.4)
		(end 155.6 92.7)
		(width 0.1)
		(layer "In3.Cu")
		(net 148)
	)
	(segment
		(start 155.6 92.7)
		(end 163.1 92.7)
		(width 0.1)
		(layer "In3.Cu")
		(net 148)
	)
	(segment
		(start 171.8 84)
		(end 171.8 81)
		(width 0.1)
		(layer "In3.Cu")
		(net 148)
	)
	(segment
		(start 171.8 81)
		(end 172.6 80.2)
		(width 0.1)
		(layer "In3.Cu")
		(net 148)
	)
	(segment
		(start 163.1 92.7)
		(end 171.8 84)
		(width 0.1)
		(layer "In3.Cu")
		(net 148)
	)
	(segment
		(start 152.295 91.695)
		(end 153 92.4)
		(width 0.1)
		(layer "In3.Cu")
		(net 148)
	)
	(segment
		(start 153 92.4)
		(end 155.3 92.4)
		(width 0.1)
		(layer "In3.Cu")
		(net 148)
	)
	(segment
		(start 152.295 91.25)
		(end 152.295 91.695)
		(width 0.1)
		(layer "In3.Cu")
		(net 148)
	)
	(via
		(at 158.35 72.75)
		(size 0.45)
		(drill 0.2)
		(layers "F.Cu" "B.Cu")
		(remove_unused_layers yes)
		(keep_end_layers yes)
		(zone_layer_connections)
		(net 149)
	)
	(segment
		(start 158.35 76.44)
		(end 159.035 75.755)
		(width 0.1)
		(layer "F.Cu")
		(net 150)
	)
	(segment
		(start 158.35 76.75)
		(end 158.35 76.44)
		(width 0.1)
		(layer "F.Cu")
		(net 150)
	)
	(segment
		(start 160.265 75.245)
		(end 160.7965 74.7135)
		(width 0.1)
		(layer "F.Cu")
		(net 150)
	)
	(segment
		(start 164.513 72.413)
		(end 164.513 73.825999)
		(width 0.1)
		(layer "F.Cu")
		(net 150)
	)
	(segment
		(start 159.895 75.245)
		(end 160.265 75.245)
		(width 0.1)
		(layer "F.Cu")
		(net 150)
	)
	(segment
		(start 164.513 73.825999)
		(end 164.513 74.4005)
		(width 0.1)
		(layer "F.Cu")
		(net 150)
	)
	(segment
		(start 159.385 75.755)
		(end 159.895 75.245)
		(width 0.1)
		(layer "F.Cu")
		(net 150)
	)
	(segment
		(start 159.035 75.755)
		(end 159.385 75.755)
		(width 0.1)
		(layer "F.Cu")
		(net 150)
	)
	(segment
		(start 163.12 67.8)
		(end 163.12 71.02)
		(width 0.1)
		(layer "F.Cu")
		(net 150)
	)
	(segment
		(start 163.12 71.02)
		(end 164.513 72.413)
		(width 0.1)
		(layer "F.Cu")
		(net 150)
	)
	(segment
		(start 164.513 74.4005)
		(end 164.2 74.7135)
		(width 0.1)
		(layer "F.Cu")
		(net 150)
	)
	(segment
		(start 160.7965 74.7135)
		(end 164.2 74.7135)
		(width 0.1)
		(layer "F.Cu")
		(net 150)
	)
	(segment
		(start 118 71.4)
		(end 118.15 71.25)
		(width 0.1)
		(layer "F.Cu")
		(net 151)
	)
	(segment
		(start 117.47 73.89)
		(end 117.48 73.9)
		(width 0.1)
		(layer "F.Cu")
		(net 151)
	)
	(segment
		(start 118 72.37)
		(end 118 71.4)
		(width 0.1)
		(layer "F.Cu")
		(net 151)
	)
	(segment
		(start 118.15 71.25)
		(end 119 71.25)
		(width 0.1)
		(layer "F.Cu")
		(net 151)
	)
	(segment
		(start 117.47 72.9)
		(end 117.47 73.89)
		(width 0.1)
		(layer "F.Cu")
		(net 151)
	)
	(segment
		(start 117.47 72.9)
		(end 118 72.37)
		(width 0.1)
		(layer "F.Cu")
		(net 151)
	)
	(segment
		(start 122.75 72)
		(end 122.75 72.75)
		(width 0.1)
		(layer "F.Cu")
		(net 152)
	)
	(segment
		(start 122 71.75)
		(end 122.5 71.75)
		(width 0.1)
		(layer "F.Cu")
		(net 152)
	)
	(segment
		(start 122.75 72.75)
		(end 123 73)
		(width 0.1)
		(layer "F.Cu")
		(net 152)
	)
	(segment
		(start 123 73)
		(end 123.52 73)
		(width 0.1)
		(layer "F.Cu")
		(net 152)
	)
	(segment
		(start 122.5 71.75)
		(end 122.75 72)
		(width 0.1)
		(layer "F.Cu")
		(net 152)
	)
	(segment
		(start 141.1 108.049997)
		(end 140.900002 107.849999)
		(width 0.15)
		(layer "F.Cu")
		(net 153)
	)
	(segment
		(start 140.900002 107.849999)
		(end 139.449999 107.849998)
		(width 0.15)
		(layer "F.Cu")
		(net 153)
	)
	(segment
		(start 141.1 109.369999)
		(end 141.1 108.049997)
		(width 0.15)
		(layer "F.Cu")
		(net 153)
	)
	(segment
		(start 122 70.75)
		(end 122.65 70.75)
		(width 0.1)
		(layer "F.Cu")
		(net 154)
	)
	(segment
		(start 122.65 70.75)
		(end 122.8 70.6)
		(width 0.1)
		(layer "F.Cu")
		(net 154)
	)
	(via
		(at 122.8 70.6)
		(size 0.45)
		(drill 0.2)
		(layers "F.Cu" "B.Cu")
		(remove_unused_layers yes)
		(keep_end_layers yes)
		(zone_layer_connections)
		(net 154)
	)
	(segment
		(start 120.799 72.601)
		(end 120.799 76)
		(width 0.1)
		(layer "B.Cu")
		(net 154)
	)
	(segment
		(start 122.8 70.6)
		(end 120.799 72.601)
		(width 0.1)
		(layer "B.Cu")
		(net 154)
	)
	(segment
		(start 118.5 76)
		(end 120.799 76)
		(width 0.1)
		(layer "B.Cu")
		(net 154)
	)
	(segment
		(start 122 71.25)
		(end 122.75 71.25)
		(width 0.1)
		(layer "F.Cu")
		(net 156)
	)
	(segment
		(start 122.75 71.25)
		(end 123 71)
		(width 0.1)
		(layer "F.Cu")
		(net 156)
	)
	(segment
		(start 123 71)
		(end 123.52 71)
		(width 0.1)
		(layer "F.Cu")
		(net 156)
	)
	(segment
		(start 123.52 72)
		(end 123.52 71)
		(width 0.1)
		(layer "F.Cu")
		(net 156)
	)
	(segment
		(start 117.48 69.9)
		(end 117.9 69.9)
		(width 0.1)
		(layer "F.Cu")
		(net 157)
	)
	(segment
		(start 117.48 69.9)
		(end 117.48 68.9)
		(width 0.1)
		(layer "F.Cu")
		(net 157)
	)
	(segment
		(start 118.25 70.25)
		(end 119 70.25)
		(width 0.1)
		(layer "F.Cu")
		(net 157)
	)
	(segment
		(start 117.9 69.9)
		(end 118.25 70.25)
		(width 0.1)
		(layer "F.Cu")
		(net 157)
	)
	(segment
		(start 117.48 70.9)
		(end 118 70.9)
		(width 0.1)
		(layer "F.Cu")
		(net 158)
	)
	(segment
		(start 118 70.9)
		(end 118.15 70.75)
		(width 0.1)
		(layer "F.Cu")
		(net 158)
	)
	(segment
		(start 118.15 70.75)
		(end 119 70.75)
		(width 0.1)
		(layer "F.Cu")
		(net 158)
	)
	(segment
		(start 139.780001 67.85)
		(end 140.697488 67.85)
		(width 0.19)
		(layer "F.Cu")
		(net 159)
	)
	(segment
		(start 140.697488 67.85)
		(end 142.901745 70.054257)
		(width 0.19)
		(layer "F.Cu")
		(net 159)
	)
	(segment
		(start 143.551744 71.249999)
		(end 142.901745 70.6)
		(width 0.19)
		(layer "F.Cu")
		(net 159)
	)
	(segment
		(start 143.655 71.249999)
		(end 143.551744 71.249999)
		(width 0.19)
		(layer "F.Cu")
		(net 159)
	)
	(segment
		(start 139.48 67.549999)
		(end 139.780001 67.85)
		(width 0.19)
		(layer "F.Cu")
		(net 159)
	)
	(segment
		(start 142.901745 70.054257)
		(end 142.901745 70.6)
		(width 0.19)
		(layer "F.Cu")
		(net 159)
	)
	(segment
		(start 139.48 68.5)
		(end 139.78 68.2)
		(width 0.19)
		(layer "F.Cu")
		(net 160)
	)
	(segment
		(start 142.064202 69.71169)
		(end 142.551745 70.199233)
		(width 0.19)
		(layer "F.Cu")
		(net 160)
	)
	(segment
		(start 141.427806 69.489748)
		(end 141.538776 69.600718)
		(width 0.19)
		(layer "F.Cu")
		(net 160)
	)
	(segment
		(start 142.79 71.038255)
		(end 142.79 71.749999)
		(width 0.19)
		(layer "F.Cu")
		(net 160)
	)
	(segment
		(start 142.551745 70.8)
		(end 142.79 71.038255)
		(width 0.19)
		(layer "F.Cu")
		(net 160)
	)
	(segment
		(start 139.78 68.2)
		(end 140.552512 68.2)
		(width 0.19)
		(layer "F.Cu")
		(net 160)
	)
	(segment
		(start 142.551745 70.634095)
		(end 142.551745 70.8)
		(width 0.19)
		(layer "F.Cu")
		(net 160)
	)
	(segment
		(start 140.552512 68.2)
		(end 141.427806 69.075294)
		(width 0.19)
		(layer "F.Cu")
		(net 160)
	)
	(segment
		(start 142.551745 70.199233)
		(end 142.551745 70.634095)
		(width 0.19)
		(layer "F.Cu")
		(net 160)
	)
	(segment
		(start 141.953231 69.600718)
		(end 142.064202 69.71169)
		(width 0.19)
		(layer "F.Cu")
		(net 160)
	)
	(arc
		(start 141.427806 69.075294)
		(mid 141.470724 69.178908)
		(end 141.427806 69.282521)
		(width 0.19)
		(layer "F.Cu")
		(net 160)
	)
	(arc
		(start 141.746004 69.600718)
		(mid 141.849617 69.5578)
		(end 141.953231 69.600718)
		(width 0.19)
		(layer "F.Cu")
		(net 160)
	)
	(arc
		(start 141.538776 69.600718)
		(mid 141.64239 69.643636)
		(end 141.746004 69.600718)
		(width 0.19)
		(layer "F.Cu")
		(net 160)
	)
	(arc
		(start 141.427806 69.282521)
		(mid 141.384888 69.386134)
		(end 141.427806 69.489748)
		(width 0.19)
		(layer "F.Cu")
		(net 160)
	)
	(segment
		(start 115.92 109.97)
		(end 115.92 109.1)
		(width 0.1)
		(layer "F.Cu")
		(net 161)
	)
	(segment
		(start 116.65 110.55)
		(end 116.5 110.55)
		(width 0.1)
		(layer "F.Cu")
		(net 161)
	)
	(segment
		(start 116.5 110.55)
		(end 115.92 109.97)
		(width 0.1)
		(layer "F.Cu")
		(net 161)
	)
	(segment
		(start 116.88 102.1)
		(end 118.5 102.1)
		(width 0.1)
		(layer "F.Cu")
		(net 162)
	)
	(segment
		(start 118.5 102.1)
		(end 118.9 102.5)
		(width 0.1)
		(layer "F.Cu")
		(net 162)
	)
	(segment
		(start 118.9 102.5)
		(end 118.9 103.151)
		(width 0.1)
		(layer "F.Cu")
		(net 162)
	)
	(segment
		(start 118.595 98.5)
		(end 118.595 100.005)
		(width 0.1)
		(layer "F.Cu")
		(net 163)
	)
	(segment
		(start 116.6 100.6)
		(end 115.92 101.28)
		(width 0.1)
		(layer "F.Cu")
		(net 163)
	)
	(segment
		(start 118.595 100.005)
		(end 118 100.6)
		(width 0.1)
		(layer "F.Cu")
		(net 163)
	)
	(segment
		(start 115.92 101.28)
		(end 115.92 102.1)
		(width 0.1)
		(layer "F.Cu")
		(net 163)
	)
	(segment
		(start 118 100.6)
		(end 116.6 100.6)
		(width 0.1)
		(layer "F.Cu")
		(net 163)
	)
	(segment
		(start 116.06 138.24)
		(end 116 138.3)
		(width 0.1)
		(layer "F.Cu")
		(net 164)
	)
	(segment
		(start 117.4 138.24)
		(end 116.06 138.24)
		(width 0.1)
		(layer "F.Cu")
		(net 164)
	)
	(segment
		(start 133.74 137)
		(end 133.58 136.84)
		(width 0.1)
		(layer "F.Cu")
		(net 165)
	)
	(segment
		(start 134 137)
		(end 133.74 137)
		(width 0.1)
		(layer "F.Cu")
		(net 165)
	)
	(via
		(at 133.58 136.84)
		(size 0.45)
		(drill 0.2)
		(layers "F.Cu" "B.Cu")
		(remove_unused_layers yes)
		(keep_end_layers yes)
		(zone_layer_connections)
		(net 165)
	)
	(segment
		(start 116.88 105.1)
		(end 116.9 105.1)
		(width 0.1)
		(layer "F.Cu")
		(net 166)
	)
	(segment
		(start 116.88 106.09)
		(end 116.88 105.1)
		(width 0.1)
		(layer "F.Cu")
		(net 166)
	)
	(segment
		(start 117.65 104.35)
		(end 118.15 104.35)
		(width 0.1)
		(layer "F.Cu")
		(net 166)
	)
	(segment
		(start 116.88 107.1)
		(end 116.88 106.09)
		(width 0.1)
		(layer "F.Cu")
		(net 166)
	)
	(segment
		(start 116.9 105.1)
		(end 117.65 104.35)
		(width 0.1)
		(layer "F.Cu")
		(net 166)
	)
	(segment
		(start 124.75 134.27)
		(end 124.75 134.245)
		(width 0.19)
		(layer "F.Cu")
		(net 167)
	)
	(segment
		(start 125.05 129.238786)
		(end 125.05 129.525)
		(width 0.1)
		(layer "F.Cu")
		(net 167)
	)
	(segment
		(start 125.28 128.927425)
		(end 125.28 129.01)
		(width 0.1)
		(layer "F.Cu")
		(net 167)
	)
	(segment
		(start 125.152426 128.825)
		(end 125.177573 128.825)
		(width 0.1)
		(layer "F.Cu")
		(net 167)
	)
	(segment
		(start 124.75 134.245)
		(end 125.075 133.92)
		(width 0.19)
		(layer "F.Cu")
		(net 167)
	)
	(segment
		(start 125.075 129.72)
		(end 125.05 129.695)
		(width 0.19)
		(layer "F.Cu")
		(net 167)
	)
	(segment
		(start 125.05 129.695)
		(end 125.05 129.525)
		(width 0.19)
		(layer "F.Cu")
		(net 167)
	)
	(segment
		(start 125.075 133.92)
		(end 125.075 129.72)
		(width 0.19)
		(layer "F.Cu")
		(net 167)
	)
	(segment
		(start 125.05 128.927426)
		(end 125.05 129.238786)
		(width 0.1)
		(layer "F.Cu")
		(net 167)
	)
	(arc
		(start 125.05 128.927426)
		(mid 125.057796 128.888229)
		(end 125.08 128.855)
		(width 0.1)
		(layer "F.Cu")
		(net 167)
	)
	(arc
		(start 125.25 128.855)
		(mid 125.216771 128.832796)
		(end 125.177573 128.825)
		(width 0.1)
		(layer "F.Cu")
		(net 167)
	)
	(arc
		(start 125.25 128.855)
		(mid 125.272203 128.888229)
		(end 125.28 128.927425)
		(width 0.1)
		(layer "F.Cu")
		(net 167)
	)
	(arc
		(start 125.152426 128.825)
		(mid 125.113229 128.832796)
		(end 125.08 128.855)
		(width 0.1)
		(layer "F.Cu")
		(net 167)
	)
	(segment
		(start 126.925 131.977512)
		(end 126.375 131.427512)
		(width 0.19)
		(layer "F.Cu")
		(net 168)
	)
	(segment
		(start 127.05 133)
		(end 126.925 132.875)
		(width 0.19)
		(layer "F.Cu")
		(net 168)
	)
	(segment
		(start 126.43 128.927426)
		(end 126.43 129.52)
		(width 0.1)
		(layer "F.Cu")
		(net 168)
	)
	(segment
		(start 126.43 129.695)
		(end 126.43 129.52)
		(width 0.19)
		(layer "F.Cu")
		(net 168)
	)
	(segment
		(start 126.375 129.75)
		(end 126.43 129.695)
		(width 0.19)
		(layer "F.Cu")
		(net 168)
	)
	(segment
		(start 126.327574 128.825)
		(end 126.302427 128.825)
		(width 0.1)
		(layer "F.Cu")
		(net 168)
	)
	(segment
		(start 126.2 128.927425)
		(end 126.2 129.01)
		(width 0.1)
		(layer "F.Cu")
		(net 168)
	)
	(segment
		(start 126.925 132.875)
		(end 126.925 131.977512)
		(width 0.19)
		(layer "F.Cu")
		(net 168)
	)
	(segment
		(start 126.375 131.427512)
		(end 126.375 129.75)
		(width 0.19)
		(layer "F.Cu")
		(net 168)
	)
	(via
		(at 127.05 133)
		(size 0.45)
		(drill 0.2)
		(layers "F.Cu" "B.Cu")
		(remove_unused_layers yes)
		(keep_end_layers yes)
		(zone_layer_connections)
		(net 168)
	)
	(arc
		(start 126.4 128.855)
		(mid 126.422204 128.888229)
		(end 126.43 128.927426)
		(width 0.1)
		(layer "F.Cu")
		(net 168)
	)
	(arc
		(start 126.23 128.855)
		(mid 126.263229 128.832796)
		(end 126.302427 128.825)
		(width 0.1)
		(layer "F.Cu")
		(net 168)
	)
	(arc
		(start 126.4 128.855)
		(mid 126.366771 128.832796)
		(end 126.327574 128.825)
		(width 0.1)
		(layer "F.Cu")
		(net 168)
	)
	(arc
		(start 126.23 128.855)
		(mid 126.207797 128.888229)
		(end 126.2 128.927425)
		(width 0.1)
		(layer "F.Cu")
		(net 168)
	)
	(segment
		(start 126.925 133.92)
		(end 126.925 133.125)
		(width 0.19)
		(layer "B.Cu")
		(net 168)
	)
	(segment
		(start 127.25 134.245)
		(end 126.925 133.92)
		(width 0.19)
		(layer "B.Cu")
		(net 168)
	)
	(segment
		(start 127.25 134.27)
		(end 127.25 134.245)
		(width 0.19)
		(layer "B.Cu")
		(net 168)
	)
	(segment
		(start 126.925 133.125)
		(end 127.05 133)
		(width 0.19)
		(layer "B.Cu")
		(net 168)
	)
	(segment
		(start 125.425 129.78)
		(end 125.51 129.695)
		(width 0.19)
		(layer "F.Cu")
		(net 169)
	)
	(segment
		(start 125.51 129.515)
		(end 125.51 128.942634)
		(width 0.1)
		(layer "F.Cu")
		(net 169)
	)
	(segment
		(start 125.75 134.245)
		(end 125.425 133.92)
		(width 0.19)
		(layer "F.Cu")
		(net 169)
	)
	(segment
		(start 125.75 134.27)
		(end 125.75 134.245)
		(width 0.19)
		(layer "F.Cu")
		(net 169)
	)
	(segment
		(start 125.425 133.92)
		(end 125.425 129.78)
		(width 0.19)
		(layer "F.Cu")
		(net 169)
	)
	(segment
		(start 125.395 128.665)
		(end 125.28 128.55)
		(width 0.1)
		(layer "F.Cu")
		(net 169)
	)
	(segment
		(start 125.51 129.695)
		(end 125.51 129.515)
		(width 0.19)
		(layer "F.Cu")
		(net 169)
	)
	(arc
		(start 125.51 128.942634)
		(mid 125.480112 128.792379)
		(end 125.395 128.665)
		(width 0.1)
		(layer "F.Cu")
		(net 169)
	)
	(segment
		(start 137 137)
		(end 137.5 137)
		(width 0.1)
		(layer "F.Cu")
		(net 170)
	)
	(segment
		(start 137.5 137)
		(end 137.5 137.5)
		(width 0.1)
		(layer "F.Cu")
		(net 170)
	)
	(segment
		(start 137.5 137)
		(end 137.5 137.024)
		(width 0.1)
		(layer "F.Cu")
		(net 170)
	)
	(segment
		(start 137.5 137.024)
		(end 137.976 137.5)
		(width 0.1)
		(layer "F.Cu")
		(net 170)
	)
	(segment
		(start 137.5 136.5)
		(end 137.5 137)
		(width 0.1)
		(layer "F.Cu")
		(net 170)
	)
	(segment
		(start 137.5 137.5)
		(end 137.976 137.5)
		(width 0.1)
		(layer "F.Cu")
		(net 170)
	)
	(via
		(at 137.976 137.5)
		(size 0.45)
		(drill 0.2)
		(layers "F.Cu" "B.Cu")
		(remove_unused_layers yes)
		(keep_end_layers yes)
		(zone_layer_connections)
		(net 170)
	)
	(segment
		(start 134 134.71)
		(end 134 134.5)
		(width 0.1)
		(layer "F.Cu")
		(net 171)
	)
	(segment
		(start 133.88 134.83)
		(end 134 134.71)
		(width 0.1)
		(layer "F.Cu")
		(net 171)
	)
	(via
		(at 133.88 134.83)
		(size 0.45)
		(drill 0.2)
		(layers "F.Cu" "B.Cu")
		(remove_unused_layers yes)
		(keep_end_layers yes)
		(zone_layer_connections)
		(net 171)
	)
	(segment
		(start 133 134)
		(end 133 133.774)
		(width 0.1)
		(layer "F.Cu")
		(net 172)
	)
	(segment
		(start 133 133.774)
		(end 132.75 133.524)
		(width 0.1)
		(layer "F.Cu")
		(net 172)
	)
	(via
		(at 132.75 133.524)
		(size 0.45)
		(drill 0.2)
		(layers "F.Cu" "B.Cu")
		(remove_unused_layers yes)
		(keep_end_layers yes)
		(zone_layer_connections)
		(net 172)
	)
	(segment
		(start 137 139)
		(end 136.5 139)
		(width 0.1)
		(layer "F.Cu")
		(net 173)
	)
	(segment
		(start 137.5 139)
		(end 137.976 139.476)
		(width 0.1)
		(layer "F.Cu")
		(net 173)
	)
	(segment
		(start 137.5 139)
		(end 137 139)
		(width 0.1)
		(layer "F.Cu")
		(net 173)
	)
	(segment
		(start 136.5 139)
		(end 136 139)
		(width 0.1)
		(layer "F.Cu")
		(net 173)
	)
	(segment
		(start 134 138.5)
		(end 134 138.37)
		(width 0.1)
		(layer "F.Cu")
		(net 173)
	)
	(segment
		(start 137.976 139.476)
		(end 137.976 139.5)
		(width 0.1)
		(layer "F.Cu")
		(net 173)
	)
	(via
		(at 134 138.37)
		(size 0.45)
		(drill 0.2)
		(layers "F.Cu" "B.Cu")
		(remove_unused_layers yes)
		(keep_end_layers yes)
		(zone_layer_connections)
		(net 173)
	)
	(via
		(at 137.976 139.5)
		(size 0.45)
		(drill 0.2)
		(layers "F.Cu" "B.Cu")
		(remove_unused_layers yes)
		(keep_end_layers yes)
		(zone_layer_connections)
		(net 173)
	)
	(segment
		(start 134.402574 138.772574)
		(end 136.1 138.772574)
		(width 0.1)
		(layer "B.Cu")
		(net 173)
	)
	(segment
		(start 134 138.37)
		(end 134.402574 138.772574)
		(width 0.1)
		(layer "B.Cu")
		(net 173)
	)
	(segment
		(start 137.87 139.55)
		(end 136.877426 139.55)
		(width 0.1)
		(layer "B.Cu")
		(net 173)
	)
	(segment
		(start 136.877426 139.55)
		(end 136.1 138.772574)
		(width 0.1)
		(layer "B.Cu")
		(net 173)
	)
	(segment
		(start 125.97 129.238786)
		(end 125.97 129.52)
		(width 0.1)
		(layer "F.Cu")
		(net 174)
	)
	(segment
		(start 126.45 133)
		(end 126.575 132.875)
		(width 0.19)
		(layer "F.Cu")
		(net 174)
	)
	(segment
		(start 125.97 129.695)
		(end 125.97 129.52)
		(width 0.19)
		(layer "F.Cu")
		(net 174)
	)
	(segment
		(start 126.085 128.665)
		(end 126.2 128.55)
		(width 0.1)
		(layer "F.Cu")
		(net 174)
	)
	(segment
		(start 125.97 128.942634)
		(end 125.97 129.238786)
		(width 0.1)
		(layer "F.Cu")
		(net 174)
	)
	(segment
		(start 126.025 129.75)
		(end 125.97 129.695)
		(width 0.19)
		(layer "F.Cu")
		(net 174)
	)
	(segment
		(start 126.575 132.875)
		(end 126.575 132.122488)
		(width 0.19)
		(layer "F.Cu")
		(net 174)
	)
	(segment
		(start 126.575 132.122488)
		(end 126.025 131.572488)
		(width 0.19)
		(layer "F.Cu")
		(net 174)
	)
	(segment
		(start 126.025 131.572488)
		(end 126.025 129.75)
		(width 0.19)
		(layer "F.Cu")
		(net 174)
	)
	(via
		(at 126.45 133)
		(size 0.45)
		(drill 0.2)
		(layers "F.Cu" "B.Cu")
		(remove_unused_layers yes)
		(keep_end_layers yes)
		(zone_layer_connections)
		(net 174)
	)
	(arc
		(start 126.085 128.665)
		(mid 125.999888 128.792379)
		(end 125.97 128.942634)
		(width 0.1)
		(layer "F.Cu")
		(net 174)
	)
	(segment
		(start 126.575 133.125)
		(end 126.45 133)
		(width 0.19)
		(layer "B.Cu")
		(net 174)
	)
	(segment
		(start 126.25 134.27)
		(end 126.25 134.245)
		(width 0.19)
		(layer "B.Cu")
		(net 174)
	)
	(segment
		(start 126.575 133.92)
		(end 126.575 133.125)
		(width 0.19)
		(layer "B.Cu")
		(net 174)
	)
	(segment
		(start 126.25 134.245)
		(end 126.575 133.92)
		(width 0.19)
		(layer "B.Cu")
		(net 174)
	)
	(segment
		(start 137.9 134.5)
		(end 138.11 134.29)
		(width 0.1)
		(layer "F.Cu")
		(net 175)
	)
	(segment
		(start 137.5 134.5)
		(end 137.9 134.5)
		(width 0.1)
		(layer "F.Cu")
		(net 175)
	)
	(via
		(at 138.11 134.29)
		(size 0.45)
		(drill 0.2)
		(layers "F.Cu" "B.Cu")
		(remove_unused_layers yes)
		(keep_end_layers yes)
		(zone_layer_connections)
		(net 175)
	)
	(segment
		(start 135.5 134)
		(end 135.5 133.56)
		(width 0.1)
		(layer "F.Cu")
		(net 176)
	)
	(segment
		(start 135.5 133.56)
		(end 135.56 133.5)
		(width 0.1)
		(layer "F.Cu")
		(net 176)
	)
	(via
		(at 135.56 133.5)
		(size 0.45)
		(drill 0.2)
		(layers "F.Cu" "B.Cu")
		(remove_unused_layers yes)
		(keep_end_layers yes)
		(zone_layer_connections)
		(net 176)
	)
	(segment
		(start 126.86926 124.91926)
		(end 126.55 124.6)
		(width 0.1)
		(layer "F.Cu")
		(net 177)
	)
	(segment
		(start 126.86926 125.58074)
		(end 126.86926 124.91926)
		(width 0.1)
		(layer "F.Cu")
		(net 177)
	)
	(via
		(at 126.86926 125.58074)
		(size 0.45)
		(drill 0.2)
		(layers "F.Cu" "B.Cu")
		(remove_unused_layers yes)
		(keep_end_layers yes)
		(zone_layer_connections)
		(net 177)
	)
	(segment
		(start 126.86926 125.58074)
		(end 127.36426 125.58074)
		(width 0.25)
		(layer "B.Cu")
		(net 177)
	)
	(segment
		(start 127.36426 125.58074)
		(end 127.519999 125.425001)
		(width 0.25)
		(layer "B.Cu")
		(net 177)
	)
	(segment
		(start 126.55 125.25)
		(end 126.225 125.575)
		(width 0.1)
		(layer "F.Cu")
		(net 178)
	)
	(via
		(at 126.225 125.575)
		(size 0.45)
		(drill 0.2)
		(layers "F.Cu" "B.Cu")
		(remove_unused_layers yes)
		(keep_end_layers yes)
		(zone_layer_connections)
		(net 178)
	)
	(segment
		(start 125.704997 125.575)
		(end 125.554998 125.425001)
		(width 0.25)
		(layer "B.Cu")
		(net 178)
	)
	(segment
		(start 126.225 125.575)
		(end 125.704997 125.575)
		(width 0.25)
		(layer "B.Cu")
		(net 178)
	)
	(segment
		(start 131.1 122.65)
		(end 131.425 122.325)
		(width 0.1)
		(layer "F.Cu")
		(net 179)
	)
	(via
		(at 131.425 122.325)
		(size 0.45)
		(drill 0.2)
		(layers "F.Cu" "B.Cu")
		(remove_unused_layers yes)
		(keep_end_layers yes)
		(zone_layer_connections)
		(net 179)
	)
	(segment
		(start 129.15 125.9)
		(end 128.825 126.225)
		(width 0.1)
		(layer "F.Cu")
		(net 180)
	)
	(segment
		(start 129.15 125.9)
		(end 129.15 125.25)
		(width 0.1)
		(layer "F.Cu")
		(net 180)
	)
	(segment
		(start 125.9 125.9)
		(end 125.575 126.225)
		(width 0.1)
		(layer "F.Cu")
		(net 180)
	)
	(segment
		(start 125.575 126.225)
		(end 125.9 126.55)
		(width 0.1)
		(layer "F.Cu")
		(net 180)
	)
	(via
		(at 129 129.55)
		(size 0.45)
		(drill 0.2)
		(layers "F.Cu" "B.Cu")
		(remove_unused_layers yes)
		(keep_end_layers yes)
		(zone_layer_connections "In3.Cu")
		(net 180)
	)
	(via
		(at 125.575 126.225)
		(size 0.45)
		(drill 0.2)
		(layers "F.Cu" "B.Cu")
		(remove_unused_layers yes)
		(keep_end_layers yes)
		(zone_layer_connections "In3.Cu")
		(net 180)
	)
	(via
		(at 128.825 126.225)
		(size 0.45)
		(drill 0.2)
		(layers "F.Cu" "B.Cu")
		(remove_unused_layers yes)
		(keep_end_layers yes)
		(zone_layer_connections "In3.Cu")
		(net 180)
	)
	(segment
		(start 127.85 122.65)
		(end 127.525 122.325)
		(width 0.1)
		(layer "F.Cu")
		(net 181)
	)
	(via
		(at 127.525 122.325)
		(size 0.45)
		(drill 0.2)
		(layers "F.Cu" "B.Cu")
		(remove_unused_layers yes)
		(keep_end_layers yes)
		(zone_layer_connections)
		(net 181)
	)
	(via
		(at 127.525 117.65)
		(size 0.45)
		(drill 0.2)
		(layers "F.Cu" "B.Cu")
		(remove_unused_layers yes)
		(keep_end_layers yes)
		(zone_layer_connections)
		(net 181)
	)
	(segment
		(start 127.529999 116.655001)
		(end 126.544997 116.655001)
		(width 0.25)
		(layer "B.Cu")
		(net 181)
	)
	(segment
		(start 126.544997 116.655001)
		(end 126.309999 116.889999)
		(width 0.25)
		(layer "B.Cu")
		(net 181)
	)
	(segment
		(start 127.529997 116.655003)
		(end 127.529999 116.655001)
		(width 0.25)
		(layer "B.Cu")
		(net 181)
	)
	(segment
		(start 127.529997 117.629999)
		(end 127.529997 116.655003)
		(width 0.25)
		(layer "B.Cu")
		(net 181)
	)
	(segment
		(start 127.525 122.325)
		(end 127.525 117.65)
		(width 0.5)
		(layer "In2.Cu")
		(net 181)
	)
	(segment
		(start 133.5 138.5)
		(end 133.5 139.89)
		(width 0.25)
		(layer "F.Cu")
		(net 182)
	)
	(segment
		(start 134 139)
		(end 134 139.82)
		(width 0.25)
		(layer "F.Cu")
		(net 182)
	)
	(segment
		(start 133 139)
		(end 133 139.92)
		(width 0.25)
		(layer "F.Cu")
		(net 182)
	)
	(segment
		(start 126.55 123.3)
		(end 126.875 122.975)
		(width 0.1)
		(layer "F.Cu")
		(net 183)
	)
	(via
		(at 126.875 122.975)
		(size 0.45)
		(drill 0.2)
		(layers "F.Cu" "B.Cu")
		(remove_unused_layers yes)
		(keep_end_layers yes)
		(zone_layer_connections)
		(net 183)
	)
	(via
		(at 126.225 120.375)
		(size 0.45)
		(drill 0.2)
		(layers "F.Cu" "B.Cu")
		(remove_unused_layers yes)
		(keep_end_layers yes)
		(zone_layer_connections)
		(net 183)
	)
	(segment
		(start 125.8 122.2)
		(end 125.8 122.6)
		(width 0.1)
		(layer "In3.Cu")
		(net 183)
	)
	(segment
		(start 126.175 122.975)
		(end 126.875 122.975)
		(width 0.1)
		(layer "In3.Cu")
		(net 183)
	)
	(segment
		(start 125.8 122.6)
		(end 126.175 122.975)
		(width 0.1)
		(layer "In3.Cu")
		(net 183)
	)
	(segment
		(start 126.225 120.375)
		(end 126.225 121.775)
		(width 0.1)
		(layer "In3.Cu")
		(net 183)
	)
	(segment
		(start 126.225 121.775)
		(end 125.8 122.2)
		(width 0.1)
		(layer "In3.Cu")
		(net 183)
	)
	(segment
		(start 134.65 123.35)
		(end 135.175 122.825)
		(width 0.1)
		(layer "F.Cu")
		(net 184)
	)
	(segment
		(start 135.35 122.1)
		(end 135.35 121.25)
		(width 0.1)
		(layer "F.Cu")
		(net 184)
	)
	(segment
		(start 135.175 122.275)
		(end 135.35 122.1)
		(width 0.1)
		(layer "F.Cu")
		(net 184)
	)
	(segment
		(start 134.65 125.55)
		(end 134.65 123.35)
		(width 0.1)
		(layer "F.Cu")
		(net 184)
	)
	(segment
		(start 135.175 122.825)
		(end 135.175 122.275)
		(width 0.1)
		(layer "F.Cu")
		(net 184)
	)
	(segment
		(start 135.35 121.25)
		(end 136 120.6)
		(width 0.1)
		(layer "F.Cu")
		(net 184)
	)
	(segment
		(start 136 120.6)
		(end 136 120.15)
		(width 0.1)
		(layer "F.Cu")
		(net 184)
	)
	(segment
		(start 133.95 126.25)
		(end 134.65 125.55)
		(width 0.1)
		(layer "F.Cu")
		(net 184)
	)
	(segment
		(start 133.56 126.25)
		(end 133.95 126.25)
		(width 0.1)
		(layer "F.Cu")
		(net 184)
	)
	(via
		(at 136 120.15)
		(size 0.45)
		(drill 0.2)
		(layers "F.Cu" "B.Cu")
		(remove_unused_layers yes)
		(keep_end_layers yes)
		(zone_layer_connections)
		(net 184)
	)
	(segment
		(start 131.1 123.3)
		(end 131.425 122.975)
		(width 0.1)
		(layer "F.Cu")
		(net 185)
	)
	(segment
		(start 131.425 122.975)
		(end 132.075 122.975)
		(width 0.1)
		(layer "F.Cu")
		(net 185)
	)
	(via
		(at 132.075 122.975)
		(size 0.45)
		(drill 0.2)
		(layers "F.Cu" "B.Cu")
		(remove_unused_layers yes)
		(keep_end_layers yes)
		(zone_layer_connections)
		(net 185)
	)
	(segment
		(start 131.2574 114.9426)
		(end 133.27 114.9426)
		(width 0.1)
		(layer "B.Cu")
		(net 185)
	)
	(segment
		(start 130.9 115.3)
		(end 131.2574 114.9426)
		(width 0.1)
		(layer "B.Cu")
		(net 185)
	)
	(segment
		(start 133.2 119.824264)
		(end 130.9 117.524264)
		(width 0.1)
		(layer "B.Cu")
		(net 185)
	)
	(segment
		(start 133.2 122.6)
		(end 133.2 119.824264)
		(width 0.1)
		(layer "B.Cu")
		(net 185)
	)
	(segment
		(start 130.9 117.524264)
		(end 130.9 115.3)
		(width 0.1)
		(layer "B.Cu")
		(net 185)
	)
	(segment
		(start 132.825 122.975)
		(end 133.2 122.6)
		(width 0.1)
		(layer "B.Cu")
		(net 185)
	)
	(segment
		(start 132.075 122.975)
		(end 132.825 122.975)
		(width 0.1)
		(layer "B.Cu")
		(net 185)
	)
	(segment
		(start 134.14515 120.9611)
		(end 133.3289 120.9611)
		(width 0.1)
		(layer "F.Cu")
		(net 186)
	)
	(segment
		(start 136 118.2)
		(end 135.55 118.65)
		(width 0.1)
		(layer "F.Cu")
		(net 186)
	)
	(segment
		(start 135.55 118.65)
		(end 135.55 119.55625)
		(width 0.1)
		(layer "F.Cu")
		(net 186)
	)
	(segment
		(start 135.55 119.55625)
		(end 134.14515 120.9611)
		(width 0.1)
		(layer "F.Cu")
		(net 186)
	)
	(segment
		(start 133.3289 120.9611)
		(end 133.1 121.19)
		(width 0.1)
		(layer "F.Cu")
		(net 186)
	)
	(via
		(at 136 118.2)
		(size 0.45)
		(drill 0.2)
		(layers "F.Cu" "B.Cu")
		(remove_unused_layers yes)
		(keep_end_layers yes)
		(zone_layer_connections)
		(net 186)
	)
	(segment
		(start 135.3 119.5)
		(end 135.3 118.3)
		(width 0.1)
		(layer "F.Cu")
		(net 187)
	)
	(segment
		(start 134.07 120.73)
		(end 135.3 119.5)
		(width 0.1)
		(layer "F.Cu")
		(net 187)
	)
	(segment
		(start 137.35 117.75)
		(end 137.95 117.15)
		(width 0.1)
		(layer "F.Cu")
		(net 187)
	)
	(segment
		(start 133.56 120.73)
		(end 134.07 120.73)
		(width 0.1)
		(layer "F.Cu")
		(net 187)
	)
	(segment
		(start 135.3 118.3)
		(end 135.85 117.75)
		(width 0.1)
		(layer "F.Cu")
		(net 187)
	)
	(segment
		(start 135.85 117.75)
		(end 137.35 117.75)
		(width 0.1)
		(layer "F.Cu")
		(net 187)
	)
	(via
		(at 137.95 117.15)
		(size 0.45)
		(drill 0.2)
		(layers "F.Cu" "B.Cu")
		(remove_unused_layers yes)
		(keep_end_layers yes)
		(zone_layer_connections)
		(net 187)
	)
	(segment
		(start 133.9989 120.5011)
		(end 133.3289 120.5011)
		(width 0.1)
		(layer "F.Cu")
		(net 188)
	)
	(segment
		(start 136.025 117.3)
		(end 135.875 117.3)
		(width 0.1)
		(layer "F.Cu")
		(net 188)
	)
	(segment
		(start 135.875 117.3)
		(end 135.1 118.075)
		(width 0.1)
		(layer "F.Cu")
		(net 188)
	)
	(segment
		(start 133.3289 120.5011)
		(end 133.1 120.73)
		(width 0.1)
		(layer "F.Cu")
		(net 188)
	)
	(segment
		(start 135.1 119.4)
		(end 133.9989 120.5011)
		(width 0.1)
		(layer "F.Cu")
		(net 188)
	)
	(segment
		(start 135.1 118.075)
		(end 135.1 119.4)
		(width 0.1)
		(layer "F.Cu")
		(net 188)
	)
	(via
		(at 136.025 117.3)
		(size 0.45)
		(drill 0.2)
		(layers "F.Cu" "B.Cu")
		(remove_unused_layers yes)
		(keep_end_layers yes)
		(zone_layer_connections)
		(net 188)
	)
	(segment
		(start 134.85 118)
		(end 135.525 117.325)
		(width 0.1)
		(layer "F.Cu")
		(net 189)
	)
	(segment
		(start 133.56 120.27)
		(end 133.93 120.27)
		(width 0.1)
		(layer "F.Cu")
		(net 189)
	)
	(segment
		(start 135.95 116.625)
		(end 137.475 116.625)
		(width 0.1)
		(layer "F.Cu")
		(net 189)
	)
	(segment
		(start 134.85 119.35)
		(end 134.85 118)
		(width 0.1)
		(layer "F.Cu")
		(net 189)
	)
	(segment
		(start 135.525 117.05)
		(end 135.95 116.625)
		(width 0.1)
		(layer "F.Cu")
		(net 189)
	)
	(segment
		(start 133.93 120.27)
		(end 134.85 119.35)
		(width 0.1)
		(layer "F.Cu")
		(net 189)
	)
	(segment
		(start 137.475 116.625)
		(end 137.975 116.125)
		(width 0.1)
		(layer "F.Cu")
		(net 189)
	)
	(segment
		(start 135.525 117.325)
		(end 135.525 117.05)
		(width 0.1)
		(layer "F.Cu")
		(net 189)
	)
	(via
		(at 137.975 116.125)
		(size 0.45)
		(drill 0.2)
		(layers "F.Cu" "B.Cu")
		(remove_unused_layers yes)
		(keep_end_layers yes)
		(zone_layer_connections)
		(net 189)
	)
	(segment
		(start 135.25 115.1)
		(end 134.65 115.1)
		(width 0.1)
		(layer "F.Cu")
		(net 190)
	)
	(segment
		(start 134.55 119.365684)
		(end 133.874584 120.0411)
		(width 0.1)
		(layer "F.Cu")
		(net 190)
	)
	(segment
		(start 134.35 117.65)
		(end 134.55 117.85)
		(width 0.1)
		(layer "F.Cu")
		(net 190)
	)
	(segment
		(start 135.8 116)
		(end 135.4 115.6)
		(width 0.1)
		(layer "F.Cu")
		(net 190)
	)
	(segment
		(start 134.35 115.4)
		(end 134.35 117.65)
		(width 0.1)
		(layer "F.Cu")
		(net 190)
	)
	(segment
		(start 134.65 115.1)
		(end 134.35 115.4)
		(width 0.1)
		(layer "F.Cu")
		(net 190)
	)
	(segment
		(start 134.55 117.85)
		(end 134.55 119.365684)
		(width 0.1)
		(layer "F.Cu")
		(net 190)
	)
	(segment
		(start 136.2 116)
		(end 135.8 116)
		(width 0.1)
		(layer "F.Cu")
		(net 190)
	)
	(segment
		(start 133.874584 120.0411)
		(end 133.3289 120.0411)
		(width 0.1)
		(layer "F.Cu")
		(net 190)
	)
	(segment
		(start 135.4 115.6)
		(end 135.4 115.25)
		(width 0.1)
		(layer "F.Cu")
		(net 190)
	)
	(segment
		(start 133.3289 120.0411)
		(end 133.1 120.27)
		(width 0.1)
		(layer "F.Cu")
		(net 190)
	)
	(segment
		(start 135.4 115.25)
		(end 135.25 115.1)
		(width 0.1)
		(layer "F.Cu")
		(net 190)
	)
	(via
		(at 136.2 116)
		(size 0.45)
		(drill 0.2)
		(layers "F.Cu" "B.Cu")
		(remove_unused_layers yes)
		(keep_end_layers yes)
		(zone_layer_connections)
		(net 190)
	)
	(segment
		(start 135.75 115.6)
		(end 137.45 115.6)
		(width 0.1)
		(layer "F.Cu")
		(net 191)
	)
	(segment
		(start 134.15 117.75)
		(end 134.15 115)
		(width 0.1)
		(layer "F.Cu")
		(net 191)
	)
	(segment
		(start 137.45 115.6)
		(end 137.95 115.1)
		(width 0.1)
		(layer "F.Cu")
		(net 191)
	)
	(segment
		(start 133.822842 119.81)
		(end 134.25 119.382842)
		(width 0.1)
		(layer "F.Cu")
		(net 191)
	)
	(segment
		(start 135.3 114.7)
		(end 135.65 115.05)
		(width 0.1)
		(layer "F.Cu")
		(net 191)
	)
	(segment
		(start 134.15 115)
		(end 134.45 114.7)
		(width 0.1)
		(layer "F.Cu")
		(net 191)
	)
	(segment
		(start 135.65 115.5)
		(end 135.75 115.6)
		(width 0.1)
		(layer "F.Cu")
		(net 191)
	)
	(segment
		(start 135.65 115.05)
		(end 135.65 115.5)
		(width 0.1)
		(layer "F.Cu")
		(net 191)
	)
	(segment
		(start 134.25 119.382842)
		(end 134.25 117.85)
		(width 0.1)
		(layer "F.Cu")
		(net 191)
	)
	(segment
		(start 134.25 117.85)
		(end 134.15 117.75)
		(width 0.1)
		(layer "F.Cu")
		(net 191)
	)
	(segment
		(start 133.56 119.81)
		(end 133.822842 119.81)
		(width 0.1)
		(layer "F.Cu")
		(net 191)
	)
	(segment
		(start 134.45 114.7)
		(end 135.3 114.7)
		(width 0.1)
		(layer "F.Cu")
		(net 191)
	)
	(via
		(at 137.95 115.1)
		(size 0.45)
		(drill 0.2)
		(layers "F.Cu" "B.Cu")
		(remove_unused_layers yes)
		(keep_end_layers yes)
		(zone_layer_connections)
		(net 191)
	)
	(segment
		(start 134.2089 126.9411)
		(end 135.4 125.75)
		(width 0.1)
		(layer "F.Cu")
		(net 192)
	)
	(segment
		(start 135.4 125.75)
		(end 135.4 123.75)
		(width 0.1)
		(layer "F.Cu")
		(net 192)
	)
	(segment
		(start 133.1 127.17)
		(end 133.3289 126.9411)
		(width 0.1)
		(layer "F.Cu")
		(net 192)
	)
	(segment
		(start 135.4 123.75)
		(end 136 123.15)
		(width 0.1)
		(layer "F.Cu")
		(net 192)
	)
	(segment
		(start 133.3289 126.9411)
		(end 134.2089 126.9411)
		(width 0.1)
		(layer "F.Cu")
		(net 192)
	)
	(via
		(at 136 123.15)
		(size 0.45)
		(drill 0.2)
		(layers "F.Cu" "B.Cu")
		(remove_unused_layers yes)
		(keep_end_layers yes)
		(zone_layer_connections)
		(net 192)
	)
	(via
		(at 132.625 127.85)
		(size 0.45)
		(drill 0.2)
		(layers "F.Cu" "B.Cu")
		(remove_unused_layers yes)
		(keep_end_layers yes)
		(zone_layer_connections)
		(net 193)
	)
	(segment
		(start 132.625 127.85)
		(end 134.375 126.1)
		(width 0.1)
		(layer "B.Cu")
		(net 193)
	)
	(segment
		(start 134.375 126.1)
		(end 136.52 126.1)
		(width 0.1)
		(layer "B.Cu")
		(net 193)
	)
	(segment
		(start 136.52 126.1)
		(end 137.02 126.6)
		(width 0.1)
		(layer "B.Cu")
		(net 193)
	)
	(via
		(at 132.625 125.9)
		(size 0.45)
		(drill 0.2)
		(layers "F.Cu" "B.Cu")
		(remove_unused_layers yes)
		(keep_end_layers yes)
		(zone_layer_connections)
		(net 194)
	)
	(segment
		(start 137.5 126.15)
		(end 137.5 127.12)
		(width 0.1)
		(layer "B.Cu")
		(net 194)
	)
	(segment
		(start 137.5 127.12)
		(end 137.02 127.6)
		(width 0.1)
		(layer "B.Cu")
		(net 194)
	)
	(segment
		(start 132.625 125.9)
		(end 137.25 125.9)
		(width 0.1)
		(layer "B.Cu")
		(net 194)
	)
	(segment
		(start 137.25 125.9)
		(end 137.5 126.15)
		(width 0.1)
		(layer "B.Cu")
		(net 194)
	)
	(segment
		(start 117.4 115.1)
		(end 117.6 114.9)
		(width 0.1)
		(layer "F.Cu")
		(net 195)
	)
	(segment
		(start 116.2 115.1)
		(end 117.4 115.1)
		(width 0.1)
		(layer "F.Cu")
		(net 195)
	)
	(segment
		(start 119.52 94.75)
		(end 118.75 94.75)
		(width 0.1)
		(layer "B.Cu")
		(net 196)
	)
	(segment
		(start 117.5 93.5)
		(end 117.5 92.18)
		(width 0.1)
		(layer "B.Cu")
		(net 196)
	)
	(segment
		(start 119.52 93.759)
		(end 120.152 93.127)
		(width 0.1)
		(layer "B.Cu")
		(net 196)
	)
	(segment
		(start 118.75 94.75)
		(end 117.5 93.5)
		(width 0.1)
		(layer "B.Cu")
		(net 196)
	)
	(segment
		(start 119.52 94.75)
		(end 119.52 93.759)
		(width 0.1)
		(layer "B.Cu")
		(net 196)
	)
	(segment
		(start 139.98 145.5)
		(end 140.8 145.5)
		(width 0.1)
		(layer "F.Cu")
		(net 197)
	)
	(via
		(at 116.1 92.2)
		(size 0.45)
		(drill 0.2)
		(layers "F.Cu" "B.Cu")
		(remove_unused_layers yes)
		(keep_end_layers yes)
		(zone_layer_connections)
		(net 197)
	)
	(via
		(at 140.8 145.5)
		(size 0.45)
		(drill 0.2)
		(layers "F.Cu" "B.Cu")
		(remove_unused_layers yes)
		(keep_end_layers yes)
		(zone_layer_connections)
		(net 197)
	)
	(segment
		(start 116.1 92.2)
		(end 116.6 91.7)
		(width 0.1)
		(layer "B.Cu")
		(net 197)
	)
	(segment
		(start 119.075 91.7)
		(end 119.5 91.275)
		(width 0.1)
		(layer "B.Cu")
		(net 197)
	)
	(segment
		(start 116.6 91.7)
		(end 119.075 91.7)
		(width 0.1)
		(layer "B.Cu")
		(net 197)
	)
	(segment
		(start 116.3 103.6)
		(end 117.5 104.8)
		(width 0.1)
		(layer "In3.Cu")
		(net 197)
	)
	(segment
		(start 115.6 92.7)
		(end 115.6 102)
		(width 0.1)
		(layer "In3.Cu")
		(net 197)
	)
	(segment
		(start 133.5 138.3)
		(end 133.5 141.8)
		(width 0.1)
		(layer "In3.Cu")
		(net 197)
	)
	(segment
		(start 133.5 141.8)
		(end 137.2 145.5)
		(width 0.1)
		(layer "In3.Cu")
		(net 197)
	)
	(segment
		(start 121.8 127.2)
		(end 123.4 128.8)
		(width 0.1)
		(layer "In3.Cu")
		(net 197)
	)
	(segment
		(start 128.8 133.6)
		(end 133.5 138.3)
		(width 0.1)
		(layer "In3.Cu")
		(net 197)
	)
	(segment
		(start 117.5 104.8)
		(end 118.4 104.8)
		(width 0.1)
		(layer "In3.Cu")
		(net 197)
	)
	(segment
		(start 118.4 104.8)
		(end 121.8 108.2)
		(width 0.1)
		(layer "In3.Cu")
		(net 197)
	)
	(segment
		(start 137.2 145.5)
		(end 140.8 145.5)
		(width 0.1)
		(layer "In3.Cu")
		(net 197)
	)
	(segment
		(start 128.8 132)
		(end 128.8 133.6)
		(width 0.1)
		(layer "In3.Cu")
		(net 197)
	)
	(segment
		(start 116.3 102.7)
		(end 116.3 103.6)
		(width 0.1)
		(layer "In3.Cu")
		(net 197)
	)
	(segment
		(start 125.6 128.8)
		(end 128.8 132)
		(width 0.1)
		(layer "In3.Cu")
		(net 197)
	)
	(segment
		(start 116.1 92.2)
		(end 115.6 92.7)
		(width 0.1)
		(layer "In3.Cu")
		(net 197)
	)
	(segment
		(start 123.4 128.8)
		(end 125.6 128.8)
		(width 0.1)
		(layer "In3.Cu")
		(net 197)
	)
	(segment
		(start 115.6 102)
		(end 116.3 102.7)
		(width 0.1)
		(layer "In3.Cu")
		(net 197)
	)
	(segment
		(start 121.8 108.2)
		(end 121.8 127.2)
		(width 0.1)
		(layer "In3.Cu")
		(net 197)
	)
	(segment
		(start 138.25 136)
		(end 138.85 136.6)
		(width 0.1)
		(layer "F.Cu")
		(net 198)
	)
	(segment
		(start 137.5 136)
		(end 138.25 136)
		(width 0.1)
		(layer "F.Cu")
		(net 198)
	)
	(segment
		(start 138.85 136.6)
		(end 139.95 136.6)
		(width 0.1)
		(layer "F.Cu")
		(net 198)
	)
	(via
		(at 139.95 136.6)
		(size 0.45)
		(drill 0.2)
		(layers "F.Cu" "B.Cu")
		(remove_unused_layers yes)
		(keep_end_layers yes)
		(zone_layer_connections)
		(net 198)
	)
	(segment
		(start 139.92 136.580998)
		(end 139.930998 136.580998)
		(width 0.25)
		(layer "B.Cu")
		(net 198)
	)
	(segment
		(start 139.930998 136.580998)
		(end 139.95 136.6)
		(width 0.25)
		(layer "B.Cu")
		(net 198)
	)
	(segment
		(start 139.65 136.05)
		(end 138.885 136.05)
		(width 0.1)
		(layer "F.Cu")
		(net 199)
	)
	(segment
		(start 139.9 135.8)
		(end 139.65 136.05)
		(width 0.1)
		(layer "F.Cu")
		(net 199)
	)
	(segment
		(start 139.9 135.6)
		(end 139.9 135.8)
		(width 0.1)
		(layer "F.Cu")
		(net 199)
	)
	(segment
		(start 138.885 136.05)
		(end 138.6 135.765)
		(width 0.1)
		(layer "F.Cu")
		(net 199)
	)
	(segment
		(start 137 136)
		(end 137.235 135.765)
		(width 0.1)
		(layer "F.Cu")
		(net 199)
	)
	(segment
		(start 137.235 135.765)
		(end 138.6 135.765)
		(width 0.1)
		(layer "F.Cu")
		(net 199)
	)
	(via
		(at 139.9 135.6)
		(size 0.45)
		(drill 0.2)
		(layers "F.Cu" "B.Cu")
		(remove_unused_layers yes)
		(keep_end_layers yes)
		(zone_layer_connections)
		(net 199)
	)
	(segment
		(start 137 136.5)
		(end 137.25 136.25)
		(width 0.1)
		(layer "F.Cu")
		(net 200)
	)
	(segment
		(start 138.75 137.05)
		(end 139.35 137.05)
		(width 0.1)
		(layer "F.Cu")
		(net 200)
	)
	(segment
		(start 137.95 136.25)
		(end 138.75 137.05)
		(width 0.1)
		(layer "F.Cu")
		(net 200)
	)
	(segment
		(start 139.35 137.05)
		(end 139.9 137.6)
		(width 0.1)
		(layer "F.Cu")
		(net 200)
	)
	(segment
		(start 137.25 136.25)
		(end 137.95 136.25)
		(width 0.1)
		(layer "F.Cu")
		(net 200)
	)
	(via
		(at 139.9 137.6)
		(size 0.45)
		(drill 0.2)
		(layers "F.Cu" "B.Cu")
		(remove_unused_layers yes)
		(keep_end_layers yes)
		(zone_layer_connections)
		(net 200)
	)
	(segment
		(start 139.919999 137.580998)
		(end 139.919002 137.580998)
		(width 0.25)
		(layer "B.Cu")
		(net 200)
	)
	(segment
		(start 139.919002 137.580998)
		(end 139.9 137.6)
		(width 0.25)
		(layer "B.Cu")
		(net 200)
	)
	(via
		(at 136.95 134.45)
		(size 0.45)
		(drill 0.2)
		(layers "F.Cu" "B.Cu")
		(remove_unused_layers yes)
		(keep_end_layers yes)
		(zone_layer_connections)
		(net 201)
	)
	(segment
		(start 136.95 134.45)
		(end 137.35 134.05)
		(width 0.1)
		(layer "B.Cu")
		(net 201)
	)
	(segment
		(start 137.35 134.05)
		(end 137.35 133.08)
		(width 0.1)
		(layer "B.Cu")
		(net 201)
	)
	(segment
		(start 137.35 133.08)
		(end 137.830001 132.599999)
		(width 0.1)
		(layer "B.Cu")
		(net 201)
	)
	(segment
		(start 139.4 139.1)
		(end 139.47 139.1)
		(width 0.1)
		(layer "F.Cu")
		(net 202)
	)
	(segment
		(start 139.47 139.1)
		(end 139.92 139.55)
		(width 0.1)
		(layer "F.Cu")
		(net 202)
	)
	(via
		(at 136.58 138.28)
		(size 0.45)
		(drill 0.2)
		(layers "F.Cu" "B.Cu")
		(remove_unused_layers yes)
		(keep_end_layers yes)
		(zone_layer_connections)
		(net 202)
	)
	(via
		(at 139.4 139.1)
		(size 0.45)
		(drill 0.2)
		(layers "F.Cu" "B.Cu")
		(remove_unused_layers yes)
		(keep_end_layers yes)
		(zone_layer_connections)
		(net 202)
	)
	(segment
		(start 137.35 139.05)
		(end 139.35 139.05)
		(width 0.1)
		(layer "B.Cu")
		(net 202)
	)
	(segment
		(start 136.58 138.28)
		(end 137.35 139.05)
		(width 0.1)
		(layer "B.Cu")
		(net 202)
	)
	(segment
		(start 139.35 139.05)
		(end 139.4 139.1)
		(width 0.1)
		(layer "B.Cu")
		(net 202)
	)
	(segment
		(start 134.5 138.5)
		(end 134.735 138.735)
		(width 0.1)
		(layer "F.Cu")
		(net 203)
	)
	(segment
		(start 134.735 138.735)
		(end 134.735 140.385)
		(width 0.1)
		(layer "F.Cu")
		(net 203)
	)
	(segment
		(start 134.735 140.385)
		(end 134.75 140.4)
		(width 0.1)
		(layer "F.Cu")
		(net 203)
	)
	(via
		(at 134.75 140.4)
		(size 0.45)
		(drill 0.2)
		(layers "F.Cu" "B.Cu")
		(remove_unused_layers yes)
		(keep_end_layers yes)
		(zone_layer_connections)
		(net 203)
	)
	(segment
		(start 136.4 137)
		(end 136.5 137.1)
		(width 0.1)
		(layer "F.Cu")
		(net 204)
	)
	(segment
		(start 136 137)
		(end 136.4 137)
		(width 0.1)
		(layer "F.Cu")
		(net 204)
	)
	(via
		(at 136.5 137.1)
		(size 0.45)
		(drill 0.2)
		(layers "F.Cu" "B.Cu")
		(remove_unused_layers yes)
		(keep_end_layers yes)
		(zone_layer_connections)
		(net 204)
	)
	(segment
		(start 137.871932 138.558596)
		(end 137.358596 138.558596)
		(width 0.1)
		(layer "B.Cu")
		(net 204)
	)
	(segment
		(start 137 138.2)
		(end 137 137.6)
		(width 0.1)
		(layer "B.Cu")
		(net 204)
	)
	(segment
		(start 137.358596 138.558596)
		(end 137 138.2)
		(width 0.1)
		(layer "B.Cu")
		(net 204)
	)
	(segment
		(start 137 137.6)
		(end 136.5 137.1)
		(width 0.1)
		(layer "B.Cu")
		(net 204)
	)
	(segment
		(start 135.54 134.5)
		(end 135 134.5)
		(width 0.1)
		(layer "F.Cu")
		(net 205)
	)
	(segment
		(start 135.54 134.5)
		(end 135.5 134.5)
		(width 0.1)
		(layer "F.Cu")
		(net 205)
	)
	(segment
		(start 135 134.5)
		(end 135.5 134.5)
		(width 0.1)
		(layer "F.Cu")
		(net 205)
	)
	(via
		(at 135.54 134.5)
		(size 0.45)
		(drill 0.2)
		(layers "F.Cu" "B.Cu")
		(remove_unused_layers yes)
		(keep_end_layers yes)
		(zone_layer_connections)
		(net 205)
	)
	(segment
		(start 136 136)
		(end 136.4 136)
		(width 0.1)
		(layer "F.Cu")
		(net 206)
	)
	(segment
		(start 136.4 136)
		(end 136.5 135.9)
		(width 0.1)
		(layer "F.Cu")
		(net 206)
	)
	(via
		(at 136.5 135.9)
		(size 0.45)
		(drill 0.2)
		(layers "F.Cu" "B.Cu")
		(remove_unused_layers yes)
		(keep_end_layers yes)
		(zone_layer_connections)
		(net 206)
	)
	(segment
		(start 137.87 135.6)
		(end 136.8 135.6)
		(width 0.1)
		(layer "B.Cu")
		(net 206)
	)
	(segment
		(start 136.8 135.6)
		(end 136.5 135.9)
		(width 0.1)
		(layer "B.Cu")
		(net 206)
	)
	(segment
		(start 135.5 135.5)
		(end 136 135.5)
		(width 0.1)
		(layer "F.Cu")
		(net 207)
	)
	(segment
		(start 136 135.5)
		(end 136.5 135)
		(width 0.1)
		(layer "F.Cu")
		(net 207)
	)
	(via
		(at 136.5 135)
		(size 0.45)
		(drill 0.2)
		(layers "F.Cu" "B.Cu")
		(remove_unused_layers yes)
		(keep_end_layers yes)
		(zone_layer_connections)
		(net 207)
	)
	(segment
		(start 139.42 135.1)
		(end 139.92 134.6)
		(width 0.1)
		(layer "B.Cu")
		(net 207)
	)
	(segment
		(start 136.6 135.1)
		(end 139.42 135.1)
		(width 0.1)
		(layer "B.Cu")
		(net 207)
	)
	(segment
		(start 136.5 135)
		(end 136.6 135.1)
		(width 0.1)
		(layer "B.Cu")
		(net 207)
	)
	(segment
		(start 135.325 132.425)
		(end 135.525 132.225)
		(width 0.1)
		(layer "F.Cu")
		(net 208)
	)
	(segment
		(start 135 134)
		(end 135 133.075)
		(width 0.1)
		(layer "F.Cu")
		(net 208)
	)
	(segment
		(start 135.325 132.75)
		(end 135.325 132.425)
		(width 0.1)
		(layer "F.Cu")
		(net 208)
	)
	(segment
		(start 135 133.075)
		(end 135.325 132.75)
		(width 0.1)
		(layer "F.Cu")
		(net 208)
	)
	(segment
		(start 135.525 132.225)
		(end 137.25 132.225)
		(width 0.1)
		(layer "F.Cu")
		(net 208)
	)
	(segment
		(start 137.25 132.225)
		(end 137.55 131.925)
		(width 0.1)
		(layer "F.Cu")
		(net 208)
	)
	(via
		(at 137.55 131.925)
		(size 0.45)
		(drill 0.2)
		(layers "F.Cu" "B.Cu")
		(remove_unused_layers yes)
		(keep_end_layers yes)
		(zone_layer_connections)
		(net 208)
	)
	(segment
		(start 135.7 132.1)
		(end 137.375 132.1)
		(width 0.1)
		(layer "B.Cu")
		(net 208)
	)
	(segment
		(start 135.4 131.169996)
		(end 135.4 131.8)
		(width 0.1)
		(layer "B.Cu")
		(net 208)
	)
	(segment
		(start 135.4 131.8)
		(end 135.7 132.1)
		(width 0.1)
		(layer "B.Cu")
		(net 208)
	)
	(segment
		(start 134.850002 130.619998)
		(end 135.4 131.169996)
		(width 0.1)
		(layer "B.Cu")
		(net 208)
	)
	(segment
		(start 137.375 132.1)
		(end 137.55 131.925)
		(width 0.1)
		(layer "B.Cu")
		(net 208)
	)
	(segment
		(start 135.5 139.125)
		(end 135.88 139.505)
		(width 0.1)
		(layer "F.Cu")
		(net 209)
	)
	(segment
		(start 135.5 139)
		(end 135.5 139.125)
		(width 0.1)
		(layer "F.Cu")
		(net 209)
	)
	(via
		(at 135.88 139.505)
		(size 0.45)
		(drill 0.2)
		(layers "F.Cu" "B.Cu")
		(remove_unused_layers yes)
		(keep_end_layers yes)
		(zone_layer_connections)
		(net 209)
	)
	(segment
		(start 136 136.5)
		(end 136.5 136.5)
		(width 0.1)
		(layer "F.Cu")
		(net 210)
	)
	(via
		(at 136.5 136.5)
		(size 0.45)
		(drill 0.2)
		(layers "F.Cu" "B.Cu")
		(remove_unused_layers yes)
		(keep_end_layers yes)
		(zone_layer_connections)
		(net 210)
	)
	(segment
		(start 136.5 136.5)
		(end 137.770002 136.5)
		(width 0.1)
		(layer "B.Cu")
		(net 210)
	)
	(segment
		(start 137.770002 136.5)
		(end 137.870001 136.599999)
		(width 0.1)
		(layer "B.Cu")
		(net 210)
	)
	(segment
		(start 135.265 138.765)
		(end 135.265 139.515)
		(width 0.1)
		(layer "F.Cu")
		(net 211)
	)
	(segment
		(start 135 138.5)
		(end 135.265 138.765)
		(width 0.1)
		(layer "F.Cu")
		(net 211)
	)
	(segment
		(start 136.36 140.01)
		(end 136.75 140.4)
		(width 0.1)
		(layer "F.Cu")
		(net 211)
	)
	(segment
		(start 135.265 139.515)
		(end 135.76 140.01)
		(width 0.1)
		(layer "F.Cu")
		(net 211)
	)
	(segment
		(start 135.76 140.01)
		(end 136.36 140.01)
		(width 0.1)
		(layer "F.Cu")
		(net 211)
	)
	(via
		(at 136.75 140.4)
		(size 0.45)
		(drill 0.2)
		(layers "F.Cu" "B.Cu")
		(remove_unused_layers yes)
		(keep_end_layers yes)
		(zone_layer_connections)
		(net 211)
	)
	(segment
		(start 134.5 134.68)
		(end 134.61 134.79)
		(width 0.1)
		(layer "F.Cu")
		(net 212)
	)
	(segment
		(start 134.5 134.5)
		(end 134.5 134.68)
		(width 0.1)
		(layer "F.Cu")
		(net 212)
	)
	(via
		(at 134.61 134.79)
		(size 0.45)
		(drill 0.2)
		(layers "F.Cu" "B.Cu")
		(remove_unused_layers yes)
		(keep_end_layers yes)
		(zone_layer_connections)
		(net 212)
	)
	(segment
		(start 125.525 102.15)
		(end 125.525 103.277512)
		(width 0.19)
		(layer "F.Cu")
		(net 213)
	)
	(segment
		(start 125.525 103.277512)
		(end 125.735356 103.487868)
		(width 0.19)
		(layer "F.Cu")
		(net 213)
	)
	(segment
		(start 125.675 101.6)
		(end 125.675 102)
		(width 0.19)
		(layer "F.Cu")
		(net 213)
	)
	(segment
		(start 125.575 121.025)
		(end 125.25 121.35)
		(width 0.1)
		(layer "F.Cu")
		(net 213)
	)
	(segment
		(start 125.675 102)
		(end 125.525 102.15)
		(width 0.19)
		(layer "F.Cu")
		(net 213)
	)
	(segment
		(start 125.735356 103.487868)
		(end 125.912132 103.487868)
		(width 0.19)
		(layer "F.Cu")
		(net 213)
	)
	(via
		(at 125.912132 103.487868)
		(size 0.45)
		(drill 0.2)
		(layers "F.Cu" "B.Cu")
		(remove_unused_layers yes)
		(keep_end_layers yes)
		(zone_layer_connections)
		(net 213)
	)
	(via
		(at 125.575 121.025)
		(size 0.45)
		(drill 0.2)
		(layers "F.Cu" "B.Cu")
		(remove_unused_layers yes)
		(keep_end_layers yes)
		(zone_layer_connections)
		(net 213)
	)
	(segment
		(start 125.912132 103.664644)
		(end 125.912132 103.487868)
		(width 0.21)
		(layer "In5.Cu")
		(net 213)
	)
	(segment
		(start 130.073552 113.752014)
		(end 129.997649 113.676111)
		(width 0.21)
		(layer "In5.Cu")
		(net 213)
	)
	(segment
		(start 125.222488 121.175)
		(end 124.875 120.827512)
		(width 0.21)
		(layer "In5.Cu")
		(net 213)
	)
	(segment
		(start 132.575 105.527512)
		(end 130.872488 103.825)
		(width 0.21)
		(layer "In5.Cu")
		(net 213)
	)
	(segment
		(start 129.997649 113.449836)
		(end 130.054218 113.393269)
		(width 0.21)
		(layer "In5.Cu")
		(net 213)
	)
	(segment
		(start 130.872488 103.825)
		(end 126.072488 103.825)
		(width 0.21)
		(layer "In5.Cu")
		(net 213)
	)
	(segment
		(start 132.575 110.872488)
		(end 132.575 105.527512)
		(width 0.21)
		(layer "In5.Cu")
		(net 213)
	)
	(segment
		(start 126.072488 103.825)
		(end 125.912132 103.664644)
		(width 0.21)
		(layer "In5.Cu")
		(net 213)
	)
	(segment
		(start 124.875 120.827512)
		(end 124.875 118.572488)
		(width 0.21)
		(layer "In5.Cu")
		(net 213)
	)
	(segment
		(start 124.875 118.572488)
		(end 129.488533 113.958955)
		(width 0.21)
		(layer "In5.Cu")
		(net 213)
	)
	(segment
		(start 125.575 121.025)
		(end 125.425 121.175)
		(width 0.21)
		(layer "In5.Cu")
		(net 213)
	)
	(segment
		(start 129.714807 113.958955)
		(end 129.790709 114.034857)
		(width 0.21)
		(layer "In5.Cu")
		(net 213)
	)
	(segment
		(start 132.402375 111.045113)
		(end 132.575 110.872488)
		(width 0.21)
		(layer "In5.Cu")
		(net 213)
	)
	(segment
		(start 130.016984 114.034857)
		(end 130.073552 113.978288)
		(width 0.21)
		(layer "In5.Cu")
		(net 213)
	)
	(segment
		(start 125.425 121.175)
		(end 125.222488 121.175)
		(width 0.21)
		(layer "In5.Cu")
		(net 213)
	)
	(segment
		(start 130.054218 113.393269)
		(end 132.402375 111.045113)
		(width 0.21)
		(layer "In5.Cu")
		(net 213)
	)
	(arc
		(start 129.488533 113.958955)
		(mid 129.60167 113.912092)
		(end 129.714807 113.958955)
		(width 0.21)
		(layer "In5.Cu")
		(net 213)
	)
	(arc
		(start 129.790709 114.034857)
		(mid 129.903847 114.08172)
		(end 130.016984 114.034857)
		(width 0.21)
		(layer "In5.Cu")
		(net 213)
	)
	(arc
		(start 129.997649 113.676111)
		(mid 129.950785 113.562974)
		(end 129.997649 113.449836)
		(width 0.21)
		(layer "In5.Cu")
		(net 213)
	)
	(arc
		(start 130.073552 113.978288)
		(mid 130.120415 113.865151)
		(end 130.073552 113.752014)
		(width 0.21)
		(layer "In5.Cu")
		(net 213)
	)
	(segment
		(start 125.175 103.422488)
		(end 125.487868 103.735356)
		(width 0.19)
		(layer "F.Cu")
		(net 214)
	)
	(segment
		(start 125.487868 103.735356)
		(end 125.487868 103.912132)
		(width 0.19)
		(layer "F.Cu")
		(net 214)
	)
	(segment
		(start 125.575 121.675)
		(end 125.25 122)
		(width 0.1)
		(layer "F.Cu")
		(net 214)
	)
	(segment
		(start 125.025 101.6)
		(end 125.025 102)
		(width 0.19)
		(layer "F.Cu")
		(net 214)
	)
	(segment
		(start 125.175 102.15)
		(end 125.175 103.422488)
		(width 0.19)
		(layer "F.Cu")
		(net 214)
	)
	(segment
		(start 125.025 102)
		(end 125.175 102.15)
		(width 0.19)
		(layer "F.Cu")
		(net 214)
	)
	(via
		(at 125.487868 103.912132)
		(size 0.45)
		(drill 0.2)
		(layers "F.Cu" "B.Cu")
		(remove_unused_layers yes)
		(keep_end_layers yes)
		(zone_layer_connections)
		(net 214)
	)
	(via
		(at 125.575 121.675)
		(size 0.45)
		(drill 0.2)
		(layers "F.Cu" "B.Cu")
		(remove_unused_layers yes)
		(keep_end_layers yes)
		(zone_layer_connections)
		(net 214)
	)
	(segment
		(start 125.927512 104.175)
		(end 130.727512 104.175)
		(width 0.21)
		(layer "In5.Cu")
		(net 214)
	)
	(segment
		(start 125.487868 103.912132)
		(end 125.664644 103.912132)
		(width 0.21)
		(layer "In5.Cu")
		(net 214)
	)
	(segment
		(start 125.425 121.525)
		(end 125.575 121.675)
		(width 0.21)
		(layer "In5.Cu")
		(net 214)
	)
	(segment
		(start 125.077512 121.525)
		(end 125.425 121.525)
		(width 0.21)
		(layer "In5.Cu")
		(net 214)
	)
	(segment
		(start 132.225 110.727512)
		(end 124.525 118.427512)
		(width 0.21)
		(layer "In5.Cu")
		(net 214)
	)
	(segment
		(start 124.525 120.972488)
		(end 125.077512 121.525)
		(width 0.21)
		(layer "In5.Cu")
		(net 214)
	)
	(segment
		(start 124.525 118.427512)
		(end 124.525 120.972488)
		(width 0.21)
		(layer "In5.Cu")
		(net 214)
	)
	(segment
		(start 130.727512 104.175)
		(end 132.225 105.672488)
		(width 0.21)
		(layer "In5.Cu")
		(net 214)
	)
	(segment
		(start 125.664644 103.912132)
		(end 125.927512 104.175)
		(width 0.21)
		(layer "In5.Cu")
		(net 214)
	)
	(segment
		(start 132.225 105.672488)
		(end 132.225 110.727512)
		(width 0.21)
		(layer "In5.Cu")
		(net 214)
	)
	(segment
		(start 123.499 149.1)
		(end 123.499 149.549)
		(width 0.25)
		(layer "F.Cu")
		(net 215)
	)
	(segment
		(start 123.499 149.549)
		(end 123.5 149.55)
		(width 0.25)
		(layer "F.Cu")
		(net 215)
	)
	(segment
		(start 118.497 144.124)
		(end 118.497 143.197)
		(width 0.1)
		(layer "F.Cu")
		(net 215)
	)
	(segment
		(start 121.25 146.75)
		(end 121.25 146.2)
		(width 0.25)
		(layer "F.Cu")
		(net 215)
	)
	(segment
		(start 121.25 147.498)
		(end 121.25 146.75)
		(width 0.25)
		(layer "F.Cu")
		(net 215)
	)
	(segment
		(start 123.499 148.651)
		(end 123.749 148.401)
		(width 0.25)
		(layer "F.Cu")
		(net 215)
	)
	(segment
		(start 116.8 143)
		(end 116.596 143.204)
		(width 0.1)
		(layer "F.Cu")
		(net 215)
	)
	(segment
		(start 123.75 146.7)
		(end 123.75 146.2)
		(width 0.25)
		(layer "F.Cu")
		(net 215)
	)
	(segment
		(start 118.3 143)
		(end 116.8 143)
		(width 0.1)
		(layer "F.Cu")
		(net 215)
	)
	(segment
		(start 120.95 148.611397)
		(end 121 148.661397)
		(width 0.25)
		(layer "F.Cu")
		(net 215)
	)
	(segment
		(start 116.596 143.204)
		(end 116.596 144.124)
		(width 0.1)
		(layer "F.Cu")
		(net 215)
	)
	(segment
		(start 121.25 147.498)
		(end 121.25 147.938603)
		(width 0.25)
		(layer "F.Cu")
		(net 215)
	)
	(segment
		(start 123.749 146.701)
		(end 123.75 146.7)
		(width 0.25)
		(layer "F.Cu")
		(net 215)
	)
	(segment
		(start 123.499 149.1)
		(end 123.499 148.651)
		(width 0.25)
		(layer "F.Cu")
		(net 215)
	)
	(segment
		(start 120.95 148.238603)
		(end 120.95 148.611397)
		(width 0.25)
		(layer "F.Cu")
		(net 215)
	)
	(segment
		(start 123.749 147.498)
		(end 123.749 146.701)
		(width 0.25)
		(layer "F.Cu")
		(net 215)
	)
	(segment
		(start 118.497 143.197)
		(end 118.3 143)
		(width 0.1)
		(layer "F.Cu")
		(net 215)
	)
	(segment
		(start 123.749 148.401)
		(end 123.749 147.498)
		(width 0.25)
		(layer "F.Cu")
		(net 215)
	)
	(segment
		(start 121.25 147.938603)
		(end 120.95 148.238603)
		(width 0.25)
		(layer "F.Cu")
		(net 215)
	)
	(segment
		(start 121 148.661397)
		(end 121 149.1)
		(width 0.25)
		(layer "F.Cu")
		(net 215)
	)
	(segment
		(start 121 149.1)
		(end 121 149.55)
		(width 0.25)
		(layer "F.Cu")
		(net 215)
	)
	(via
		(at 119 145.8)
		(size 0.45)
		(drill 0.2)
		(layers "F.Cu" "B.Cu")
		(remove_unused_layers yes)
		(keep_end_layers yes)
		(free yes)
		(zone_layer_connections "In2.Cu")
		(net 215)
	)
	(via
		(at 121 149.55)
		(size 0.45)
		(drill 0.2)
		(layers "F.Cu" "B.Cu")
		(remove_unused_layers yes)
		(keep_end_layers yes)
		(zone_layer_connections "In2.Cu")
		(net 215)
	)
	(via
		(at 118.4 146.4)
		(size 0.45)
		(drill 0.2)
		(layers "F.Cu" "B.Cu")
		(remove_unused_layers yes)
		(keep_end_layers yes)
		(free yes)
		(zone_layer_connections "In2.Cu")
		(net 215)
	)
	(via
		(at 119 145.2)
		(size 0.45)
		(drill 0.2)
		(layers "F.Cu" "B.Cu")
		(remove_unused_layers yes)
		(keep_end_layers yes)
		(free yes)
		(zone_layer_connections "In2.Cu")
		(net 215)
	)
	(via
		(at 121.25 146.75)
		(size 0.45)
		(drill 0.2)
		(layers "F.Cu" "B.Cu")
		(remove_unused_layers yes)
		(keep_end_layers yes)
		(zone_layer_connections "In2.Cu")
		(net 215)
	)
	(via
		(at 119 146.4)
		(size 0.45)
		(drill 0.2)
		(layers "F.Cu" "B.Cu")
		(remove_unused_layers yes)
		(keep_end_layers yes)
		(free yes)
		(zone_layer_connections "In2.Cu")
		(net 215)
	)
	(via
		(at 123.75 146.7)
		(size 0.45)
		(drill 0.2)
		(layers "F.Cu" "B.Cu")
		(remove_unused_layers yes)
		(keep_end_layers yes)
		(zone_layer_connections "In2.Cu")
		(net 215)
	)
	(via
		(at 123.5 149.55)
		(size 0.45)
		(drill 0.2)
		(layers "F.Cu" "B.Cu")
		(remove_unused_layers yes)
		(keep_end_layers yes)
		(zone_layer_connections "In2.Cu")
		(net 215)
	)
	(via
		(at 121.25 146.2)
		(size 0.45)
		(drill 0.2)
		(layers "F.Cu" "B.Cu")
		(remove_unused_layers yes)
		(keep_end_layers yes)
		(zone_layer_connections "In2.Cu")
		(net 215)
	)
	(via
		(at 118.4 145.8)
		(size 0.45)
		(drill 0.2)
		(layers "F.Cu" "B.Cu")
		(remove_unused_layers yes)
		(keep_end_layers yes)
		(free yes)
		(zone_layer_connections "In2.Cu")
		(net 215)
	)
	(via
		(at 118.4 145.2)
		(size 0.45)
		(drill 0.2)
		(layers "F.Cu" "B.Cu")
		(remove_unused_layers yes)
		(keep_end_layers yes)
		(free yes)
		(zone_layer_connections "In2.Cu")
		(net 215)
	)
	(via
		(at 123.75 146.2)
		(size 0.45)
		(drill 0.2)
		(layers "F.Cu" "B.Cu")
		(remove_unused_layers yes)
		(keep_end_layers yes)
		(zone_layer_connections "In2.Cu")
		(net 215)
	)
	(segment
		(start 123.001 150.6)
		(end 123.82 150.6)
		(width 0.25)
		(layer "B.Cu")
		(net 215)
	)
	(segment
		(start 123.75 146.2)
		(end 123.75 145.73)
		(width 0.25)
		(layer "B.Cu")
		(net 215)
	)
	(segment
		(start 120.78 149.77)
		(end 121 149.55)
		(width 0.25)
		(layer "B.Cu")
		(net 215)
	)
	(segment
		(start 123.75 145.73)
		(end 123.6 145.58)
		(width 0.25)
		(layer "B.Cu")
		(net 215)
	)
	(segment
		(start 121.25 145.93)
		(end 121.6 145.58)
		(width 0.25)
		(layer "B.Cu")
		(net 215)
	)
	(segment
		(start 121.6 145.58)
		(end 121.7 145.58)
		(width 0.25)
		(layer "B.Cu")
		(net 215)
	)
	(segment
		(start 123.82 149.87)
		(end 123.5 149.55)
		(width 0.25)
		(layer "B.Cu")
		(net 215)
	)
	(segment
		(start 123.82 150.6)
		(end 123.82 149.87)
		(width 0.25)
		(layer "B.Cu")
		(net 215)
	)
	(segment
		(start 121.25 146.2)
		(end 121.25 145.93)
		(width 0.25)
		(layer "B.Cu")
		(net 215)
	)
	(segment
		(start 123.6 145.58)
		(end 123.5 145.58)
		(width 0.25)
		(layer "B.Cu")
		(net 215)
	)
	(segment
		(start 120.78 150.6)
		(end 120.78 149.77)
		(width 0.25)
		(layer "B.Cu")
		(net 215)
	)
	(segment
		(start 130.9275 118.0275)
		(end 131.2475 118.0275)
		(width 0.1)
		(layer "F.Cu")
		(net 216)
	)
	(segment
		(start 130.509997 116.98)
		(end 130.509997 117.609997)
		(width 0.1)
		(layer "F.Cu")
		(net 216)
	)
	(segment
		(start 131.2475 118.0275)
		(end 131.72 118.5)
		(width 0.1)
		(layer "F.Cu")
		(net 216)
	)
	(segment
		(start 130.509997 117.609997)
		(end 130.9275 118.0275)
		(width 0.1)
		(layer "F.Cu")
		(net 216)
	)
	(segment
		(start 131.72 118.5)
		(end 131.72 118.89)
		(width 0.1)
		(layer "F.Cu")
		(net 216)
	)
	(segment
		(start 134.5 114.3)
		(end 133.9 114.9)
		(width 0.1)
		(layer "F.Cu")
		(net 217)
	)
	(segment
		(start 136.05 115.1)
		(end 135.25 114.3)
		(width 0.1)
		(layer "F.Cu")
		(net 217)
	)
	(segment
		(start 133.33 119.58)
		(end 133.1 119.81)
		(width 0.1)
		(layer "F.Cu")
		(net 217)
	)
	(segment
		(start 135.25 114.3)
		(end 134.5 114.3)
		(width 0.1)
		(layer "F.Cu")
		(net 217)
	)
	(segment
		(start 133.95 119.4)
		(end 133.77 119.58)
		(width 0.1)
		(layer "F.Cu")
		(net 217)
	)
	(segment
		(start 133.77 119.58)
		(end 133.33 119.58)
		(width 0.1)
		(layer "F.Cu")
		(net 217)
	)
	(segment
		(start 133.95 117.9)
		(end 133.95 119.4)
		(width 0.1)
		(layer "F.Cu")
		(net 217)
	)
	(segment
		(start 133.9 114.9)
		(end 133.9 117.85)
		(width 0.1)
		(layer "F.Cu")
		(net 217)
	)
	(segment
		(start 133.9 117.85)
		(end 133.95 117.9)
		(width 0.1)
		(layer "F.Cu")
		(net 217)
	)
	(via
		(at 136.05 115.1)
		(size 0.45)
		(drill 0.2)
		(layers "F.Cu" "B.Cu")
		(remove_unused_layers yes)
		(keep_end_layers yes)
		(zone_layer_connections)
		(net 217)
	)
	(segment
		(start 136.05 115.1)
		(end 136.020001 115.1)
		(width 0.1)
		(layer "B.Cu")
		(net 217)
	)
	(via
		(at 141.1 116.1)
		(size 0.45)
		(drill 0.2)
		(layers "F.Cu" "B.Cu")
		(remove_unused_layers yes)
		(keep_end_layers yes)
		(zone_layer_connections)
		(net 218)
	)
	(via
		(at 131.75 119.825)
		(size 0.45)
		(drill 0.2)
		(layers "F.Cu" "B.Cu")
		(remove_unused_layers yes)
		(keep_end_layers yes)
		(zone_layer_connections)
		(net 218)
	)
	(segment
		(start 141.080001 116.119999)
		(end 141.1 116.1)
		(width 0.1)
		(layer "B.Cu")
		(net 218)
	)
	(segment
		(start 141.080001 116.124999)
		(end 141.080001 116.119999)
		(width 0.1)
		(layer "B.Cu")
		(net 218)
	)
	(segment
		(start 136.65 115.55)
		(end 137.6 116.5)
		(width 0.1)
		(layer "In3.Cu")
		(net 218)
	)
	(segment
		(start 137.6 116.5)
		(end 138.45 116.5)
		(width 0.1)
		(layer "In3.Cu")
		(net 218)
	)
	(segment
		(start 133.6 117.45)
		(end 133.6 115.6)
		(width 0.1)
		(layer "In3.Cu")
		(net 218)
	)
	(segment
		(start 132.3875 119.1875)
		(end 132.3875 118.6625)
		(width 0.1)
		(layer "In3.Cu")
		(net 218)
	)
	(segment
		(start 138.45 116.5)
		(end 138.85 116.1)
		(width 0.1)
		(layer "In3.Cu")
		(net 218)
	)
	(segment
		(start 134.15 115.05)
		(end 135.35 115.05)
		(width 0.1)
		(layer "In3.Cu")
		(net 218)
	)
	(segment
		(start 138.85 116.1)
		(end 141.1 116.1)
		(width 0.1)
		(layer "In3.Cu")
		(net 218)
	)
	(segment
		(start 135.35 115.05)
		(end 135.85 115.55)
		(width 0.1)
		(layer "In3.Cu")
		(net 218)
	)
	(segment
		(start 135.85 115.55)
		(end 136.65 115.55)
		(width 0.1)
		(layer "In3.Cu")
		(net 218)
	)
	(segment
		(start 132.3875 118.6625)
		(end 133.6 117.45)
		(width 0.1)
		(layer "In3.Cu")
		(net 218)
	)
	(segment
		(start 131.75 119.825)
		(end 132.3875 119.1875)
		(width 0.1)
		(layer "In3.Cu")
		(net 218)
	)
	(segment
		(start 133.6 115.6)
		(end 134.15 115.05)
		(width 0.1)
		(layer "In3.Cu")
		(net 218)
	)
	(via
		(at 132.625 122.552)
		(size 0.45)
		(drill 0.2)
		(layers "F.Cu" "B.Cu")
		(remove_unused_layers yes)
		(keep_end_layers yes)
		(zone_layer_connections)
		(net 219)
	)
	(via
		(at 142.05 118.15)
		(size 0.45)
		(drill 0.2)
		(layers "F.Cu" "B.Cu")
		(remove_unused_layers yes)
		(keep_end_layers yes)
		(zone_layer_connections)
		(net 219)
	)
	(segment
		(start 142.02 118.174998)
		(end 142.025002 118.174998)
		(width 0.1)
		(layer "B.Cu")
		(net 219)
	)
	(segment
		(start 142.025002 118.174998)
		(end 142.05 118.15)
		(width 0.1)
		(layer "B.Cu")
		(net 219)
	)
	(segment
		(start 137.2 113.8)
		(end 140.6 117.2)
		(width 0.1)
		(layer "In5.Cu")
		(net 219)
	)
	(segment
		(start 133.45 122.35)
		(end 133.45 120.8)
		(width 0.1)
		(layer "In5.Cu")
		(net 219)
	)
	(segment
		(start 140.6 117.4)
		(end 140.9 117.7)
		(width 0.1)
		(layer "In5.Cu")
		(net 219)
	)
	(segment
		(start 140.9 117.7)
		(end 141.6 117.7)
		(width 0.1)
		(layer "In5.Cu")
		(net 219)
	)
	(segment
		(start 135.4 113.8)
		(end 137.2 113.8)
		(width 0.1)
		(layer "In5.Cu")
		(net 219)
	)
	(segment
		(start 133.975 120.275)
		(end 133.975 115.225)
		(width 0.1)
		(layer "In5.Cu")
		(net 219)
	)
	(segment
		(start 133.248 122.552)
		(end 133.45 122.35)
		(width 0.1)
		(layer "In5.Cu")
		(net 219)
	)
	(segment
		(start 140.6 117.2)
		(end 140.6 117.4)
		(width 0.1)
		(layer "In5.Cu")
		(net 219)
	)
	(segment
		(start 132.625 122.552)
		(end 133.248 122.552)
		(width 0.1)
		(layer "In5.Cu")
		(net 219)
	)
	(segment
		(start 141.6 117.7)
		(end 142.05 118.15)
		(width 0.1)
		(layer "In5.Cu")
		(net 219)
	)
	(segment
		(start 133.45 120.8)
		(end 133.975 120.275)
		(width 0.1)
		(layer "In5.Cu")
		(net 219)
	)
	(segment
		(start 133.975 115.225)
		(end 135.4 113.8)
		(width 0.1)
		(layer "In5.Cu")
		(net 219)
	)
	(via
		(at 131.1 119.825)
		(size 0.45)
		(drill 0.2)
		(layers "F.Cu" "B.Cu")
		(remove_unused_layers yes)
		(keep_end_layers yes)
		(zone_layer_connections)
		(net 220)
	)
	(via
		(at 141.1 115.1)
		(size 0.45)
		(drill 0.2)
		(layers "F.Cu" "B.Cu")
		(remove_unused_layers yes)
		(keep_end_layers yes)
		(zone_layer_connections)
		(net 220)
	)
	(segment
		(start 141.08 115.1)
		(end 141.1 115.1)
		(width 0.1)
		(layer "B.Cu")
		(net 220)
	)
	(segment
		(start 133.95 114.55)
		(end 136.3 114.55)
		(width 0.1)
		(layer "In3.Cu")
		(net 220)
	)
	(segment
		(start 140.15 115.55)
		(end 140.6 115.1)
		(width 0.1)
		(layer "In3.Cu")
		(net 220)
	)
	(segment
		(start 133.15 115.35)
		(end 133.95 114.55)
		(width 0.1)
		(layer "In3.Cu")
		(net 220)
	)
	(segment
		(start 136.3 114.55)
		(end 137.3 115.55)
		(width 0.1)
		(layer "In3.Cu")
		(net 220)
	)
	(segment
		(start 131.175 119.825)
		(end 132.025 118.975)
		(width 0.1)
		(layer "In3.Cu")
		(net 220)
	)
	(segment
		(start 132.025 118.575)
		(end 133.15 117.45)
		(width 0.1)
		(layer "In3.Cu")
		(net 220)
	)
	(segment
		(start 132.025 118.975)
		(end 132.025 118.575)
		(width 0.1)
		(layer "In3.Cu")
		(net 220)
	)
	(segment
		(start 133.15 117.45)
		(end 133.15 115.35)
		(width 0.1)
		(layer "In3.Cu")
		(net 220)
	)
	(segment
		(start 131.1 119.825)
		(end 131.175 119.825)
		(width 0.1)
		(layer "In3.Cu")
		(net 220)
	)
	(segment
		(start 137.3 115.55)
		(end 140.15 115.55)
		(width 0.1)
		(layer "In3.Cu")
		(net 220)
	)
	(segment
		(start 140.6 115.1)
		(end 141.1 115.1)
		(width 0.1)
		(layer "In3.Cu")
		(net 220)
	)
	(segment
		(start 130.775 120.375)
		(end 132.075 120.375)
		(width 0.1)
		(layer "F.Cu")
		(net 221)
	)
	(segment
		(start 130.45 120.05)
		(end 130.775 120.375)
		(width 0.1)
		(layer "F.Cu")
		(net 221)
	)
	(via
		(at 132.075 120.375)
		(size 0.45)
		(drill 0.2)
		(layers "F.Cu" "B.Cu")
		(remove_unused_layers yes)
		(keep_end_layers yes)
		(zone_layer_connections)
		(net 221)
	)
	(via
		(at 141.1 118.15)
		(size 0.45)
		(drill 0.2)
		(layers "F.Cu" "B.Cu")
		(remove_unused_layers yes)
		(keep_end_layers yes)
		(zone_layer_connections)
		(net 221)
	)
	(segment
		(start 141.080002 118.169998)
		(end 141.1 118.15)
		(width 0.1)
		(layer "B.Cu")
		(net 221)
	)
	(segment
		(start 141.080002 118.174998)
		(end 141.080002 118.169998)
		(width 0.1)
		(layer "B.Cu")
		(net 221)
	)
	(segment
		(start 135.55 117.75)
		(end 138 117.75)
		(width 0.1)
		(layer "In3.Cu")
		(net 221)
	)
	(segment
		(start 133.95 119.35)
		(end 135.55 117.75)
		(width 0.1)
		(layer "In3.Cu")
		(net 221)
	)
	(segment
		(start 139.15 117.3)
		(end 139.55 117.7)
		(width 0.1)
		(layer "In3.Cu")
		(net 221)
	)
	(segment
		(start 133.45 119.35)
		(end 133.95 119.35)
		(width 0.1)
		(layer "In3.Cu")
		(net 221)
	)
	(segment
		(start 138.45 117.3)
		(end 139.15 117.3)
		(width 0.1)
		(layer "In3.Cu")
		(net 221)
	)
	(segment
		(start 132.425 120.375)
		(end 133.45 119.35)
		(width 0.1)
		(layer "In3.Cu")
		(net 221)
	)
	(segment
		(start 138 117.75)
		(end 138.45 117.3)
		(width 0.1)
		(layer "In3.Cu")
		(net 221)
	)
	(segment
		(start 139.55 117.7)
		(end 140.65 117.7)
		(width 0.1)
		(layer "In3.Cu")
		(net 221)
	)
	(segment
		(start 140.65 117.7)
		(end 141.1 118.15)
		(width 0.1)
		(layer "In3.Cu")
		(net 221)
	)
	(segment
		(start 132.075 120.375)
		(end 132.425 120.375)
		(width 0.1)
		(layer "In3.Cu")
		(net 221)
	)
	(via
		(at 132.624 123.399)
		(size 0.45)
		(drill 0.2)
		(layers "F.Cu" "B.Cu")
		(remove_unused_layers yes)
		(keep_end_layers yes)
		(zone_layer_connections)
		(net 222)
	)
	(via
		(at 142.3 119)
		(size 0.45)
		(drill 0.2)
		(layers "F.Cu" "B.Cu")
		(remove_unused_layers yes)
		(keep_end_layers yes)
		(zone_layer_connections)
		(net 222)
	)
	(segment
		(start 135.2 114.6)
		(end 136.4 114.6)
		(width 0.1)
		(layer "In5.Cu")
		(net 222)
	)
	(segment
		(start 133.199 123.399)
		(end 133.3 123.5)
		(width 0.1)
		(layer "In5.Cu")
		(net 222)
	)
	(segment
		(start 136.4 114.6)
		(end 137.3 115.5)
		(width 0.1)
		(layer "In5.Cu")
		(net 222)
	)
	(segment
		(start 139.7 118.3)
		(end 140.4 119)
		(width 0.1)
		(layer "In5.Cu")
		(net 222)
	)
	(segment
		(start 137.3 116.3)
		(end 137.6 116.6)
		(width 0.1)
		(layer "In5.Cu")
		(net 222)
	)
	(segment
		(start 134.3 115.5)
		(end 135.2 114.6)
		(width 0.1)
		(layer "In5.Cu")
		(net 222)
	)
	(segment
		(start 137.6 116.6)
		(end 138.9 116.6)
		(width 0.1)
		(layer "In5.Cu")
		(net 222)
	)
	(segment
		(start 140.4 119)
		(end 142.3 119)
		(width 0.1)
		(layer "In5.Cu")
		(net 222)
	)
	(segment
		(start 135.4 122.6)
		(end 135.4 118.8)
		(width 0.1)
		(layer "In5.Cu")
		(net 222)
	)
	(segment
		(start 137.3 115.5)
		(end 137.3 116.3)
		(width 0.1)
		(layer "In5.Cu")
		(net 222)
	)
	(segment
		(start 133.3 123.5)
		(end 134.5 123.5)
		(width 0.1)
		(layer "In5.Cu")
		(net 222)
	)
	(segment
		(start 138.9 116.6)
		(end 139.7 117.4)
		(width 0.1)
		(layer "In5.Cu")
		(net 222)
	)
	(segment
		(start 132.624 123.399)
		(end 133.199 123.399)
		(width 0.1)
		(layer "In5.Cu")
		(net 222)
	)
	(segment
		(start 134.5 123.5)
		(end 135.4 122.6)
		(width 0.1)
		(layer "In5.Cu")
		(net 222)
	)
	(segment
		(start 139.7 117.4)
		(end 139.7 118.3)
		(width 0.1)
		(layer "In5.Cu")
		(net 222)
	)
	(segment
		(start 134.3 117.7)
		(end 134.3 115.5)
		(width 0.1)
		(layer "In5.Cu")
		(net 222)
	)
	(segment
		(start 135.4 118.8)
		(end 134.3 117.7)
		(width 0.1)
		(layer "In5.Cu")
		(net 222)
	)
	(segment
		(start 125.9 120.05)
		(end 125.575 120.375)
		(width 0.1)
		(layer "F.Cu")
		(net 223)
	)
	(via
		(at 125.575 120.375)
		(size 0.45)
		(drill 0.2)
		(layers "F.Cu" "B.Cu")
		(remove_unused_layers yes)
		(keep_end_layers yes)
		(zone_layer_connections)
		(net 223)
	)
	(segment
		(start 125.222 120.431)
		(end 125.519 120.431)
		(width 0.25)
		(layer "B.Cu")
		(net 223)
	)
	(segment
		(start 125.519 120.431)
		(end 125.575 120.375)
		(width 0.25)
		(layer "B.Cu")
		(net 223)
	)
	(via
		(at 132.4 119.825)
		(size 0.45)
		(drill 0.2)
		(layers "F.Cu" "B.Cu")
		(remove_unused_layers yes)
		(keep_end_layers yes)
		(zone_layer_connections)
		(net 224)
	)
	(via
		(at 141.1 117.15)
		(size 0.45)
		(drill 0.2)
		(layers "F.Cu" "B.Cu")
		(remove_unused_layers yes)
		(keep_end_layers yes)
		(zone_layer_connections)
		(net 224)
	)
	(segment
		(start 141.099997 117.149997)
		(end 141.1 117.15)
		(width 0.1)
		(layer "B.Cu")
		(net 224)
	)
	(segment
		(start 141.08 117.149997)
		(end 141.099997 117.149997)
		(width 0.1)
		(layer "B.Cu")
		(net 224)
	)
	(segment
		(start 135.75 116.75)
		(end 135.3 117.2)
		(width 0.1)
		(layer "In3.Cu")
		(net 224)
	)
	(segment
		(start 141.1 117.15)
		(end 139.35 117.15)
		(width 0.1)
		(layer "In3.Cu")
		(net 224)
	)
	(segment
		(start 132.675 119.55)
		(end 132.4 119.825)
		(width 0.1)
		(layer "In3.Cu")
		(net 224)
	)
	(segment
		(start 132.675 118.875)
		(end 132.675 119.55)
		(width 0.1)
		(layer "In3.Cu")
		(net 224)
	)
	(segment
		(start 135.3 117.2)
		(end 135.3 117.6)
		(width 0.1)
		(layer "In3.Cu")
		(net 224)
	)
	(segment
		(start 138.95 116.75)
		(end 135.75 116.75)
		(width 0.1)
		(layer "In3.Cu")
		(net 224)
	)
	(segment
		(start 139.35 117.15)
		(end 138.95 116.75)
		(width 0.1)
		(layer "In3.Cu")
		(net 224)
	)
	(segment
		(start 133.25 118.3)
		(end 132.675 118.875)
		(width 0.1)
		(layer "In3.Cu")
		(net 224)
	)
	(segment
		(start 134.6 118.3)
		(end 133.25 118.3)
		(width 0.1)
		(layer "In3.Cu")
		(net 224)
	)
	(segment
		(start 135.3 117.6)
		(end 134.6 118.3)
		(width 0.1)
		(layer "In3.Cu")
		(net 224)
	)
	(via
		(at 132.625 121.35)
		(size 0.45)
		(drill 0.2)
		(layers "F.Cu" "B.Cu")
		(remove_unused_layers yes)
		(keep_end_layers yes)
		(zone_layer_connections)
		(net 225)
	)
	(via
		(at 142 116.1)
		(size 0.45)
		(drill 0.2)
		(layers "F.Cu" "B.Cu")
		(remove_unused_layers yes)
		(keep_end_layers yes)
		(zone_layer_connections)
		(net 225)
	)
	(segment
		(start 142.02 116.12)
		(end 142 116.1)
		(width 0.1)
		(layer "B.Cu")
		(net 225)
	)
	(segment
		(start 142.02 116.124996)
		(end 142.02 116.12)
		(width 0.1)
		(layer "B.Cu")
		(net 225)
	)
	(segment
		(start 132.625 121.35)
		(end 134.175 119.8)
		(width 0.1)
		(layer "In3.Cu")
		(net 225)
	)
	(segment
		(start 136.75 120)
		(end 142 120)
		(width 0.1)
		(layer "In3.Cu")
		(net 225)
	)
	(segment
		(start 142 120)
		(end 142.7 119.3)
		(width 0.1)
		(layer "In3.Cu")
		(net 225)
	)
	(segment
		(start 134.6 119.8)
		(end 134.85 119.55)
		(width 0.1)
		(layer "In3.Cu")
		(net 225)
	)
	(segment
		(start 134.175 119.8)
		(end 134.6 119.8)
		(width 0.1)
		(layer "In3.Cu")
		(net 225)
	)
	(segment
		(start 142.7 119.3)
		(end 142.7 116.8)
		(width 0.1)
		(layer "In3.Cu")
		(net 225)
	)
	(segment
		(start 134.85 119.55)
		(end 136.3 119.55)
		(width 0.1)
		(layer "In3.Cu")
		(net 225)
	)
	(segment
		(start 142.7 116.8)
		(end 142 116.1)
		(width 0.1)
		(layer "In3.Cu")
		(net 225)
	)
	(segment
		(start 136.3 119.55)
		(end 136.75 120)
		(width 0.1)
		(layer "In3.Cu")
		(net 225)
	)
	(via
		(at 132.625 122)
		(size 0.45)
		(drill 0.2)
		(layers "F.Cu" "B.Cu")
		(remove_unused_layers yes)
		(keep_end_layers yes)
		(zone_layer_connections)
		(net 226)
	)
	(via
		(at 142.05 117.15)
		(size 0.45)
		(drill 0.2)
		(layers "F.Cu" "B.Cu")
		(remove_unused_layers yes)
		(keep_end_layers yes)
		(zone_layer_connections)
		(net 226)
	)
	(segment
		(start 142.020001 117.15)
		(end 142.05 117.15)
		(width 0.1)
		(layer "B.Cu")
		(net 226)
	)
	(segment
		(start 141.65 116.75)
		(end 142.05 117.15)
		(width 0.1)
		(layer "In5.Cu")
		(net 226)
	)
	(segment
		(start 137.2 113.4)
		(end 140.55 116.75)
		(width 0.1)
		(layer "In5.Cu")
		(net 226)
	)
	(segment
		(start 132.75 122)
		(end 133.1 121.65)
		(width 0.1)
		(layer "In5.Cu")
		(net 226)
	)
	(segment
		(start 133.1 115.5)
		(end 135.1 113.5)
		(width 0.1)
		(layer "In5.Cu")
		(net 226)
	)
	(segment
		(start 136.7 113.5)
		(end 136.8 113.4)
		(width 0.1)
		(layer "In5.Cu")
		(net 226)
	)
	(segment
		(start 135.1 113.5)
		(end 136.7 113.5)
		(width 0.1)
		(layer "In5.Cu")
		(net 226)
	)
	(segment
		(start 140.55 116.75)
		(end 141.65 116.75)
		(width 0.1)
		(layer "In5.Cu")
		(net 226)
	)
	(segment
		(start 136.8 113.4)
		(end 137.2 113.4)
		(width 0.1)
		(layer "In5.Cu")
		(net 226)
	)
	(segment
		(start 132.625 122)
		(end 132.75 122)
		(width 0.1)
		(layer "In5.Cu")
		(net 226)
	)
	(segment
		(start 133.1 121.65)
		(end 133.1 115.5)
		(width 0.1)
		(layer "In5.Cu")
		(net 226)
	)
	(via
		(at 142 115.1)
		(size 0.45)
		(drill 0.2)
		(layers "F.Cu" "B.Cu")
		(remove_unused_layers yes)
		(keep_end_layers yes)
		(zone_layer_connections)
		(net 227)
	)
	(via
		(at 132.625 120.7)
		(size 0.45)
		(drill 0.2)
		(layers "F.Cu" "B.Cu")
		(remove_unused_layers yes)
		(keep_end_layers yes)
		(zone_layer_connections)
		(net 227)
	)
	(segment
		(start 142.02 115.099997)
		(end 142.000003 115.099997)
		(width 0.1)
		(layer "B.Cu")
		(net 227)
	)
	(segment
		(start 142.000003 115.099997)
		(end 142 115.1)
		(width 0.1)
		(layer "B.Cu")
		(net 227)
	)
	(segment
		(start 141.6 118.25)
		(end 141.6 115.5)
		(width 0.1)
		(layer "In3.Cu")
		(net 227)
	)
	(segment
		(start 132.625 120.7)
		(end 133.725 119.6)
		(width 0.1)
		(layer "In3.Cu")
		(net 227)
	)
	(segment
		(start 141.15 118.7)
		(end 141.6 118.25)
		(width 0.1)
		(layer "In3.Cu")
		(net 227)
	)
	(segment
		(start 141.6 115.5)
		(end 142 115.1)
		(width 0.1)
		(layer "In3.Cu")
		(net 227)
	)
	(segment
		(start 133.725 119.6)
		(end 134.3 119.6)
		(width 0.1)
		(layer "In3.Cu")
		(net 227)
	)
	(segment
		(start 134.3 119.6)
		(end 135.2 118.7)
		(width 0.1)
		(layer "In3.Cu")
		(net 227)
	)
	(segment
		(start 135.2 118.7)
		(end 141.15 118.7)
		(width 0.1)
		(layer "In3.Cu")
		(net 227)
	)
	(segment
		(start 125.25 125.9)
		(end 124.925 126.225)
		(width 0.1)
		(layer "F.Cu")
		(net 228)
	)
	(via
		(at 124.925 126.225)
		(size 0.45)
		(drill 0.2)
		(layers "F.Cu" "B.Cu")
		(remove_unused_layers yes)
		(keep_end_layers yes)
		(zone_layer_connections)
		(net 228)
	)
	(segment
		(start 123.23 127.025)
		(end 123.555 126.7)
		(width 0.1)
		(layer "B.Cu")
		(net 228)
	)
	(segment
		(start 123.555 126.7)
		(end 124.45 126.7)
		(width 0.1)
		(layer "B.Cu")
		(net 228)
	)
	(segment
		(start 124.45 126.7)
		(end 124.925 126.225)
		(width 0.1)
		(layer "B.Cu")
		(net 228)
	)
	(segment
		(start 131.1 125.25)
		(end 131.425 125.575)
		(width 0.1)
		(layer "F.Cu")
		(net 229)
	)
	(via
		(at 131.425 125.575)
		(size 0.45)
		(drill 0.2)
		(layers "F.Cu" "B.Cu")
		(remove_unused_layers yes)
		(keep_end_layers yes)
		(zone_layer_connections)
		(net 229)
	)
	(segment
		(start 131.1 125.9)
		(end 131.425 126.225)
		(width 0.1)
		(layer "F.Cu")
		(net 230)
	)
	(via
		(at 131.425 126.225)
		(size 0.45)
		(drill 0.2)
		(layers "F.Cu" "B.Cu")
		(remove_unused_layers yes)
		(keep_end_layers yes)
		(zone_layer_connections)
		(net 230)
	)
	(segment
		(start 132.4111 128.7811)
		(end 132.4111 129.4111)
		(width 0.1)
		(layer "F.Cu")
		(net 231)
	)
	(segment
		(start 132.18 128.55)
		(end 132.4111 128.7811)
		(width 0.1)
		(layer "F.Cu")
		(net 231)
	)
	(segment
		(start 132.4111 129.4111)
		(end 132.55 129.55)
		(width 0.1)
		(layer "F.Cu")
		(net 231)
	)
	(via
		(at 132.55 129.55)
		(size 0.45)
		(drill 0.2)
		(layers "F.Cu" "B.Cu")
		(remove_unused_layers yes)
		(keep_end_layers yes)
		(zone_layer_connections)
		(net 231)
	)
	(segment
		(start 135.2 127.68)
		(end 135.12 127.6)
		(width 0.1)
		(layer "B.Cu")
		(net 231)
	)
	(segment
		(start 134.95 129.55)
		(end 135.2 129.3)
		(width 0.1)
		(layer "B.Cu")
		(net 231)
	)
	(segment
		(start 135.2 129.3)
		(end 135.2 127.68)
		(width 0.1)
		(layer "B.Cu")
		(net 231)
	)
	(segment
		(start 132.55 129.55)
		(end 134.95 129.55)
		(width 0.1)
		(layer "B.Cu")
		(net 231)
	)
	(segment
		(start 131.72 128.55)
		(end 131.9489 128.7789)
		(width 0.1)
		(layer "F.Cu")
		(net 232)
	)
	(segment
		(start 131.4 129.8)
		(end 131.9489 129.2511)
		(width 0.1)
		(layer "F.Cu")
		(net 232)
	)
	(segment
		(start 131.9489 128.7789)
		(end 131.9489 129.2511)
		(width 0.1)
		(layer "F.Cu")
		(net 232)
	)
	(segment
		(start 131.4 129.8)
		(end 131 129.8)
		(width 0.1)
		(layer "F.Cu")
		(net 232)
	)
	(via
		(at 131 129.8)
		(size 0.45)
		(drill 0.2)
		(layers "F.Cu" "B.Cu")
		(remove_unused_layers yes)
		(keep_end_layers yes)
		(zone_layer_connections)
		(net 232)
	)
	(segment
		(start 134.6125 128.2875)
		(end 134.6125 127.2)
		(width 0.1)
		(layer "B.Cu")
		(net 232)
	)
	(segment
		(start 131 129.8)
		(end 131.5 129.8)
		(width 0.1)
		(layer "B.Cu")
		(net 232)
	)
	(segment
		(start 134.3 128.6)
		(end 134.6125 128.2875)
		(width 0.1)
		(layer "B.Cu")
		(net 232)
	)
	(segment
		(start 131.5 129.8)
		(end 132.7 128.6)
		(width 0.1)
		(layer "B.Cu")
		(net 232)
	)
	(segment
		(start 135.120001 126.692499)
		(end 135.120001 126.604998)
		(width 0.1)
		(layer "B.Cu")
		(net 232)
	)
	(segment
		(start 132.7 128.6)
		(end 134.3 128.6)
		(width 0.1)
		(layer "B.Cu")
		(net 232)
	)
	(segment
		(start 134.6125 127.2)
		(end 135.120001 126.692499)
		(width 0.1)
		(layer "B.Cu")
		(net 232)
	)
	(segment
		(start 133.1 126.25)
		(end 133.3311 126.0189)
		(width 0.1)
		(layer "F.Cu")
		(net 233)
	)
	(segment
		(start 134.975 122.175)
		(end 135.15 122)
		(width 0.1)
		(layer "F.Cu")
		(net 233)
	)
	(segment
		(start 133.3311 126.0189)
		(end 133.7811 126.0189)
		(width 0.1)
		(layer "F.Cu")
		(net 233)
	)
	(segment
		(start 134.4 123.2)
		(end 134.975 122.625)
		(width 0.1)
		(layer "F.Cu")
		(net 233)
	)
	(segment
		(start 133.7811 126.0189)
		(end 134.4 125.4)
		(width 0.1)
		(layer "F.Cu")
		(net 233)
	)
	(segment
		(start 135.55 120.7)
		(end 135.55 119.9)
		(width 0.1)
		(layer "F.Cu")
		(net 233)
	)
	(segment
		(start 135.15 122)
		(end 135.15 121.1)
		(width 0.1)
		(layer "F.Cu")
		(net 233)
	)
	(segment
		(start 135.15 121.1)
		(end 135.55 120.7)
		(width 0.1)
		(layer "F.Cu")
		(net 233)
	)
	(segment
		(start 135.55 119.9)
		(end 136 119.45)
		(width 0.1)
		(layer "F.Cu")
		(net 233)
	)
	(segment
		(start 136 119.45)
		(end 136 119.15)
		(width 0.1)
		(layer "F.Cu")
		(net 233)
	)
	(segment
		(start 134.975 122.625)
		(end 134.975 122.175)
		(width 0.1)
		(layer "F.Cu")
		(net 233)
	)
	(segment
		(start 134.4 125.4)
		(end 134.4 123.2)
		(width 0.1)
		(layer "F.Cu")
		(net 233)
	)
	(via
		(at 136 119.15)
		(size 0.45)
		(drill 0.2)
		(layers "F.Cu" "B.Cu")
		(remove_unused_layers yes)
		(keep_end_layers yes)
		(zone_layer_connections)
		(net 233)
	)
	(segment
		(start 125.25 126.55)
		(end 124.925 126.875)
		(width 0.1)
		(layer "F.Cu")
		(net 234)
	)
	(via
		(at 124.925 126.875)
		(size 0.45)
		(drill 0.2)
		(layers "F.Cu" "B.Cu")
		(remove_unused_layers yes)
		(keep_end_layers yes)
		(zone_layer_connections)
		(net 234)
	)
	(segment
		(start 123.274999 128.025001)
		(end 123.725 127.575)
		(width 0.1)
		(layer "B.Cu")
		(net 234)
	)
	(segment
		(start 124.475 127.35)
		(end 124.475 126.975)
		(width 0.1)
		(layer "B.Cu")
		(net 234)
	)
	(segment
		(start 124.575 126.875)
		(end 124.925 126.875)
		(width 0.1)
		(layer "B.Cu")
		(net 234)
	)
	(segment
		(start 123.23 128.025001)
		(end 123.274999 128.025001)
		(width 0.1)
		(layer "B.Cu")
		(net 234)
	)
	(segment
		(start 124.475 126.975)
		(end 124.575 126.875)
		(width 0.1)
		(layer "B.Cu")
		(net 234)
	)
	(segment
		(start 123.725 127.575)
		(end 124.25 127.575)
		(width 0.1)
		(layer "B.Cu")
		(net 234)
	)
	(segment
		(start 124.25 127.575)
		(end 124.475 127.35)
		(width 0.1)
		(layer "B.Cu")
		(net 234)
	)
	(segment
		(start 134.35 127.4)
		(end 136.05 125.7)
		(width 0.1)
		(layer "F.Cu")
		(net 235)
	)
	(segment
		(start 136.05 125.7)
		(end 136.05 125.15)
		(width 0.1)
		(layer "F.Cu")
		(net 235)
	)
	(segment
		(start 133.33 127.4)
		(end 134.35 127.4)
		(width 0.1)
		(layer "F.Cu")
		(net 235)
	)
	(segment
		(start 133.33 127.4)
		(end 133.1 127.63)
		(width 0.1)
		(layer "F.Cu")
		(net 235)
	)
	(via
		(at 136.05 125.15)
		(size 0.45)
		(drill 0.2)
		(layers "F.Cu" "B.Cu")
		(remove_unused_layers yes)
		(keep_end_layers yes)
		(zone_layer_connections)
		(net 235)
	)
	(segment
		(start 135.6 122.55)
		(end 136 122.15)
		(width 0.1)
		(layer "F.Cu")
		(net 236)
	)
	(segment
		(start 135.15 123.65)
		(end 135.6 123.2)
		(width 0.1)
		(layer "F.Cu")
		(net 236)
	)
	(segment
		(start 134.09 126.71)
		(end 135.15 125.65)
		(width 0.1)
		(layer "F.Cu")
		(net 236)
	)
	(segment
		(start 133.56 126.71)
		(end 134.09 126.71)
		(width 0.1)
		(layer "F.Cu")
		(net 236)
	)
	(segment
		(start 135.6 123.2)
		(end 135.6 122.55)
		(width 0.1)
		(layer "F.Cu")
		(net 236)
	)
	(segment
		(start 135.15 125.65)
		(end 135.15 123.65)
		(width 0.1)
		(layer "F.Cu")
		(net 236)
	)
	(via
		(at 136 122.15)
		(size 0.45)
		(drill 0.2)
		(layers "F.Cu" "B.Cu")
		(remove_unused_layers yes)
		(keep_end_layers yes)
		(zone_layer_connections)
		(net 236)
	)
	(segment
		(start 133.56 127.17)
		(end 134.28 127.17)
		(width 0.1)
		(layer "F.Cu")
		(net 237)
	)
	(segment
		(start 134.28 127.17)
		(end 135.625 125.825)
		(width 0.1)
		(layer "F.Cu")
		(net 237)
	)
	(segment
		(start 135.625 124.545)
		(end 136.02 124.15)
		(width 0.1)
		(layer "F.Cu")
		(net 237)
	)
	(segment
		(start 135.625 125.825)
		(end 135.625 124.545)
		(width 0.1)
		(layer "F.Cu")
		(net 237)
	)
	(via
		(at 136.02 124.15)
		(size 0.45)
		(drill 0.2)
		(layers "F.Cu" "B.Cu")
		(remove_unused_layers yes)
		(keep_end_layers yes)
		(zone_layer_connections)
		(net 237)
	)
	(segment
		(start 131.52 117.825)
		(end 131.9511 118.2561)
		(width 0.1)
		(layer "F.Cu")
		(net 238)
	)
	(segment
		(start 131.52 116.98)
		(end 131.52 117.825)
		(width 0.1)
		(layer "F.Cu")
		(net 238)
	)
	(segment
		(start 131.9511 119.1189)
		(end 131.9511 118.2561)
		(width 0.1)
		(layer "F.Cu")
		(net 238)
	)
	(segment
		(start 131.72 119.35)
		(end 131.9511 119.1189)
		(width 0.1)
		(layer "F.Cu")
		(net 238)
	)
	(segment
		(start 126.875 120.375)
		(end 127.2 120.05)
		(width 0.1)
		(layer "F.Cu")
		(net 239)
	)
	(via
		(at 132.5 116.17)
		(size 0.45)
		(drill 0.2)
		(layers "F.Cu" "B.Cu")
		(remove_unused_layers yes)
		(keep_end_layers yes)
		(zone_layer_connections)
		(net 239)
	)
	(via
		(at 126.875 120.375)
		(size 0.45)
		(drill 0.2)
		(layers "F.Cu" "B.Cu")
		(remove_unused_layers yes)
		(keep_end_layers yes)
		(zone_layer_connections)
		(net 239)
	)
	(segment
		(start 132.909999 116.325)
		(end 132.655 116.325)
		(width 0.15)
		(layer "B.Cu")
		(net 239)
	)
	(segment
		(start 133.259999 116)
		(end 133.234999 116)
		(width 0.15)
		(layer "B.Cu")
		(net 239)
	)
	(segment
		(start 132.655 116.325)
		(end 132.5 116.17)
		(width 0.15)
		(layer "B.Cu")
		(net 239)
	)
	(segment
		(start 133.234999 116)
		(end 132.909999 116.325)
		(width 0.15)
		(layer "B.Cu")
		(net 239)
	)
	(segment
		(start 131.927512 116.325)
		(end 132.345 116.325)
		(width 0.15)
		(layer "In5.Cu")
		(net 239)
	)
	(segment
		(start 127.025 120.525)
		(end 127.227512 120.525)
		(width 0.14)
		(layer "In5.Cu")
		(net 239)
	)
	(segment
		(start 127.575 118.877512)
		(end 128.727512 117.725)
		(width 0.15)
		(layer "In5.Cu")
		(net 239)
	)
	(segment
		(start 126.875 120.375)
		(end 127.025 120.525)
		(width 0.14)
		(layer "In5.Cu")
		(net 239)
	)
	(segment
		(start 128.727512 117.725)
		(end 130.527512 117.725)
		(width 0.15)
		(layer "In5.Cu")
		(net 239)
	)
	(segment
		(start 130.527512 117.725)
		(end 131.927512 116.325)
		(width 0.15)
		(layer "In5.Cu")
		(net 239)
	)
	(segment
		(start 127.227512 120.525)
		(end 127.575 120.177512)
		(width 0.14)
		(layer "In5.Cu")
		(net 239)
	)
	(segment
		(start 132.345 116.325)
		(end 132.5 116.17)
		(width 0.14)
		(layer "In5.Cu")
		(net 239)
	)
	(segment
		(start 127.575 120.177512)
		(end 127.575 118.877512)
		(width 0.15)
		(layer "In5.Cu")
		(net 239)
	)
	(segment
		(start 126.875 121.025)
		(end 127.2 120.7)
		(width 0.1)
		(layer "F.Cu")
		(net 240)
	)
	(via
		(at 126.875 121.025)
		(size 0.45)
		(drill 0.2)
		(layers "F.Cu" "B.Cu")
		(remove_unused_layers yes)
		(keep_end_layers yes)
		(zone_layer_connections)
		(net 240)
	)
	(via
		(at 132.5 116.83)
		(size 0.45)
		(drill 0.2)
		(layers "F.Cu" "B.Cu")
		(remove_unused_layers yes)
		(keep_end_layers yes)
		(zone_layer_connections)
		(net 240)
	)
	(segment
		(start 132.909999 116.675)
		(end 132.655 116.675)
		(width 0.15)
		(layer "B.Cu")
		(net 240)
	)
	(segment
		(start 133.259999 117)
		(end 133.234999 117)
		(width 0.15)
		(layer "B.Cu")
		(net 240)
	)
	(segment
		(start 133.234999 117)
		(end 132.909999 116.675)
		(width 0.15)
		(layer "B.Cu")
		(net 240)
	)
	(segment
		(start 132.655 116.675)
		(end 132.5 116.83)
		(width 0.15)
		(layer "B.Cu")
		(net 240)
	)
	(segment
		(start 127.025 120.875)
		(end 127.372488 120.875)
		(width 0.14)
		(layer "In5.Cu")
		(net 240)
	)
	(segment
		(start 127.372488 120.875)
		(end 127.925 120.322488)
		(width 0.14)
		(layer "In5.Cu")
		(net 240)
	)
	(segment
		(start 127.925 119.022488)
		(end 128.872488 118.075)
		(width 0.15)
		(layer "In5.Cu")
		(net 240)
	)
	(segment
		(start 132.072488 116.675)
		(end 132.345 116.675)
		(width 0.15)
		(layer "In5.Cu")
		(net 240)
	)
	(segment
		(start 128.872488 118.075)
		(end 130.672488 118.075)
		(width 0.15)
		(layer "In5.Cu")
		(net 240)
	)
	(segment
		(start 127.925 120.322488)
		(end 127.925 119.022488)
		(width 0.15)
		(layer "In5.Cu")
		(net 240)
	)
	(segment
		(start 126.875 121.025)
		(end 127.025 120.875)
		(width 0.14)
		(layer "In5.Cu")
		(net 240)
	)
	(segment
		(start 132.345 116.675)
		(end 132.5 116.83)
		(width 0.14)
		(layer "In5.Cu")
		(net 240)
	)
	(segment
		(start 130.672488 118.075)
		(end 132.072488 116.675)
		(width 0.15)
		(layer "In5.Cu")
		(net 240)
	)
	(segment
		(start 156.300004 107.85)
		(end 154.850001 107.85)
		(width 0.15)
		(layer "F.Cu")
		(net 241)
	)
	(segment
		(start 156.500002 108.049999)
		(end 156.300004 107.85)
		(width 0.15)
		(layer "F.Cu")
		(net 241)
	)
	(segment
		(start 156.500002 109.369999)
		(end 156.500002 108.049999)
		(width 0.15)
		(layer "F.Cu")
		(net 241)
	)
	(segment
		(start 156.500002 110.33)
		(end 155.820002 109.649998)
		(width 0.15)
		(layer "F.Cu")
		(net 302)
	)
	(segment
		(start 155.820002 109.649998)
		(end 155.375001 109.649998)
		(width 0.15)
		(layer "F.Cu")
		(net 302)
	)
	(segment
		(start 117.132 103.352)
		(end 116.88 103.1)
		(width 0.25)
		(layer "F.Cu")
		(net 303)
	)
	(segment
		(start 116.88 104.1)
		(end 116.88 103.1)
		(width 0.1)
		(layer "F.Cu")
		(net 303)
	)
	(segment
		(start 118.15 103.352)
		(end 117.132 103.352)
		(width 0.25)
		(layer "F.Cu")
		(net 303)
	)
	(segment
		(start 134.625 133.3)
		(end 134.5 133.425)
		(width 0.25)
		(layer "F.Cu")
		(net 304)
	)
	(segment
		(start 134.5 133.425)
		(end 134.5 134)
		(width 0.25)
		(layer "F.Cu")
		(net 304)
	)
	(via
		(at 139.45 140.45)
		(size 0.45)
		(drill 0.2)
		(layers "F.Cu" "B.Cu")
		(remove_unused_layers yes)
		(keep_end_layers yes)
		(zone_layer_connections)
		(net 304)
	)
	(via
		(at 134.625 133.3)
		(size 0.45)
		(drill 0.2)
		(layers "F.Cu" "B.Cu")
		(remove_unused_layers yes)
		(keep_end_layers yes)
		(zone_layer_connections)
		(net 304)
	)
	(segment
		(start 138.831932 138.558596)
		(end 140.441404 138.558596)
		(width 0.25)
		(layer "B.Cu")
		(net 304)
	)
	(segment
		(start 133.355004 131.1)
		(end 132.875002 130.619998)
		(width 0.1)
		(layer "B.Cu")
		(net 304)
	)
	(segment
		(start 136.75 141.38)
		(end 138.52 141.38)
		(width 0.25)
		(layer "B.Cu")
		(net 304)
	)
	(segment
		(start 134.35 131.2)
		(end 134.25 131.1)
		(width 0.1)
		(layer "B.Cu")
		(net 304)
	)
	(segment
		(start 134.75 141.38)
		(end 136.75 141.38)
		(width 0.25)
		(layer "B.Cu")
		(net 304)
	)
	(segment
		(start 134.625 133.3)
		(end 134.625 133.354998)
		(width 0.1)
		(layer "B.Cu")
		(net 304)
	)
	(segment
		(start 138.52 141.38)
		(end 140.441404 139.458596)
		(width 0.25)
		(layer "B.Cu")
		(net 304)
	)
	(segment
		(start 140.88 134.6)
		(end 140.88 136.1)
		(width 0.25)
		(layer "B.Cu")
		(net 304)
	)
	(segment
		(start 134.625 133.275)
		(end 134.35 133)
		(width 0.1)
		(layer "B.Cu")
		(net 304)
	)
	(segment
		(start 140.441404 139.458596)
		(end 140.441404 138.558596)
		(width 0.25)
		(layer "B.Cu")
		(net 304)
	)
	(segment
		(start 134.625 133.354998)
		(end 134.850002 133.58)
		(width 0.1)
		(layer "B.Cu")
		(net 304)
	)
	(segment
		(start 138.83 135.6)
		(end 139.33 136.1)
		(width 0.1)
		(layer "B.Cu")
		(net 304)
	)
	(segment
		(start 134.625 133.3)
		(end 134.625 133.275)
		(width 0.1)
		(layer "B.Cu")
		(net 304)
	)
	(segment
		(start 134.850002 133.58)
		(end 135.330002 133.1)
		(width 0.1)
		(layer "B.Cu")
		(net 304)
	)
	(segment
		(start 140.88 136.1)
		(end 140.88 137.580997)
		(width 0.25)
		(layer "B.Cu")
		(net 304)
	)
	(segment
		(start 139.33 136.1)
		(end 140.88 136.1)
		(width 0.1)
		(layer "B.Cu")
		(net 304)
	)
	(segment
		(start 135.330002 133.1)
		(end 136.37 133.1)
		(width 0.1)
		(layer "B.Cu")
		(net 304)
	)
	(segment
		(start 140.88 137.580997)
		(end 140.879999 137.580998)
		(width 0.25)
		(layer "B.Cu")
		(net 304)
	)
	(segment
		(start 134.25 131.1)
		(end 133.355004 131.1)
		(width 0.1)
		(layer "B.Cu")
		(net 304)
	)
	(segment
		(start 140.879999 138.120001)
		(end 140.879999 137.580998)
		(width 0.25)
		(layer "B.Cu")
		(net 304)
	)
	(segment
		(start 134.35 133)
		(end 134.35 131.2)
		(width 0.1)
		(layer "B.Cu")
		(net 304)
	)
	(segment
		(start 136.37 133.1)
		(end 136.870001 132.599999)
		(width 0.1)
		(layer "B.Cu")
		(net 304)
	)
	(segment
		(start 140.441404 138.558596)
		(end 140.879999 138.120001)
		(width 0.25)
		(layer "B.Cu")
		(net 304)
	)
	(segment
		(start 135 134)
		(end 135.8 134)
		(width 0.25)
		(layer "In5.Cu")
		(net 304)
	)
	(segment
		(start 135.8 134)
		(end 136 134.2)
		(width 0.25)
		(layer "In5.Cu")
		(net 304)
	)
	(segment
		(start 134.56 133.365)
		(end 134.56 133.56)
		(width 0.25)
		(layer "In5.Cu")
		(net 304)
	)
	(segment
		(start 135.4 137.8)
		(end 135.4 138.4)
		(width 0.25)
		(layer "In5.Cu")
		(net 304)
	)
	(segment
		(start 137.45 140.45)
		(end 139.45 140.45)
		(width 0.25)
		(layer "In5.Cu")
		(net 304)
	)
	(segment
		(start 136 134.2)
		(end 136 137.2)
		(width 0.25)
		(layer "In5.Cu")
		(net 304)
	)
	(segment
		(start 136 137.2)
		(end 135.4 137.8)
		(width 0.25)
		(layer "In5.Cu")
		(net 304)
	)
	(segment
		(start 135.4 138.4)
		(end 137.45 140.45)
		(width 0.25)
		(layer "In5.Cu")
		(net 304)
	)
	(segment
		(start 134.625 133.3)
		(end 134.56 133.365)
		(width 0.25)
		(layer "In5.Cu")
		(net 304)
	)
	(segment
		(start 134.56 133.56)
		(end 135 134)
		(width 0.25)
		(layer "In5.Cu")
		(net 304)
	)
	(segment
		(start 123.1 148.3)
		(end 123.1 148.375)
		(width 0.1)
		(layer "F.Cu")
		(net 305)
	)
	(segment
		(start 132.32 138.5)
		(end 132.5 138.5)
		(width 0.1)
		(layer "F.Cu")
		(net 305)
	)
	(segment
		(start 123.1 148.375)
		(end 122.999 148.476)
		(width 0.1)
		(layer "F.Cu")
		(net 305)
	)
	(segment
		(start 131.39 139.43)
		(end 132.32 138.5)
		(width 0.1)
		(layer "F.Cu")
		(net 305)
	)
	(segment
		(start 131.4 139.8)
		(end 131.39 139.79)
		(width 0.1)
		(layer "F.Cu")
		(net 305)
	)
	(segment
		(start 131.39 139.79)
		(end 131.39 139.43)
		(width 0.1)
		(layer "F.Cu")
		(net 305)
	)
	(segment
		(start 122.999 148.476)
		(end 122.999 149.1)
		(width 0.1)
		(layer "F.Cu")
		(net 305)
	)
	(via
		(at 127.8 143.38)
		(size 0.45)
		(drill 0.2)
		(layers "F.Cu" "B.Cu")
		(remove_unused_layers yes)
		(keep_end_layers yes)
		(zone_layer_connections)
		(net 305)
	)
	(via
		(at 131.4 139.8)
		(size 0.45)
		(drill 0.2)
		(layers "F.Cu" "B.Cu")
		(remove_unused_layers yes)
		(keep_end_layers yes)
		(zone_layer_connections)
		(net 305)
	)
	(via
		(at 123.1 148.3)
		(size 0.45)
		(drill 0.2)
		(layers "F.Cu" "B.Cu")
		(remove_unused_layers yes)
		(keep_end_layers yes)
		(zone_layer_connections)
		(net 305)
	)
	(segment
		(start 127.8 142.81)
		(end 127.8 143.38)
		(width 0.1)
		(layer "B.Cu")
		(net 305)
	)
	(segment
		(start 127.8 143.95)
		(end 127.8 143.38)
		(width 0.1)
		(layer "B.Cu")
		(net 305)
	)
	(segment
		(start 127.82 143.38)
		(end 127.8 143.38)
		(width 0.1)
		(layer "In3.Cu")
		(net 305)
	)
	(segment
		(start 125.1 147.6)
		(end 127.8 144.9)
		(width 0.1)
		(layer "In3.Cu")
		(net 305)
	)
	(segment
		(start 131.4 139.8)
		(end 127.82 143.38)
		(width 0.1)
		(layer "In3.Cu")
		(net 305)
	)
	(segment
		(start 123.8 147.6)
		(end 125.1 147.6)
		(width 0.1)
		(layer "In3.Cu")
		(net 305)
	)
	(segment
		(start 127.8 144.9)
		(end 127.8 143.38)
		(width 0.1)
		(layer "In3.Cu")
		(net 305)
	)
	(segment
		(start 123.1 148.3)
		(end 123.8 147.6)
		(width 0.1)
		(layer "In3.Cu")
		(net 305)
	)
	(segment
		(start 131.72 138.52)
		(end 132.24 138)
		(width 0.1)
		(layer "F.Cu")
		(net 306)
	)
	(segment
		(start 132.24 138)
		(end 132.5 138)
		(width 0.1)
		(layer "F.Cu")
		(net 306)
	)
	(segment
		(start 131.4 138.52)
		(end 131.72 138.52)
		(width 0.1)
		(layer "F.Cu")
		(net 306)
	)
	(segment
		(start 121.75 147.498)
		(end 121.75 146.45)
		(width 0.1)
		(layer "F.Cu")
		(net 306)
	)
	(via
		(at 126.8 143.35)
		(size 0.45)
		(drill 0.2)
		(layers "F.Cu" "B.Cu")
		(remove_unused_layers yes)
		(keep_end_layers yes)
		(zone_layer_connections)
		(net 306)
	)
	(via
		(at 121.75 146.45)
		(size 0.45)
		(drill 0.2)
		(layers "F.Cu" "B.Cu")
		(remove_unused_layers yes)
		(keep_end_layers yes)
		(zone_layer_connections)
		(net 306)
	)
	(via
		(at 131.4 138.52)
		(size 0.45)
		(drill 0.2)
		(layers "F.Cu" "B.Cu")
		(remove_unused_layers yes)
		(keep_end_layers yes)
		(zone_layer_connections)
		(net 306)
	)
	(segment
		(start 126.8 142.78)
		(end 126.8 143.35)
		(width 0.1)
		(layer "B.Cu")
		(net 306)
	)
	(segment
		(start 126.8 143.92)
		(end 126.8 143.35)
		(width 0.1)
		(layer "B.Cu")
		(net 306)
	)
	(segment
		(start 129.98 138.52)
		(end 131.4 138.52)
		(width 0.1)
		(layer "In3.Cu")
		(net 306)
	)
	(segment
		(start 126.8 144)
		(end 125.2 145.6)
		(width 0.1)
		(layer "In3.Cu")
		(net 306)
	)
	(segment
		(start 128.95 139.55)
		(end 129.98 138.52)
		(width 0.1)
		(layer "In3.Cu")
		(net 306)
	)
	(segment
		(start 126.8 142.8)
		(end 128.95 140.65)
		(width 0.1)
		(layer "In3.Cu")
		(net 306)
	)
	(segment
		(start 128.95 140.65)
		(end 128.95 139.55)
		(width 0.1)
		(layer "In3.Cu")
		(net 306)
	)
	(segment
		(start 125.2 145.6)
		(end 122.6 145.6)
		(width 0.1)
		(layer "In3.Cu")
		(net 306)
	)
	(segment
		(start 122.6 145.6)
		(end 121.75 146.45)
		(width 0.1)
		(layer "In3.Cu")
		(net 306)
	)
	(segment
		(start 126.8 143.35)
		(end 126.8 144)
		(width 0.1)
		(layer "In3.Cu")
		(net 306)
	)
	(segment
		(start 126.8 143.35)
		(end 126.8 142.8)
		(width 0.1)
		(layer "In3.Cu")
		(net 306)
	)
	(segment
		(start 163.519998 109.649997)
		(end 163.074998 109.649997)
		(width 0.15)
		(layer "F.Cu")
		(net 307)
	)
	(segment
		(start 164.199999 110.329999)
		(end 163.519998 109.649997)
		(width 0.15)
		(layer "F.Cu")
		(net 307)
	)
	(segment
		(start 122.825 138.427512)
		(end 122.825 141.927512)
		(width 0.19)
		(layer "F.Cu")
		(net 308)
	)
	(segment
		(start 124.75 135.255)
		(end 125.075 135.58)
		(width 0.19)
		(layer "F.Cu")
		(net 308)
	)
	(segment
		(start 125.075 136.177512)
		(end 122.825 138.427512)
		(width 0.19)
		(layer "F.Cu")
		(net 308)
	)
	(segment
		(start 125.075 135.58)
		(end 125.075 136.177512)
		(width 0.19)
		(layer "F.Cu")
		(net 308)
	)
	(segment
		(start 122.825 141.927512)
		(end 120.325 144.427512)
		(width 0.19)
		(layer "F.Cu")
		(net 308)
	)
	(segment
		(start 120.25 146.822999)
		(end 120.25 147.498)
		(width 0.19)
		(layer "F.Cu")
		(net 308)
	)
	(segment
		(start 124.75 135.23)
		(end 124.75 135.255)
		(width 0.19)
		(layer "F.Cu")
		(net 308)
	)
	(segment
		(start 120.325 146.747999)
		(end 120.25 146.822999)
		(width 0.19)
		(layer "F.Cu")
		(net 308)
	)
	(segment
		(start 120.325 144.427512)
		(end 120.325 146.747999)
		(width 0.19)
		(layer "F.Cu")
		(net 308)
	)
	(via
		(at 124.5 148.9)
		(size 0.45)
		(drill 0.2)
		(layers "F.Cu" "B.Cu")
		(remove_unused_layers yes)
		(keep_end_layers yes)
		(zone_layer_connections)
		(net 309)
	)
	(segment
		(start 124.675 146.03235)
		(end 124.675 139.572488)
		(width 0.19)
		(layer "B.Cu")
		(net 309)
	)
	(segment
		(start 126.925 136.035001)
		(end 127.25 135.710001)
		(width 0.19)
		(layer "B.Cu")
		(net 309)
	)
	(segment
		(start 124.075 147.972488)
		(end 124.675 147.372488)
		(width 0.19)
		(layer "B.Cu")
		(net 309)
	)
	(segment
		(start 126.925 137.322488)
		(end 126.925 136.035001)
		(width 0.19)
		(layer "B.Cu")
		(net 309)
	)
	(segment
		(start 124.885304 146.43235)
		(end 124.885304 146.242654)
		(width 0.19)
		(layer "B.Cu")
		(net 309)
	)
	(segment
		(start 124.675 139.572488)
		(end 126.925 137.322488)
		(width 0.19)
		(layer "B.Cu")
		(net 309)
	)
	(segment
		(start 124.675 147.372488)
		(end 124.675 146.642654)
		(width 0.19)
		(layer "B.Cu")
		(net 309)
	)
	(segment
		(start 124.247488 148.9)
		(end 124.075 148.727512)
		(width 0.19)
		(layer "B.Cu")
		(net 309)
	)
	(segment
		(start 127.25 135.710001)
		(end 127.25 135.23)
		(width 0.19)
		(layer "B.Cu")
		(net 309)
	)
	(segment
		(start 124.5 148.9)
		(end 124.247488 148.9)
		(width 0.19)
		(layer "B.Cu")
		(net 309)
	)
	(segment
		(start 124.075 148.727512)
		(end 124.075 147.972488)
		(width 0.19)
		(layer "B.Cu")
		(net 309)
	)
	(arc
		(start 124.885304 146.242654)
		(mid 124.854506 146.1683)
		(end 124.780152 146.137502)
		(width 0.19)
		(layer "B.Cu")
		(net 309)
	)
	(arc
		(start 124.780152 146.537502)
		(mid 124.854506 146.506704)
		(end 124.885304 146.43235)
		(width 0.19)
		(layer "B.Cu")
		(net 309)
	)
	(arc
		(start 124.675 146.642654)
		(mid 124.705798 146.5683)
		(end 124.780152 146.537502)
		(width 0.19)
		(layer "B.Cu")
		(net 309)
	)
	(arc
		(start 124.780152 146.137502)
		(mid 124.705798 146.106704)
		(end 124.675 146.03235)
		(width 0.19)
		(layer "B.Cu")
		(net 309)
	)
	(segment
		(start 164.199999 108.049998)
		(end 164 107.849999)
		(width 0.15)
		(layer "F.Cu")
		(net 310)
	)
	(segment
		(start 164.199999 109.369998)
		(end 164.199999 108.049998)
		(width 0.15)
		(layer "F.Cu")
		(net 310)
	)
	(segment
		(start 164 107.849999)
		(end 162.549998 107.849998)
		(width 0.15)
		(layer "F.Cu")
		(net 310)
	)
	(segment
		(start 125.425 136.322488)
		(end 123.175 138.572488)
		(width 0.19)
		(layer "F.Cu")
		(net 311)
	)
	(segment
		(start 120.675 146.747999)
		(end 120.75 146.822999)
		(width 0.19)
		(layer "F.Cu")
		(net 311)
	)
	(segment
		(start 120.75 146.822999)
		(end 120.75 147.498)
		(width 0.19)
		(layer "F.Cu")
		(net 311)
	)
	(segment
		(start 125.75 135.23)
		(end 125.75 135.255)
		(width 0.19)
		(layer "F.Cu")
		(net 311)
	)
	(segment
		(start 125.425 135.58)
		(end 125.425 136.322488)
		(width 0.19)
		(layer "F.Cu")
		(net 311)
	)
	(segment
		(start 125.75 135.255)
		(end 125.425 135.58)
		(width 0.19)
		(layer "F.Cu")
		(net 311)
	)
	(segment
		(start 123.175 142.072488)
		(end 120.675 144.572488)
		(width 0.19)
		(layer "F.Cu")
		(net 311)
	)
	(segment
		(start 123.175 138.572488)
		(end 123.175 142.072488)
		(width 0.19)
		(layer "F.Cu")
		(net 311)
	)
	(segment
		(start 120.675 144.572488)
		(end 120.675 146.747999)
		(width 0.19)
		(layer "F.Cu")
		(net 311)
	)
	(via
		(at 124 149.3)
		(size 0.45)
		(drill 0.2)
		(layers "F.Cu" "B.Cu")
		(remove_unused_layers yes)
		(keep_end_layers yes)
		(zone_layer_connections)
		(net 312)
	)
	(segment
		(start 123.725 147.827512)
		(end 124.325 147.227512)
		(width 0.19)
		(layer "B.Cu")
		(net 312)
	)
	(segment
		(start 126.575 137.177512)
		(end 126.575 136.035001)
		(width 0.19)
		(layer "B.Cu")
		(net 312)
	)
	(segment
		(start 123.725 148.872488)
		(end 123.725 147.827512)
		(width 0.19)
		(layer "B.Cu")
		(net 312)
	)
	(segment
		(start 126.25 135.710001)
		(end 126.25 135.23)
		(width 0.19)
		(layer "B.Cu")
		(net 312)
	)
	(segment
		(start 124 149.147488)
		(end 123.725 148.872488)
		(width 0.19)
		(layer "B.Cu")
		(net 312)
	)
	(segment
		(start 124.325 139.427512)
		(end 126.575 137.177512)
		(width 0.19)
		(layer "B.Cu")
		(net 312)
	)
	(segment
		(start 126.575 136.035001)
		(end 126.25 135.710001)
		(width 0.19)
		(layer "B.Cu")
		(net 312)
	)
	(segment
		(start 124.325 147.227512)
		(end 124.325 139.427512)
		(width 0.19)
		(layer "B.Cu")
		(net 312)
	)
	(segment
		(start 124 149.3)
		(end 124 149.147488)
		(width 0.19)
		(layer "B.Cu")
		(net 312)
	)
	(segment
		(start 148.8 109.37)
		(end 148.8 108.049999)
		(width 0.15)
		(layer "F.Cu")
		(net 313)
	)
	(segment
		(start 148.600002 107.85)
		(end 147.149999 107.849999)
		(width 0.15)
		(layer "F.Cu")
		(net 313)
	)
	(segment
		(start 148.8 108.049999)
		(end 148.600002 107.85)
		(width 0.15)
		(layer "F.Cu")
		(net 313)
	)
	(segment
		(start 117.32 118)
		(end 117.295 118)
		(width 0.19)
		(layer "F.Cu")
		(net 314)
	)
	(segment
		(start 117.295 118)
		(end 116.97 118.325)
		(width 0.19)
		(layer "F.Cu")
		(net 314)
	)
	(segment
		(start 116.25 118.325)
		(end 116.1 118.175)
		(width 0.19)
		(layer "F.Cu")
		(net 314)
	)
	(segment
		(start 116.97 118.325)
		(end 116.25 118.325)
		(width 0.19)
		(layer "F.Cu")
		(net 314)
	)
	(via
		(at 143.645 73.25)
		(size 0.45)
		(drill 0.2)
		(layers "F.Cu" "B.Cu")
		(remove_unused_layers yes)
		(keep_end_layers yes)
		(zone_layer_connections)
		(net 314)
	)
	(via
		(at 116.1 118.175)
		(size 0.45)
		(drill 0.2)
		(layers "F.Cu" "B.Cu")
		(remove_unused_layers yes)
		(keep_end_layers yes)
		(zone_layer_connections)
		(net 314)
	)
	(segment
		(start 142.622488 73.575)
		(end 143.32 73.575)
		(width 0.21)
		(layer "In5.Cu")
		(net 314)
	)
	(segment
		(start 140.527512 72.825)
		(end 141.872488 72.825)
		(width 0.21)
		(layer "In5.Cu")
		(net 314)
	)
	(segment
		(start 116.1 118.175)
		(end 116.25 118.325)
		(width 0.21)
		(layer "In5.Cu")
		(net 314)
	)
	(segment
		(start 120.625 112.642766)
		(end 119.550001 111.567767)
		(width 0.21)
		(layer "In5.Cu")
		(net 314)
	)
	(segment
		(start 117.725 117.477512)
		(end 117.725 116.077512)
		(width 0.21)
		(layer "In5.Cu")
		(net 314)
	)
	(segment
		(start 133.45 75.302512)
		(end 134.927512 73.825)
		(width 0.21)
		(layer "In5.Cu")
		(net 314)
	)
	(segment
		(start 120.625 115.177512)
		(end 120.625 112.642766)
		(width 0.21)
		(layer "In5.Cu")
		(net 314)
	)
	(segment
		(start 119.550001 111.567767)
		(end 119.550001 101.882237)
		(width 0.21)
		(layer "In5.Cu")
		(net 314)
	)
	(segment
		(start 116.877512 118.325)
		(end 117.725 117.477512)
		(width 0.21)
		(layer "In5.Cu")
		(net 314)
	)
	(segment
		(start 139.527512 73.825)
		(end 140.527512 72.825)
		(width 0.21)
		(layer "In5.Cu")
		(net 314)
	)
	(segment
		(start 118.377512 115.425)
		(end 120.377512 115.425)
		(width 0.21)
		(layer "In5.Cu")
		(net 314)
	)
	(segment
		(start 143.32 73.575)
		(end 143.645 73.25)
		(width 0.21)
		(layer "In5.Cu")
		(net 314)
	)
	(segment
		(start 133.45 87.982238)
		(end 133.45 75.302512)
		(width 0.21)
		(layer "In5.Cu")
		(net 314)
	)
	(segment
		(start 120.377512 115.425)
		(end 120.625 115.177512)
		(width 0.21)
		(layer "In5.Cu")
		(net 314)
	)
	(segment
		(start 141.872488 72.825)
		(end 142.622488 73.575)
		(width 0.21)
		(layer "In5.Cu")
		(net 314)
	)
	(segment
		(start 119.550001 101.882237)
		(end 133.45 87.982238)
		(width 0.21)
		(layer "In5.Cu")
		(net 314)
	)
	(segment
		(start 117.725 116.077512)
		(end 118.377512 115.425)
		(width 0.21)
		(layer "In5.Cu")
		(net 314)
	)
	(segment
		(start 116.25 118.325)
		(end 116.877512 118.325)
		(width 0.21)
		(layer "In5.Cu")
		(net 314)
	)
	(segment
		(start 134.927512 73.825)
		(end 139.527512 73.825)
		(width 0.21)
		(layer "In5.Cu")
		(net 314)
	)
	(segment
		(start 123.785 121.305)
		(end 123.9 121.19)
		(width 0.1)
		(layer "F.Cu")
		(net 315)
	)
	(segment
		(start 123.033701 121.42)
		(end 123.507366 121.42)
		(width 0.1)
		(layer "F.Cu")
		(net 315)
	)
	(segment
		(start 122.81799 121.365478)
		(end 120.127512 118.675)
		(width 0.19)
		(layer "F.Cu")
		(net 315)
	)
	(segment
		(start 118.305 119)
		(end 118.28 119)
		(width 0.19)
		(layer "F.Cu")
		(net 315)
	)
	(segment
		(start 120.127512 118.675)
		(end 118.63 118.675)
		(width 0.19)
		(layer "F.Cu")
		(net 315)
	)
	(segment
		(start 118.63 118.675)
		(end 118.305 119)
		(width 0.19)
		(layer "F.Cu")
		(net 315)
	)
	(segment
		(start 123.033701 121.42)
		(end 122.979179 121.365478)
		(width 0.1)
		(layer "F.Cu")
		(net 315)
	)
	(segment
		(start 122.979179 121.365478)
		(end 122.81799 121.365478)
		(width 0.19)
		(layer "F.Cu")
		(net 315)
	)
	(arc
		(start 123.507366 121.42)
		(mid 123.657621 121.390112)
		(end 123.785 121.305)
		(width 0.1)
		(layer "F.Cu")
		(net 315)
	)
	(segment
		(start 120.227512 121.675)
		(end 121.752512 123.2)
		(width 0.19)
		(layer "F.Cu")
		(net 316)
	)
	(segment
		(start 118.305 122)
		(end 118.63 121.675)
		(width 0.19)
		(layer "F.Cu")
		(net 316)
	)
	(segment
		(start 123.035 123.26)
		(end 122.975 123.2)
		(width 0.1)
		(layer "F.Cu")
		(net 316)
	)
	(segment
		(start 123.785 123.145)
		(end 123.9 123.03)
		(width 0.1)
		(layer "F.Cu")
		(net 316)
	)
	(segment
		(start 118.28 122)
		(end 118.305 122)
		(width 0.19)
		(layer "F.Cu")
		(net 316)
	)
	(segment
		(start 121.752512 123.2)
		(end 122.975 123.2)
		(width 0.19)
		(layer "F.Cu")
		(net 316)
	)
	(segment
		(start 118.63 121.675)
		(end 120.227512 121.675)
		(width 0.19)
		(layer "F.Cu")
		(net 316)
	)
	(segment
		(start 123.035 123.26)
		(end 123.507366 123.26)
		(width 0.1)
		(layer "F.Cu")
		(net 316)
	)
	(arc
		(start 123.507366 123.26)
		(mid 123.657621 123.230112)
		(end 123.785 123.145)
		(width 0.1)
		(layer "F.Cu")
		(net 316)
	)
	(segment
		(start 116.25 121.325)
		(end 116.1 121.175)
		(width 0.19)
		(layer "F.Cu")
		(net 317)
	)
	(segment
		(start 117.32 121)
		(end 117.295 121)
		(width 0.19)
		(layer "F.Cu")
		(net 317)
	)
	(segment
		(start 116.97 121.325)
		(end 116.25 121.325)
		(width 0.19)
		(layer "F.Cu")
		(net 317)
	)
	(segment
		(start 117.295 121)
		(end 116.97 121.325)
		(width 0.19)
		(layer "F.Cu")
		(net 317)
	)
	(via
		(at 142.78 75.75)
		(size 0.45)
		(drill 0.2)
		(layers "F.Cu" "B.Cu")
		(remove_unused_layers yes)
		(keep_end_layers yes)
		(zone_layer_connections)
		(net 317)
	)
	(via
		(at 116.1 121.175)
		(size 0.45)
		(drill 0.2)
		(layers "F.Cu" "B.Cu")
		(remove_unused_layers yes)
		(keep_end_layers yes)
		(zone_layer_connections)
		(net 317)
	)
	(segment
		(start 120.377512 121.325)
		(end 121.075 120.627512)
		(width 0.21)
		(layer "In5.Cu")
		(net 317)
	)
	(segment
		(start 121.075 120.627512)
		(end 121.075 117.277512)
		(width 0.21)
		(layer "In5.Cu")
		(net 317)
	)
	(segment
		(start 135.375 76.425)
		(end 139.527512 76.425)
		(width 0.21)
		(layer "In5.Cu")
		(net 317)
	)
	(segment
		(start 142.455 76.075)
		(end 142.78 75.75)
		(width 0.21)
		(layer "In5.Cu")
		(net 317)
	)
	(segment
		(start 141.922488 76.075)
		(end 142.455 76.075)
		(width 0.21)
		(layer "In5.Cu")
		(net 317)
	)
	(segment
		(start 116.1 121.175)
		(end 116.25 121.325)
		(width 0.21)
		(layer "In5.Cu")
		(net 317)
	)
	(segment
		(start 140.327512 75.625)
		(end 141.472488 75.625)
		(width 0.21)
		(layer "In5.Cu")
		(net 317)
	)
	(segment
		(start 120.8 111.05)
		(end 120.8 102.4)
		(width 0.21)
		(layer "In5.Cu")
		(net 317)
	)
	(segment
		(start 121.075 117.277512)
		(end 121.875 116.477512)
		(width 0.21)
		(layer "In5.Cu")
		(net 317)
	)
	(segment
		(start 134.699998 77.100002)
		(end 135.375 76.425)
		(width 0.21)
		(layer "In5.Cu")
		(net 317)
	)
	(segment
		(start 139.527512 76.425)
		(end 140.327512 75.625)
		(width 0.21)
		(layer "In5.Cu")
		(net 317)
	)
	(segment
		(start 121.875 116.477512)
		(end 121.875 112.125)
		(width 0.21)
		(layer "In5.Cu")
		(net 317)
	)
	(segment
		(start 134.699998 88.500002)
		(end 134.699998 77.100002)
		(width 0.21)
		(layer "In5.Cu")
		(net 317)
	)
	(segment
		(start 120.8 102.4)
		(end 134.699998 88.500002)
		(width 0.21)
		(layer "In5.Cu")
		(net 317)
	)
	(segment
		(start 121.875 112.125)
		(end 120.8 111.05)
		(width 0.21)
		(layer "In5.Cu")
		(net 317)
	)
	(segment
		(start 141.472488 75.625)
		(end 141.922488 76.075)
		(width 0.21)
		(layer "In5.Cu")
		(net 317)
	)
	(segment
		(start 116.25 121.325)
		(end 120.377512 121.325)
		(width 0.21)
		(layer "In5.Cu")
		(net 317)
	)
	(segment
		(start 121.7 125.045)
		(end 121.695 125.05)
		(width 0.19)
		(layer "F.Cu")
		(net 318)
	)
	(segment
		(start 123.025 125.045)
		(end 121.7 125.045)
		(width 0.19)
		(layer "F.Cu")
		(net 318)
	)
	(segment
		(start 123.08 125.1)
		(end 123.507366 125.1)
		(width 0.1)
		(layer "F.Cu")
		(net 318)
	)
	(segment
		(start 121.695 125.05)
		(end 120.552512 125.05)
		(width 0.19)
		(layer "F.Cu")
		(net 318)
	)
	(segment
		(start 120.177512 124.675)
		(end 120.552512 125.05)
		(width 0.19)
		(layer "F.Cu")
		(net 318)
	)
	(segment
		(start 118.305 125)
		(end 118.63 124.675)
		(width 0.19)
		(layer "F.Cu")
		(net 318)
	)
	(segment
		(start 123.785 124.985)
		(end 123.9 124.87)
		(width 0.1)
		(layer "F.Cu")
		(net 318)
	)
	(segment
		(start 118.28 125)
		(end 118.305 125)
		(width 0.19)
		(layer "F.Cu")
		(net 318)
	)
	(segment
		(start 118.63 124.675)
		(end 120.177512 124.675)
		(width 0.19)
		(layer "F.Cu")
		(net 318)
	)
	(segment
		(start 123.08 125.1)
		(end 123.025 125.045)
		(width 0.1)
		(layer "F.Cu")
		(net 318)
	)
	(arc
		(start 123.507366 125.1)
		(mid 123.657621 125.070112)
		(end 123.785 124.985)
		(width 0.1)
		(layer "F.Cu")
		(net 318)
	)
	(segment
		(start 116.97 124.325)
		(end 116.25 124.325)
		(width 0.19)
		(layer "F.Cu")
		(net 319)
	)
	(segment
		(start 117.32 124)
		(end 117.295 124)
		(width 0.19)
		(layer "F.Cu")
		(net 319)
	)
	(segment
		(start 116.25 124.325)
		(end 116.1 124.175)
		(width 0.19)
		(layer "F.Cu")
		(net 319)
	)
	(segment
		(start 117.295 124)
		(end 116.97 124.325)
		(width 0.19)
		(layer "F.Cu")
		(net 319)
	)
	(via
		(at 116.1 124.175)
		(size 0.45)
		(drill 0.2)
		(layers "F.Cu" "B.Cu")
		(remove_unused_layers yes)
		(keep_end_layers yes)
		(zone_layer_connections)
		(net 319)
	)
	(via
		(at 142.78 78.75)
		(size 0.45)
		(drill 0.2)
		(layers "F.Cu" "B.Cu")
		(remove_unused_layers yes)
		(keep_end_layers yes)
		(zone_layer_connections)
		(net 319)
	)
	(segment
		(start 121.95 110.573654)
		(end 121.95 103.755026)
		(width 0.21)
		(layer "In5.Cu")
		(net 319)
	)
	(segment
		(start 142.455 79.075)
		(end 142.78 78.75)
		(width 0.21)
		(layer "In5.Cu")
		(net 319)
	)
	(segment
		(start 137.625 80.375)
		(end 139.375 78.625)
		(width 0.21)
		(layer "In5.Cu")
		(net 319)
	)
	(segment
		(start 122.075 118.177512)
		(end 123.025 117.227512)
		(width 0.21)
		(layer "In5.Cu")
		(net 319)
	)
	(segment
		(start 129.749999 99.250001)
		(end 135.8 93.2)
		(width 0.21)
		(layer "In5.Cu")
		(net 319)
	)
	(segment
		(start 123.025 111.648654)
		(end 121.95 110.573654)
		(width 0.21)
		(layer "In5.Cu")
		(net 319)
	)
	(segment
		(start 141.922488 79.075)
		(end 142.455 79.075)
		(width 0.21)
		(layer "In5.Cu")
		(net 319)
	)
	(segment
		(start 116.25 124.325)
		(end 121.177512 124.325)
		(width 0.21)
		(layer "In5.Cu")
		(net 319)
	)
	(segment
		(start 135.8 93.2)
		(end 135.8 83.852512)
		(width 0.21)
		(layer "In5.Cu")
		(net 319)
	)
	(segment
		(start 139.375 78.625)
		(end 141.472488 78.625)
		(width 0.21)
		(layer "In5.Cu")
		(net 319)
	)
	(segment
		(start 141.472488 78.625)
		(end 141.922488 79.075)
		(width 0.21)
		(layer "In5.Cu")
		(net 319)
	)
	(segment
		(start 135.8 83.852512)
		(end 137.625 82.027512)
		(width 0.21)
		(layer "In5.Cu")
		(net 319)
	)
	(segment
		(start 121.95 103.755026)
		(end 126.455025 99.250001)
		(width 0.21)
		(layer "In5.Cu")
		(net 319)
	)
	(segment
		(start 126.455025 99.250001)
		(end 129.749999 99.250001)
		(width 0.21)
		(layer "In5.Cu")
		(net 319)
	)
	(segment
		(start 137.625 82.027512)
		(end 137.625 80.375)
		(width 0.21)
		(layer "In5.Cu")
		(net 319)
	)
	(segment
		(start 123.025 117.227512)
		(end 123.025 111.648654)
		(width 0.21)
		(layer "In5.Cu")
		(net 319)
	)
	(segment
		(start 116.1 124.175)
		(end 116.25 124.325)
		(width 0.21)
		(layer "In5.Cu")
		(net 319)
	)
	(segment
		(start 122.075 123.427512)
		(end 122.075 118.177512)
		(width 0.21)
		(layer "In5.Cu")
		(net 319)
	)
	(segment
		(start 121.177512 124.325)
		(end 122.075 123.427512)
		(width 0.21)
		(layer "In5.Cu")
		(net 319)
	)
	(segment
		(start 121.572488 127.675)
		(end 122.362488 126.885)
		(width 0.19)
		(layer "F.Cu")
		(net 320)
	)
	(segment
		(start 118.28 128)
		(end 118.305 128)
		(width 0.19)
		(layer "F.Cu")
		(net 320)
	)
	(segment
		(start 123.105 126.94)
		(end 123.507366 126.94)
		(width 0.1)
		(layer "F.Cu")
		(net 320)
	)
	(segment
		(start 122.362488 126.885)
		(end 123.05 126.885)
		(width 0.19)
		(layer "F.Cu")
		(net 320)
	)
	(segment
		(start 123.9 126.71)
		(end 123.785 126.825)
		(width 0.1)
		(layer "F.Cu")
		(net 320)
	)
	(segment
		(start 123.05 126.885)
		(end 123.105 126.94)
		(width 0.1)
		(layer "F.Cu")
		(net 320)
	)
	(segment
		(start 118.63 127.675)
		(end 121.572488 127.675)
		(width 0.19)
		(layer "F.Cu")
		(net 320)
	)
	(segment
		(start 118.305 128)
		(end 118.63 127.675)
		(width 0.19)
		(layer "F.Cu")
		(net 320)
	)
	(arc
		(start 123.785 126.825)
		(mid 123.657621 126.910112)
		(end 123.507366 126.94)
		(width 0.1)
		(layer "F.Cu")
		(net 320)
	)
	(segment
		(start 116.25 127.325)
		(end 116.1 127.175)
		(width 0.19)
		(layer "F.Cu")
		(net 321)
	)
	(segment
		(start 117.295 127)
		(end 116.97 127.325)
		(width 0.19)
		(layer "F.Cu")
		(net 321)
	)
	(segment
		(start 116.97 127.325)
		(end 116.25 127.325)
		(width 0.19)
		(layer "F.Cu")
		(net 321)
	)
	(segment
		(start 117.32 127)
		(end 117.295 127)
		(width 0.19)
		(layer "F.Cu")
		(net 321)
	)
	(via
		(at 142.78 81.75)
		(size 0.45)
		(drill 0.2)
		(layers "F.Cu" "B.Cu")
		(remove_unused_layers yes)
		(keep_end_layers yes)
		(zone_layer_connections)
		(net 321)
	)
	(via
		(at 116.1 127.175)
		(size 0.45)
		(drill 0.2)
		(layers "F.Cu" "B.Cu")
		(remove_unused_layers yes)
		(keep_end_layers yes)
		(zone_layer_connections)
		(net 321)
	)
	(segment
		(start 123.075 118.477512)
		(end 124.225 117.327512)
		(width 0.21)
		(layer "In5.Cu")
		(net 321)
	)
	(segment
		(start 141.722488 82.075)
		(end 142.455 82.075)
		(width 0.21)
		(layer "In5.Cu")
		(net 321)
	)
	(segment
		(start 130.655028 100.45)
		(end 137.288479 93.816549)
		(width 0.21)
		(layer "In5.Cu")
		(net 321)
	)
	(segment
		(start 123.15 104.252082)
		(end 126.952082 100.45)
		(width 0.21)
		(layer "In5.Cu")
		(net 321)
	)
	(segment
		(start 126.952082 100.45)
		(end 130.655028 100.45)
		(width 0.21)
		(layer "In5.Cu")
		(net 321)
	)
	(segment
		(start 121.427512 127.325)
		(end 123.075 125.677512)
		(width 0.21)
		(layer "In5.Cu")
		(net 321)
	)
	(segment
		(start 141.272488 81.625)
		(end 141.722488 82.075)
		(width 0.21)
		(layer "In5.Cu")
		(net 321)
	)
	(segment
		(start 123.075 125.677512)
		(end 123.075 118.477512)
		(width 0.21)
		(layer "In5.Cu")
		(net 321)
	)
	(segment
		(start 137.288479 93.816549)
		(end 137.288479 83.864033)
		(width 0.21)
		(layer "In5.Cu")
		(net 321)
	)
	(segment
		(start 123.15 110.076598)
		(end 123.15 104.252082)
		(width 0.21)
		(layer "In5.Cu")
		(net 321)
	)
	(segment
		(start 142.455 82.075)
		(end 142.78 81.75)
		(width 0.21)
		(layer "In5.Cu")
		(net 321)
	)
	(segment
		(start 124.225 117.327512)
		(end 124.225 111.151598)
		(width 0.21)
		(layer "In5.Cu")
		(net 321)
	)
	(segment
		(start 137.288479 83.864033)
		(end 139.527512 81.625)
		(width 0.21)
		(layer "In5.Cu")
		(net 321)
	)
	(segment
		(start 139.527512 81.625)
		(end 141.272488 81.625)
		(width 0.21)
		(layer "In5.Cu")
		(net 321)
	)
	(segment
		(start 116.25 127.325)
		(end 121.427512 127.325)
		(width 0.21)
		(layer "In5.Cu")
		(net 321)
	)
	(segment
		(start 116.1 127.175)
		(end 116.25 127.325)
		(width 0.21)
		(layer "In5.Cu")
		(net 321)
	)
	(segment
		(start 124.225 111.151598)
		(end 123.15 110.076598)
		(width 0.21)
		(layer "In5.Cu")
		(net 321)
	)
	(segment
		(start 117.295 119)
		(end 116.97 118.675)
		(width 0.19)
		(layer "F.Cu")
		(net 322)
	)
	(segment
		(start 116.25 118.675)
		(end 116.1 118.825)
		(width 0.19)
		(layer "F.Cu")
		(net 322)
	)
	(segment
		(start 116.97 118.675)
		(end 116.25 118.675)
		(width 0.19)
		(layer "F.Cu")
		(net 322)
	)
	(segment
		(start 117.32 119)
		(end 117.295 119)
		(width 0.19)
		(layer "F.Cu")
		(net 322)
	)
	(via
		(at 116.1 118.825)
		(size 0.45)
		(drill 0.2)
		(layers "F.Cu" "B.Cu")
		(remove_unused_layers yes)
		(keep_end_layers yes)
		(zone_layer_connections)
		(net 322)
	)
	(via
		(at 143.645 74.25)
		(size 0.45)
		(drill 0.2)
		(layers "F.Cu" "B.Cu")
		(remove_unused_layers yes)
		(keep_end_layers yes)
		(zone_layer_connections)
		(net 322)
	)
	(segment
		(start 116.1 118.825)
		(end 116.25 118.675)
		(width 0.21)
		(layer "In5.Cu")
		(net 322)
	)
	(segment
		(start 119.900001 102.027211)
		(end 133.8 88.127212)
		(width 0.21)
		(layer "In5.Cu")
		(net 322)
	)
	(segment
		(start 119.900001 111.422793)
		(end 119.900001 102.027211)
		(width 0.21)
		(layer "In5.Cu")
		(net 322)
	)
	(segment
		(start 116.25 118.675)
		(end 117.022488 118.675)
		(width 0.21)
		(layer "In5.Cu")
		(net 322)
	)
	(segment
		(start 120.975 115.322488)
		(end 120.975 112.497792)
		(width 0.21)
		(layer "In5.Cu")
		(net 322)
	)
	(segment
		(start 133.8 88.127212)
		(end 133.8 75.447488)
		(width 0.21)
		(layer "In5.Cu")
		(net 322)
	)
	(segment
		(start 133.8 75.447488)
		(end 135.072488 74.175)
		(width 0.21)
		(layer "In5.Cu")
		(net 322)
	)
	(segment
		(start 135.072488 74.175)
		(end 139.672488 74.175)
		(width 0.21)
		(layer "In5.Cu")
		(net 322)
	)
	(segment
		(start 118.075 116.222488)
		(end 118.522488 115.775)
		(width 0.21)
		(layer "In5.Cu")
		(net 322)
	)
	(segment
		(start 120.522488 115.775)
		(end 120.975 115.322488)
		(width 0.21)
		(layer "In5.Cu")
		(net 322)
	)
	(segment
		(start 139.672488 74.175)
		(end 140.672488 73.175)
		(width 0.21)
		(layer "In5.Cu")
		(net 322)
	)
	(segment
		(start 117.022488 118.675)
		(end 118.075 117.622488)
		(width 0.21)
		(layer "In5.Cu")
		(net 322)
	)
	(segment
		(start 141.727512 73.175)
		(end 142.477512 73.925)
		(width 0.21)
		(layer "In5.Cu")
		(net 322)
	)
	(segment
		(start 140.672488 73.175)
		(end 141.727512 73.175)
		(width 0.21)
		(layer "In5.Cu")
		(net 322)
	)
	(segment
		(start 143.32 73.925)
		(end 143.645 74.25)
		(width 0.21)
		(layer "In5.Cu")
		(net 322)
	)
	(segment
		(start 120.975 112.497792)
		(end 119.900001 111.422793)
		(width 0.21)
		(layer "In5.Cu")
		(net 322)
	)
	(segment
		(start 118.522488 115.775)
		(end 120.522488 115.775)
		(width 0.21)
		(layer "In5.Cu")
		(net 322)
	)
	(segment
		(start 142.477512 73.925)
		(end 143.32 73.925)
		(width 0.21)
		(layer "In5.Cu")
		(net 322)
	)
	(segment
		(start 118.075 117.622488)
		(end 118.075 116.222488)
		(width 0.21)
		(layer "In5.Cu")
		(net 322)
	)
	(segment
		(start 123.06 120.96)
		(end 122.907488 120.96)
		(width 0.19)
		(layer "F.Cu")
		(net 323)
	)
	(segment
		(start 118.63 118.325)
		(end 118.305 118)
		(width 0.19)
		(layer "F.Cu")
		(net 323)
	)
	(segment
		(start 120.272488 118.325)
		(end 118.63 118.325)
		(width 0.19)
		(layer "F.Cu")
		(net 323)
	)
	(segment
		(start 123.175 120.96)
		(end 123.06 120.96)
		(width 0.1)
		(layer "F.Cu")
		(net 323)
	)
	(segment
		(start 118.305 118)
		(end 118.28 118)
		(width 0.19)
		(layer "F.Cu")
		(net 323)
	)
	(segment
		(start 123.44 121.19)
		(end 123.522574 121.19)
		(width 0.1)
		(layer "F.Cu")
		(net 323)
	)
	(segment
		(start 122.907488 120.96)
		(end 120.272488 118.325)
		(width 0.19)
		(layer "F.Cu")
		(net 323)
	)
	(segment
		(start 123.625 121.087573)
		(end 123.625 121.062426)
		(width 0.1)
		(layer "F.Cu")
		(net 323)
	)
	(segment
		(start 123.522574 120.96)
		(end 123.175 120.96)
		(width 0.1)
		(layer "F.Cu")
		(net 323)
	)
	(arc
		(start 123.522574 121.19)
		(mid 123.561771 121.182203)
		(end 123.595 121.16)
		(width 0.1)
		(layer "F.Cu")
		(net 323)
	)
	(arc
		(start 123.595 121.16)
		(mid 123.617204 121.12677)
		(end 123.625 121.087573)
		(width 0.1)
		(layer "F.Cu")
		(net 323)
	)
	(arc
		(start 123.625 121.062426)
		(mid 123.617204 121.023229)
		(end 123.595 120.99)
		(width 0.1)
		(layer "F.Cu")
		(net 323)
	)
	(arc
		(start 123.595 120.99)
		(mid 123.561771 120.967796)
		(end 123.522574 120.96)
		(width 0.1)
		(layer "F.Cu")
		(net 323)
	)
	(segment
		(start 116.97 121.675)
		(end 116.25 121.675)
		(width 0.19)
		(layer "F.Cu")
		(net 324)
	)
	(segment
		(start 116.25 121.675)
		(end 116.1 121.825)
		(width 0.19)
		(layer "F.Cu")
		(net 324)
	)
	(segment
		(start 117.295 122)
		(end 116.97 121.675)
		(width 0.19)
		(layer "F.Cu")
		(net 324)
	)
	(segment
		(start 117.32 122)
		(end 117.295 122)
		(width 0.19)
		(layer "F.Cu")
		(net 324)
	)
	(via
		(at 116.1 121.825)
		(size 0.45)
		(drill 0.2)
		(layers "F.Cu" "B.Cu")
		(remove_unused_layers yes)
		(keep_end_layers yes)
		(zone_layer_connections)
		(net 324)
	)
	(via
		(at 142.78 76.75)
		(size 0.45)
		(drill 0.2)
		(layers "F.Cu" "B.Cu")
		(remove_unused_layers yes)
		(keep_end_layers yes)
		(zone_layer_connections)
		(net 324)
	)
	(segment
		(start 122.225 116.622488)
		(end 122.225 111.980026)
		(width 0.21)
		(layer "In5.Cu")
		(net 324)
	)
	(segment
		(start 139.672488 76.775)
		(end 140.472488 75.975)
		(width 0.21)
		(layer "In5.Cu")
		(net 324)
	)
	(segment
		(start 121.425 120.772488)
		(end 121.425 117.422488)
		(width 0.21)
		(layer "In5.Cu")
		(net 324)
	)
	(segment
		(start 121.425 117.422488)
		(end 122.225 116.622488)
		(width 0.21)
		(layer "In5.Cu")
		(net 324)
	)
	(segment
		(start 141.777512 76.425)
		(end 142.455 76.425)
		(width 0.21)
		(layer "In5.Cu")
		(net 324)
	)
	(segment
		(start 135.049997 88.644977)
		(end 135.049997 77.244977)
		(width 0.21)
		(layer "In5.Cu")
		(net 324)
	)
	(segment
		(start 135.519974 76.775)
		(end 139.672488 76.775)
		(width 0.21)
		(layer "In5.Cu")
		(net 324)
	)
	(segment
		(start 122.225 111.980026)
		(end 121.149999 110.905025)
		(width 0.21)
		(layer "In5.Cu")
		(net 324)
	)
	(segment
		(start 116.1 121.825)
		(end 116.25 121.675)
		(width 0.21)
		(layer "In5.Cu")
		(net 324)
	)
	(segment
		(start 121.149999 102.544975)
		(end 135.049997 88.644977)
		(width 0.21)
		(layer "In5.Cu")
		(net 324)
	)
	(segment
		(start 140.472488 75.975)
		(end 141.327512 75.975)
		(width 0.21)
		(layer "In5.Cu")
		(net 324)
	)
	(segment
		(start 135.049997 77.244977)
		(end 135.519974 76.775)
		(width 0.21)
		(layer "In5.Cu")
		(net 324)
	)
	(segment
		(start 120.522488 121.675)
		(end 121.425 120.772488)
		(width 0.21)
		(layer "In5.Cu")
		(net 324)
	)
	(segment
		(start 142.455 76.425)
		(end 142.78 76.75)
		(width 0.21)
		(layer "In5.Cu")
		(net 324)
	)
	(segment
		(start 121.149999 110.905025)
		(end 121.149999 102.544975)
		(width 0.21)
		(layer "In5.Cu")
		(net 324)
	)
	(segment
		(start 141.327512 75.975)
		(end 141.777512 76.425)
		(width 0.21)
		(layer "In5.Cu")
		(net 324)
	)
	(segment
		(start 116.25 121.675)
		(end 120.522488 121.675)
		(width 0.21)
		(layer "In5.Cu")
		(net 324)
	)
	(segment
		(start 123.625 122.927573)
		(end 123.625 122.902426)
		(width 0.1)
		(layer "F.Cu")
		(net 325)
	)
	(segment
		(start 121.897488 122.85)
		(end 122.975 122.85)
		(width 0.19)
		(layer "F.Cu")
		(net 325)
	)
	(segment
		(start 123.44 123.03)
		(end 123.522574 123.03)
		(width 0.1)
		(layer "F.Cu")
		(net 325)
	)
	(segment
		(start 118.305 121)
		(end 118.63 121.325)
		(width 0.19)
		(layer "F.Cu")
		(net 325)
	)
	(segment
		(start 118.63 121.325)
		(end 120.372488 121.325)
		(width 0.19)
		(layer "F.Cu")
		(net 325)
	)
	(segment
		(start 120.372488 121.325)
		(end 121.897488 122.85)
		(width 0.19)
		(layer "F.Cu")
		(net 325)
	)
	(segment
		(start 118.28 121)
		(end 118.305 121)
		(width 0.19)
		(layer "F.Cu")
		(net 325)
	)
	(segment
		(start 123.15 122.8)
		(end 123.025 122.8)
		(width 0.1)
		(layer "F.Cu")
		(net 325)
	)
	(segment
		(start 123.025 122.8)
		(end 122.975 122.85)
		(width 0.1)
		(layer "F.Cu")
		(net 325)
	)
	(segment
		(start 123.522574 122.8)
		(end 123.15 122.8)
		(width 0.1)
		(layer "F.Cu")
		(net 325)
	)
	(arc
		(start 123.595 122.83)
		(mid 123.561771 122.807796)
		(end 123.522574 122.8)
		(width 0.1)
		(layer "F.Cu")
		(net 325)
	)
	(arc
		(start 123.595 123)
		(mid 123.617204 122.96677)
		(end 123.625 122.927573)
		(width 0.1)
		(layer "F.Cu")
		(net 325)
	)
	(arc
		(start 123.625 122.902426)
		(mid 123.617204 122.863229)
		(end 123.595 122.83)
		(width 0.1)
		(layer "F.Cu")
		(net 325)
	)
	(arc
		(start 123.522574 123.03)
		(mid 123.561771 123.022203)
		(end 123.595 123)
		(width 0.1)
		(layer "F.Cu")
		(net 325)
	)
	(segment
		(start 117.32 125)
		(end 117.295 125)
		(width 0.19)
		(layer "F.Cu")
		(net 326)
	)
	(segment
		(start 116.97 124.675)
		(end 116.25 124.675)
		(width 0.19)
		(layer "F.Cu")
		(net 326)
	)
	(segment
		(start 116.25 124.675)
		(end 116.1 124.825)
		(width 0.19)
		(layer "F.Cu")
		(net 326)
	)
	(segment
		(start 117.295 125)
		(end 116.97 124.675)
		(width 0.19)
		(layer "F.Cu")
		(net 326)
	)
	(via
		(at 142.78 79.75)
		(size 0.45)
		(drill 0.2)
		(layers "F.Cu" "B.Cu")
		(remove_unused_layers yes)
		(keep_end_layers yes)
		(zone_layer_connections)
		(net 326)
	)
	(via
		(at 116.1 124.825)
		(size 0.45)
		(drill 0.2)
		(layers "F.Cu" "B.Cu")
		(remove_unused_layers yes)
		(keep_end_layers yes)
		(zone_layer_connections)
		(net 326)
	)
	(segment
		(start 122.299999 103.900001)
		(end 126.6 99.6)
		(width 0.21)
		(layer "In5.Cu")
		(net 326)
	)
	(segment
		(start 126.6 99.6)
		(end 129.894974 99.6)
		(width 0.21)
		(layer "In5.Cu")
		(net 326)
	)
	(segment
		(start 121.322488 124.675)
		(end 122.425 123.572488)
		(width 0.21)
		(layer "In5.Cu")
		(net 326)
	)
	(segment
		(start 139.519974 78.975)
		(end 141.327512 78.975)
		(width 0.21)
		(layer "In5.Cu")
		(net 326)
	)
	(segment
		(start 116.25 124.675)
		(end 121.322488 124.675)
		(width 0.21)
		(layer "In5.Cu")
		(net 326)
	)
	(segment
		(start 116.1 124.825)
		(end 116.25 124.675)
		(width 0.21)
		(layer "In5.Cu")
		(net 326)
	)
	(segment
		(start 123.375 111.50368)
		(end 122.299999 110.428679)
		(width 0.21)
		(layer "In5.Cu")
		(net 326)
	)
	(segment
		(start 141.777512 79.425)
		(end 142.455 79.425)
		(width 0.21)
		(layer "In5.Cu")
		(net 326)
	)
	(segment
		(start 137.975 82.172488)
		(end 137.975 80.519974)
		(width 0.21)
		(layer "In5.Cu")
		(net 326)
	)
	(segment
		(start 122.299999 110.428679)
		(end 122.299999 103.900001)
		(width 0.21)
		(layer "In5.Cu")
		(net 326)
	)
	(segment
		(start 141.327512 78.975)
		(end 141.777512 79.425)
		(width 0.21)
		(layer "In5.Cu")
		(net 326)
	)
	(segment
		(start 137.975 80.519974)
		(end 139.519974 78.975)
		(width 0.21)
		(layer "In5.Cu")
		(net 326)
	)
	(segment
		(start 122.425 118.322488)
		(end 123.375 117.372488)
		(width 0.21)
		(layer "In5.Cu")
		(net 326)
	)
	(segment
		(start 142.455 79.425)
		(end 142.78 79.75)
		(width 0.21)
		(layer "In5.Cu")
		(net 326)
	)
	(segment
		(start 122.425 123.572488)
		(end 122.425 118.322488)
		(width 0.21)
		(layer "In5.Cu")
		(net 326)
	)
	(segment
		(start 123.375 117.372488)
		(end 123.375 111.50368)
		(width 0.21)
		(layer "In5.Cu")
		(net 326)
	)
	(segment
		(start 136.149999 83.997489)
		(end 137.975 82.172488)
		(width 0.21)
		(layer "In5.Cu")
		(net 326)
	)
	(segment
		(start 136.149999 93.344975)
		(end 136.149999 83.997489)
		(width 0.21)
		(layer "In5.Cu")
		(net 326)
	)
	(segment
		(start 129.894974 99.6)
		(end 136.149999 93.344975)
		(width 0.21)
		(layer "In5.Cu")
		(net 326)
	)
	(segment
		(start 123.175 124.64)
		(end 123.08 124.64)
		(width 0.1)
		(layer "F.Cu")
		(net 327)
	)
	(segment
		(start 120.322488 124.325)
		(end 118.63 124.325)
		(width 0.19)
		(layer "F.Cu")
		(net 327)
	)
	(segment
		(start 123.625 124.742426)
		(end 123.625 124.767573)
		(width 0.1)
		(layer "F.Cu")
		(net 327)
	)
	(segment
		(start 121.566062 124.695)
		(end 121.561062 124.7)
		(width 0.19)
		(layer "F.Cu")
		(net 327)
	)
	(segment
		(start 121.561062 124.7)
		(end 120.697488 124.7)
		(width 0.19)
		(layer "F.Cu")
		(net 327)
	)
	(segment
		(start 118.305 124)
		(end 118.28 124)
		(width 0.19)
		(layer "F.Cu")
		(net 327)
	)
	(segment
		(start 123.522574 124.87)
		(end 123.44 124.87)
		(width 0.1)
		(layer "F.Cu")
		(net 327)
	)
	(segment
		(start 123.08 124.64)
		(end 123.025 124.695)
		(width 0.1)
		(layer "F.Cu")
		(net 327)
	)
	(segment
		(start 123.025 124.695)
		(end 121.566062 124.695)
		(width 0.19)
		(layer "F.Cu")
		(net 327)
	)
	(segment
		(start 123.175 124.64)
		(end 123.522574 124.64)
		(width 0.1)
		(layer "F.Cu")
		(net 327)
	)
	(segment
		(start 120.697488 124.7)
		(end 120.322488 124.325)
		(width 0.19)
		(layer "F.Cu")
		(net 327)
	)
	(segment
		(start 118.63 124.325)
		(end 118.305 124)
		(width 0.19)
		(layer "F.Cu")
		(net 327)
	)
	(arc
		(start 123.522574 124.64)
		(mid 123.561771 124.647796)
		(end 123.595 124.67)
		(width 0.1)
		(layer "F.Cu")
		(net 327)
	)
	(arc
		(start 123.595 124.67)
		(mid 123.617204 124.703229)
		(end 123.625 124.742426)
		(width 0.1)
		(layer "F.Cu")
		(net 327)
	)
	(arc
		(start 123.595 124.84)
		(mid 123.561771 124.862203)
		(end 123.522574 124.87)
		(width 0.1)
		(layer "F.Cu")
		(net 327)
	)
	(arc
		(start 123.625 124.767573)
		(mid 123.617204 124.80677)
		(end 123.595 124.84)
		(width 0.1)
		(layer "F.Cu")
		(net 327)
	)
	(segment
		(start 117.295 128)
		(end 116.97 127.675)
		(width 0.19)
		(layer "F.Cu")
		(net 328)
	)
	(segment
		(start 117.32 128)
		(end 117.295 128)
		(width 0.19)
		(layer "F.Cu")
		(net 328)
	)
	(segment
		(start 116.97 127.675)
		(end 116.25 127.675)
		(width 0.19)
		(layer "F.Cu")
		(net 328)
	)
	(segment
		(start 116.25 127.675)
		(end 116.1 127.825)
		(width 0.19)
		(layer "F.Cu")
		(net 328)
	)
	(via
		(at 142.78 82.75)
		(size 0.45)
		(drill 0.2)
		(layers "F.Cu" "B.Cu")
		(remove_unused_layers yes)
		(keep_end_layers yes)
		(zone_layer_connections)
		(net 328)
	)
	(via
		(at 116.1 127.825)
		(size 0.45)
		(drill 0.2)
		(layers "F.Cu" "B.Cu")
		(remove_unused_layers yes)
		(keep_end_layers yes)
		(zone_layer_connections)
		(net 328)
	)
	(segment
		(start 137.638477 93.961523)
		(end 137.638477 84.009011)
		(width 0.21)
		(layer "In5.Cu")
		(net 328)
	)
	(segment
		(start 127.097057 100.799999)
		(end 130.800001 100.799999)
		(width 0.21)
		(layer "In5.Cu")
		(net 328)
	)
	(segment
		(start 142.455 82.425)
		(end 142.78 82.75)
		(width 0.21)
		(layer "In5.Cu")
		(net 328)
	)
	(segment
		(start 121.572488 127.675)
		(end 123.425 125.822488)
		(width 0.21)
		(layer "In5.Cu")
		(net 328)
	)
	(segment
		(start 116.1 127.825)
		(end 116.25 127.675)
		(width 0.21)
		(layer "In5.Cu")
		(net 328)
	)
	(segment
		(start 137.638477 84.009011)
		(end 139.672488 81.975)
		(width 0.21)
		(layer "In5.Cu")
		(net 328)
	)
	(segment
		(start 124.575 117.472488)
		(end 124.575 111.006624)
		(width 0.21)
		(layer "In5.Cu")
		(net 328)
	)
	(segment
		(start 124.575 111.006624)
		(end 123.499999 109.931623)
		(width 0.21)
		(layer "In5.Cu")
		(net 328)
	)
	(segment
		(start 141.577512 82.425)
		(end 142.455 82.425)
		(width 0.21)
		(layer "In5.Cu")
		(net 328)
	)
	(segment
		(start 141.127512 81.975)
		(end 141.577512 82.425)
		(width 0.21)
		(layer "In5.Cu")
		(net 328)
	)
	(segment
		(start 123.499999 104.397057)
		(end 127.097057 100.799999)
		(width 0.21)
		(layer "In5.Cu")
		(net 328)
	)
	(segment
		(start 116.25 127.675)
		(end 121.572488 127.675)
		(width 0.21)
		(layer "In5.Cu")
		(net 328)
	)
	(segment
		(start 123.425 125.822488)
		(end 123.425 118.622488)
		(width 0.21)
		(layer "In5.Cu")
		(net 328)
	)
	(segment
		(start 123.499999 109.931623)
		(end 123.499999 104.397057)
		(width 0.21)
		(layer "In5.Cu")
		(net 328)
	)
	(segment
		(start 130.800001 100.799999)
		(end 137.638477 93.961523)
		(width 0.21)
		(layer "In5.Cu")
		(net 328)
	)
	(segment
		(start 139.672488 81.975)
		(end 141.127512 81.975)
		(width 0.21)
		(layer "In5.Cu")
		(net 328)
	)
	(segment
		(start 123.425 118.622488)
		(end 124.575 117.472488)
		(width 0.21)
		(layer "In5.Cu")
		(net 328)
	)
	(segment
		(start 118.305 127)
		(end 118.63 127.325)
		(width 0.19)
		(layer "F.Cu")
		(net 329)
	)
	(segment
		(start 123.105 126.48)
		(end 123.522574 126.48)
		(width 0.1)
		(layer "F.Cu")
		(net 329)
	)
	(segment
		(start 122.217512 126.535)
		(end 123.05 126.535)
		(width 0.19)
		(layer "F.Cu")
		(net 329)
	)
	(segment
		(start 123.05 126.535)
		(end 123.105 126.48)
		(width 0.1)
		(layer "F.Cu")
		(net 329)
	)
	(segment
		(start 123.44 126.71)
		(end 123.522574 126.71)
		(width 0.1)
		(layer "F.Cu")
		(net 329)
	)
	(segment
		(start 123.625 126.607573)
		(end 123.625 126.582426)
		(width 0.1)
		(layer "F.Cu")
		(net 329)
	)
	(segment
		(start 118.28 127)
		(end 118.305 127)
		(width 0.19)
		(layer "F.Cu")
		(net 329)
	)
	(segment
		(start 121.427512 127.325)
		(end 122.217512 126.535)
		(width 0.19)
		(layer "F.Cu")
		(net 329)
	)
	(segment
		(start 118.63 127.325)
		(end 121.427512 127.325)
		(width 0.19)
		(layer "F.Cu")
		(net 329)
	)
	(arc
		(start 123.595 126.51)
		(mid 123.561771 126.487796)
		(end 123.522574 126.48)
		(width 0.1)
		(layer "F.Cu")
		(net 329)
	)
	(arc
		(start 123.522574 126.71)
		(mid 123.561771 126.702203)
		(end 123.595 126.68)
		(width 0.1)
		(layer "F.Cu")
		(net 329)
	)
	(arc
		(start 123.595 126.68)
		(mid 123.617204 126.64677)
		(end 123.625 126.607573)
		(width 0.1)
		(layer "F.Cu")
		(net 329)
	)
	(arc
		(start 123.625 126.582426)
		(mid 123.617204 126.543229)
		(end 123.595 126.51)
		(width 0.1)
		(layer "F.Cu")
		(net 329)
	)
	(segment
		(start 116.12 131.281)
		(end 116.301 131.1)
		(width 0.1)
		(layer "F.Cu")
		(net 330)
	)
	(segment
		(start 122.845 128.135)
		(end 122.845 129.355)
		(width 0.1)
		(layer "F.Cu")
		(net 330)
	)
	(segment
		(start 117.201 130.2)
		(end 116.301 131.1)
		(width 0.1)
		(layer "F.Cu")
		(net 330)
	)
	(segment
		(start 122.845 129.355)
		(end 122 130.2)
		(width 0.1)
		(layer "F.Cu")
		(net 330)
	)
	(segment
		(start 123.67 127.86)
		(end 123.12 127.86)
		(width 0.1)
		(layer "F.Cu")
		(net 330)
	)
	(segment
		(start 116.12 132.4)
		(end 116.12 131.281)
		(width 0.1)
		(layer "F.Cu")
		(net 330)
	)
	(segment
		(start 123.9 127.63)
		(end 123.67 127.86)
		(width 0.1)
		(layer "F.Cu")
		(net 330)
	)
	(segment
		(start 123.12 127.86)
		(end 122.845 128.135)
		(width 0.1)
		(layer "F.Cu")
		(net 330)
	)
	(segment
		(start 122 130.2)
		(end 117.201 130.2)
		(width 0.1)
		(layer "F.Cu")
		(net 330)
	)
	(segment
		(start 123.565 127.63)
		(end 123.625 127.57)
		(width 0.1)
		(layer "F.Cu")
		(net 331)
	)
	(segment
		(start 123.1 127.4)
		(end 122.645 127.855)
		(width 0.1)
		(layer "F.Cu")
		(net 331)
	)
	(segment
		(start 123.625 127.57)
		(end 123.625 127.46)
		(width 0.1)
		(layer "F.Cu")
		(net 331)
	)
	(segment
		(start 119.92 128.6)
		(end 119.302 128.6)
		(width 0.1)
		(layer "F.Cu")
		(net 331)
	)
	(segment
		(start 122.645 127.855)
		(end 122.645 128.955)
		(width 0.1)
		(layer "F.Cu")
		(net 331)
	)
	(segment
		(start 119.302 128.6)
		(end 118.601 129.301)
		(width 0.1)
		(layer "F.Cu")
		(net 331)
	)
	(segment
		(start 120.72 129.4)
		(end 119.92 128.6)
		(width 0.1)
		(layer "F.Cu")
		(net 331)
	)
	(segment
		(start 123.565 127.4)
		(end 123.1 127.4)
		(width 0.1)
		(layer "F.Cu")
		(net 331)
	)
	(segment
		(start 122.645 128.955)
		(end 122.2 129.4)
		(width 0.1)
		(layer "F.Cu")
		(net 331)
	)
	(segment
		(start 123.44 127.63)
		(end 123.565 127.63)
		(width 0.1)
		(layer "F.Cu")
		(net 331)
	)
	(segment
		(start 122.2 129.4)
		(end 120.72 129.4)
		(width 0.1)
		(layer "F.Cu")
		(net 331)
	)
	(segment
		(start 123.625 127.46)
		(end 123.565 127.4)
		(width 0.1)
		(layer "F.Cu")
		(net 331)
	)
	(segment
		(start 148.119999 109.649998)
		(end 147.674999 109.649998)
		(width 0.15)
		(layer "F.Cu")
		(net 332)
	)
	(segment
		(start 148.8 110.33)
		(end 148.119999 109.649998)
		(width 0.15)
		(layer "F.Cu")
		(net 332)
	)
	(segment
		(start 133.950001 94.349999)
		(end 134 94.3)
		(width 0.1)
		(layer "F.Cu")
		(net 333)
	)
	(segment
		(start 129.04 92.2)
		(end 129.04 94.2)
		(width 0.1)
		(layer "F.Cu")
		(net 333)
	)
	(segment
		(start 128.6 92.2)
		(end 129.04 92.2)
		(width 0.1)
		(layer "F.Cu")
		(net 333)
	)
	(segment
		(start 133.950001 94.874998)
		(end 133.950001 94.349999)
		(width 0.1)
		(layer "F.Cu")
		(net 333)
	)
	(segment
		(start 128.3 92.5)
		(end 128.6 92.2)
		(width 0.1)
		(layer "F.Cu")
		(net 333)
	)
	(via
		(at 128.3 92.5)
		(size 0.45)
		(drill 0.2)
		(layers "F.Cu" "B.Cu")
		(remove_unused_layers yes)
		(keep_end_layers yes)
		(zone_layer_connections)
		(net 333)
	)
	(via
		(at 134 94.3)
		(size 0.45)
		(drill 0.2)
		(layers "F.Cu" "B.Cu")
		(remove_unused_layers yes)
		(keep_end_layers yes)
		(zone_layer_connections)
		(net 333)
	)
	(segment
		(start 128.3 92.5)
		(end 128.4 92.6)
		(width 0.1)
		(layer "In3.Cu")
		(net 333)
	)
	(segment
		(start 132.5 93.3)
		(end 133 93.3)
		(width 0.1)
		(layer "In3.Cu")
		(net 333)
	)
	(segment
		(start 133 93.3)
		(end 134 94.3)
		(width 0.1)
		(layer "In3.Cu")
		(net 333)
	)
	(segment
		(start 128.4 92.6)
		(end 131.8 92.6)
		(width 0.1)
		(layer "In3.Cu")
		(net 333)
	)
	(segment
		(start 131.8 92.6)
		(end 132.5 93.3)
		(width 0.1)
		(layer "In3.Cu")
		(net 333)
	)
	(segment
		(start 139 97.5)
		(end 138.7 97.8)
		(width 0.1)
		(layer "F.Cu")
		(net 334)
	)
	(segment
		(start 137.5 145)
		(end 137.5 143.8)
		(width 0.25)
		(layer "F.Cu")
		(net 334)
	)
	(segment
		(start 183.9 70)
		(end 183.9 76)
		(width 0.25)
		(layer "F.Cu")
		(net 334)
	)
	(segment
		(start 130 92.2)
		(end 130 93.2)
		(width 0.1)
		(layer "F.Cu")
		(net 334)
	)
	(segment
		(start 139 96.274999)
		(end 139 97.5)
		(width 0.1)
		(layer "F.Cu")
		(net 334)
	)
	(segment
		(start 183.9 76)
		(end 183.9 69)
		(width 0.25)
		(layer "F.Cu")
		(net 334)
	)
	(segment
		(start 135.48 145.5)
		(end 137 145.5)
		(width 0.25)
		(layer "F.Cu")
		(net 334)
	)
	(segment
		(start 130.6 93.2)
		(end 131 93.6)
		(width 0.1)
		(layer "F.Cu")
		(net 334)
	)
	(segment
		(start 130 93.2)
		(end 130.6 93.2)
		(width 0.1)
		(layer "F.Cu")
		(net 334)
	)
	(segment
		(start 137 145.5)
		(end 137.5 145)
		(width 0.25)
		(layer "F.Cu")
		(net 334)
	)
	(via
		(at 131 93.6)
		(size 0.45)
		(drill 0.2)
		(layers "F.Cu" "B.Cu")
		(remove_unused_layers yes)
		(keep_end_layers yes)
		(zone_layer_connections)
		(net 334)
	)
	(via
		(at 137.5 143.8)
		(size 0.45)
		(drill 0.2)
		(layers "F.Cu" "B.Cu")
		(remove_unused_layers yes)
		(keep_end_layers yes)
		(zone_layer_connections)
		(net 334)
	)
	(via
		(at 183.9 69)
		(size 0.45)
		(drill 0.2)
		(layers "F.Cu" "B.Cu")
		(remove_unused_layers yes)
		(keep_end_layers yes)
		(zone_layer_connections)
		(net 334)
	)
	(via
		(at 138 97.2)
		(size 0.45)
		(drill 0.2)
		(layers "F.Cu" "B.Cu")
		(remove_unused_layers yes)
		(keep_end_layers yes)
		(zone_layer_connections)
		(net 334)
	)
	(via
		(at 138.7 97.8)
		(size 0.45)
		(drill 0.2)
		(layers "F.Cu" "B.Cu")
		(remove_unused_layers yes)
		(keep_end_layers yes)
		(zone_layer_connections)
		(net 334)
	)
	(segment
		(start 131 93.6)
		(end 131.1 93.6)
		(width 0.1)
		(layer "In3.Cu")
		(net 334)
	)
	(segment
		(start 135.6 94.8)
		(end 138 97.2)
		(width 0.1)
		(layer "In3.Cu")
		(net 334)
	)
	(segment
		(start 132.3 94.8)
		(end 135.6 94.8)
		(width 0.1)
		(layer "In3.Cu")
		(net 334)
	)
	(segment
		(start 131.1 93.6)
		(end 132.3 94.8)
		(width 0.1)
		(layer "In3.Cu")
		(net 334)
	)
	(segment
		(start 147.25 90.68)
		(end 147.55 90.98)
		(width 0.25)
		(layer "In5.Cu")
		(net 334)
	)
	(segment
		(start 166.45 92.3)
		(end 173.75 85)
		(width 0.25)
		(layer "In5.Cu")
		(net 334)
	)
	(segment
		(start 142.4 124.3)
		(end 146.25 120.45)
		(width 0.25)
		(layer "In5.Cu")
		(net 334)
	)
	(segment
		(start 142.4 126.65)
		(end 142.4 124.3)
		(width 0.25)
		(layer "In5.Cu")
		(net 334)
	)
	(segment
		(start 139.2 103)
		(end 139.8 103)
		(width 0.25)
		(layer "In5.Cu")
		(net 334)
	)
	(segment
		(start 155.45 95.01)
		(end 158.16 92.3)
		(width 0.25)
		(layer "In5.Cu")
		(net 334)
	)
	(segment
		(start 140.8 98.5)
		(end 139.4 98.5)
		(width 0.25)
		(layer "In5.Cu")
		(net 334)
	)
	(segment
		(start 145.05 109.2)
		(end 143.85 108)
		(width 0.25)
		(layer "In5.Cu")
		(net 334)
	)
	(segment
		(start 145.574124 89.715876)
		(end 146.128248 90.27)
		(width 0.25)
		(layer "In5.Cu")
		(net 334)
	)
	(segment
		(start 146.128248 90.27)
		(end 146.47 90.27)
		(width 0.25)
		(layer "In5.Cu")
		(net 334)
	)
	(segment
		(start 174.7 67.3)
		(end 176.2 65.8)
		(width 0.25)
		(layer "In5.Cu")
		(net 334)
	)
	(segment
		(start 143.85 108)
		(end 140.4 108)
		(width 0.25)
		(layer "In5.Cu")
		(net 334)
	)
	(segment
		(start 143 91.201752)
		(end 144.485876 89.715876)
		(width 0.25)
		(layer "In5.Cu")
		(net 334)
	)
	(segment
		(start 144.485876 89.715876)
		(end 145.574124 89.715876)
		(width 0.25)
		(layer "In5.Cu")
		(net 334)
	)
	(segment
		(start 158.16 92.3)
		(end 166.45 92.3)
		(width 0.25)
		(layer "In5.Cu")
		(net 334)
	)
	(segment
		(start 174.7 78.05)
		(end 174.7 67.3)
		(width 0.25)
		(layer "In5.Cu")
		(net 334)
	)
	(segment
		(start 173.75 79)
		(end 174.7 78.05)
		(width 0.25)
		(layer "In5.Cu")
		(net 334)
	)
	(segment
		(start 147.55 91.87)
		(end 147.98 92.3)
		(width 0.25)
		(layer "In5.Cu")
		(net 334)
	)
	(segment
		(start 142.8 127.05)
		(end 142.4 126.65)
		(width 0.25)
		(layer "In5.Cu")
		(net 334)
	)
	(segment
		(start 140.8 97.6)
		(end 143 95.4)
		(width 0.25)
		(layer "In5.Cu")
		(net 334)
	)
	(segment
		(start 147.55 90.98)
		(end 147.55 91.87)
		(width 0.25)
		(layer "In5.Cu")
		(net 334)
	)
	(segment
		(start 150.62 94.76)
		(end 150.87 95.01)
		(width 0.25)
		(layer "In5.Cu")
		(net 334)
	)
	(segment
		(start 143 95.4)
		(end 143 91.201752)
		(width 0.25)
		(layer "In5.Cu")
		(net 334)
	)
	(segment
		(start 137.5 143.8)
		(end 138.95 143.8)
		(width 0.25)
		(layer "In5.Cu")
		(net 334)
	)
	(segment
		(start 140.8 102)
		(end 140.8 98.5)
		(width 0.25)
		(layer "In5.Cu")
		(net 334)
	)
	(segment
		(start 147.98 92.3)
		(end 149.54 92.3)
		(width 0.25)
		(layer "In5.Cu")
		(net 334)
	)
	(segment
		(start 149.54 92.3)
		(end 150.62 93.38)
		(width 0.25)
		(layer "In5.Cu")
		(net 334)
	)
	(segment
		(start 142.8 139.95)
		(end 142.8 127.05)
		(width 0.25)
		(layer "In5.Cu")
		(net 334)
	)
	(segment
		(start 145.05 114.9)
		(end 145.05 109.2)
		(width 0.25)
		(layer "In5.Cu")
		(net 334)
	)
	(segment
		(start 146.25 116.1)
		(end 145.05 114.9)
		(width 0.25)
		(layer "In5.Cu")
		(net 334)
	)
	(segment
		(start 176.2 65.8)
		(end 181.9 65.8)
		(width 0.25)
		(layer "In5.Cu")
		(net 334)
	)
	(segment
		(start 183.9 67.8)
		(end 183.9 69)
		(width 0.25)
		(layer "In5.Cu")
		(net 334)
	)
	(segment
		(start 138.95 143.8)
		(end 142.8 139.95)
		(width 0.25)
		(layer "In5.Cu")
		(net 334)
	)
	(segment
		(start 150.87 95.01)
		(end 155.45 95.01)
		(width 0.25)
		(layer "In5.Cu")
		(net 334)
	)
	(segment
		(start 146.25 120.45)
		(end 146.25 116.1)
		(width 0.25)
		(layer "In5.Cu")
		(net 334)
	)
	(segment
		(start 140.8 98.5)
		(end 140.8 97.6)
		(width 0.25)
		(layer "In5.Cu")
		(net 334)
	)
	(segment
		(start 173.75 85)
		(end 173.75 79)
		(width 0.25)
		(layer "In5.Cu")
		(net 334)
	)
	(segment
		(start 146.47 90.27)
		(end 146.88 90.68)
		(width 0.25)
		(layer "In5.Cu")
		(net 334)
	)
	(segment
		(start 150.62 93.38)
		(end 150.62 94.76)
		(width 0.25)
		(layer "In5.Cu")
		(net 334)
	)
	(segment
		(start 137.8 104.4)
		(end 139.2 103)
		(width 0.25)
		(layer "In5.Cu")
		(net 334)
	)
	(segment
		(start 139.4 98.5)
		(end 138.7 97.8)
		(width 0.25)
		(layer "In5.Cu")
		(net 334)
	)
	(segment
		(start 181.9 65.8)
		(end 183.9 67.8)
		(width 0.25)
		(layer "In5.Cu")
		(net 334)
	)
	(segment
		(start 146.88 90.68)
		(end 147.25 90.68)
		(width 0.25)
		(layer "In5.Cu")
		(net 334)
	)
	(segment
		(start 139.8 103)
		(end 140.8 102)
		(width 0.25)
		(layer "In5.Cu")
		(net 334)
	)
	(segment
		(start 140.4 108)
		(end 137.8 105.4)
		(width 0.25)
		(layer "In5.Cu")
		(net 334)
	)
	(segment
		(start 137.8 105.4)
		(end 137.8 104.4)
		(width 0.25)
		(layer "In5.Cu")
		(net 334)
	)
	(segment
		(start 135.669999 110.149999)
		(end 134.449999 110.149999)
		(width 0.1)
		(layer "F.Cu")
		(net 335)
	)
	(segment
		(start 134.449999 110.149999)
		(end 133.6 109.3)
		(width 0.1)
		(layer "F.Cu")
		(net 335)
	)
	(segment
		(start 133.6 105.3)
		(end 133.999999 104.900001)
		(width 0.1)
		(layer "F.Cu")
		(net 335)
	)
	(segment
		(start 133.999999 104.900001)
		(end 135.1 104.900001)
		(width 0.1)
		(layer "F.Cu")
		(net 335)
	)
	(segment
		(start 135.669999 111.149997)
		(end 135.669999 110.149997)
		(width 0.15)
		(layer "F.Cu")
		(net 335)
	)
	(segment
		(start 133.6 109.3)
		(end 133.6 105.3)
		(width 0.1)
		(layer "F.Cu")
		(net 335)
	)
	(via
		(at 177.3 67.402)
		(size 0.45)
		(drill 0.2)
		(layers "F.Cu" "B.Cu")
		(remove_unused_layers yes)
		(keep_end_layers yes)
		(zone_layer_connections)
		(net 335)
	)
	(via
		(at 139.4 104.5)
		(size 0.45)
		(drill 0.2)
		(layers "F.Cu" "B.Cu")
		(remove_unused_layers yes)
		(keep_end_layers yes)
		(zone_layer_connections)
		(net 335)
	)
	(segment
		(start 139.4 104.52)
		(end 139.4 104.5)
		(width 0.1)
		(layer "B.Cu")
		(net 335)
	)
	(segment
		(start 177.302 67.4)
		(end 177.3 67.402)
		(width 0.1)
		(layer "B.Cu")
		(net 335)
	)
	(segment
		(start 178 67.4)
		(end 177.302 67.4)
		(width 0.1)
		(layer "B.Cu")
		(net 335)
	)
	(segment
		(start 145.4 96.8)
		(end 145.4 102.4)
		(width 0.1)
		(layer "In5.Cu")
		(net 335)
	)
	(segment
		(start 143.3 104.5)
		(end 139.4 104.5)
		(width 0.1)
		(layer "In5.Cu")
		(net 335)
	)
	(segment
		(start 148.45 97.15)
		(end 147.5 96.2)
		(width 0.1)
		(layer "In5.Cu")
		(net 335)
	)
	(segment
		(start 160.3 100)
		(end 157.05 103.25)
		(width 0.1)
		(layer "In5.Cu")
		(net 335)
	)
	(segment
		(start 151.55 103.25)
		(end 148.45 100.15)
		(width 0.1)
		(layer "In5.Cu")
		(net 335)
	)
	(segment
		(start 147.5 96.2)
		(end 146 96.2)
		(width 0.1)
		(layer "In5.Cu")
		(net 335)
	)
	(segment
		(start 157.05 103.25)
		(end 151.55 103.25)
		(width 0.1)
		(layer "In5.Cu")
		(net 335)
	)
	(segment
		(start 146 96.2)
		(end 145.4 96.8)
		(width 0.1)
		(layer "In5.Cu")
		(net 335)
	)
	(segment
		(start 145.4 102.4)
		(end 143.3 104.5)
		(width 0.1)
		(layer "In5.Cu")
		(net 335)
	)
	(segment
		(start 175.601 69.101)
		(end 175.601 93.233314)
		(width 0.1)
		(layer "In5.Cu")
		(net 335)
	)
	(segment
		(start 168.834314 100)
		(end 160.3 100)
		(width 0.1)
		(layer "In5.Cu")
		(net 335)
	)
	(segment
		(start 177.3 67.402)
		(end 175.601 69.101)
		(width 0.1)
		(layer "In5.Cu")
		(net 335)
	)
	(segment
		(start 175.601 93.233314)
		(end 168.834314 100)
		(width 0.1)
		(layer "In5.Cu")
		(net 335)
	)
	(segment
		(start 148.45 100.15)
		(end 148.45 97.15)
		(width 0.1)
		(layer "In5.Cu")
		(net 335)
	)
	(segment
		(start 136.629999 110.149997)
		(end 138.124999 110.149998)
		(width 0.15)
		(layer "F.Cu")
		(net 336)
	)
	(segment
		(start 136.629999 110.149997)
		(end 136.63 111.15)
		(width 0.15)
		(layer "F.Cu")
		(net 336)
	)
	(segment
		(start 136.629999 112.149999)
		(end 136.63 111.15)
		(width 0.15)
		(layer "F.Cu")
		(net 336)
	)
	(segment
		(start 152.03 112.15)
		(end 152.030002 111.15)
		(width 0.15)
		(layer "F.Cu")
		(net 337)
	)
	(segment
		(start 152.03 110.149998)
		(end 153.525001 110.15)
		(width 0.15)
		(layer "F.Cu")
		(net 337)
	)
	(segment
		(start 152.03 110.149998)
		(end 152.030002 111.15)
		(width 0.15)
		(layer "F.Cu")
		(net 337)
	)
	(segment
		(start 149.4 109.3)
		(end 149.4 105.1)
		(width 0.1)
		(layer "F.Cu")
		(net 338)
	)
	(segment
		(start 149.6 104.9)
		(end 150.500001 104.900001)
		(width 0.1)
		(layer "F.Cu")
		(net 338)
	)
	(segment
		(start 150.25 110.15)
		(end 149.4 109.3)
		(width 0.1)
		(layer "F.Cu")
		(net 338)
	)
	(segment
		(start 149.4 105.1)
		(end 149.6 104.9)
		(width 0.1)
		(layer "F.Cu")
		(net 338)
	)
	(segment
		(start 151.07 110.15)
		(end 150.25 110.15)
		(width 0.1)
		(layer "F.Cu")
		(net 338)
	)
	(segment
		(start 151.069999 111.149998)
		(end 151.07 110.149998)
		(width 0.15)
		(layer "F.Cu")
		(net 338)
	)
	(via
		(at 154.9 104.5)
		(size 0.45)
		(drill 0.2)
		(layers "F.Cu" "B.Cu")
		(remove_unused_layers yes)
		(keep_end_layers yes)
		(zone_layer_connections)
		(net 338)
	)
	(via
		(at 177.3 69.802)
		(size 0.45)
		(drill 0.2)
		(layers "F.Cu" "B.Cu")
		(remove_unused_layers yes)
		(keep_end_layers yes)
		(zone_layer_connections)
		(net 338)
	)
	(segment
		(start 178 69.8)
		(end 177.302 69.8)
		(width 0.1)
		(layer "B.Cu")
		(net 338)
	)
	(segment
		(start 154.9 104.52)
		(end 154.9 104.5)
		(width 0.1)
		(layer "B.Cu")
		(net 338)
	)
	(segment
		(start 177.302 69.8)
		(end 177.3 69.802)
		(width 0.1)
		(layer "B.Cu")
		(net 338)
	)
	(segment
		(start 169 100.4)
		(end 163.2 100.4)
		(width 0.1)
		(layer "In5.Cu")
		(net 338)
	)
	(segment
		(start 177.3 69.802)
		(end 176.051 71.051)
		(width 0.1)
		(layer "In5.Cu")
		(net 338)
	)
	(segment
		(start 159.1 104.5)
		(end 154.9 104.5)
		(width 0.1)
		(layer "In5.Cu")
		(net 338)
	)
	(segment
		(start 176.051 93.349)
		(end 169 100.4)
		(width 0.1)
		(layer "In5.Cu")
		(net 338)
	)
	(segment
		(start 163.2 100.4)
		(end 159.1 104.5)
		(width 0.1)
		(layer "In5.Cu")
		(net 338)
	)
	(segment
		(start 176.051 71.051)
		(end 176.051 93.349)
		(width 0.1)
		(layer "In5.Cu")
		(net 338)
	)
	(segment
		(start 157.1 105.1)
		(end 157.3 104.9)
		(width 0.1)
		(layer "F.Cu")
		(net 339)
	)
	(segment
		(start 157.3 104.9)
		(end 158.2 104.900001)
		(width 0.1)
		(layer "F.Cu")
		(net 339)
	)
	(segment
		(start 158.769996 111.149998)
		(end 158.769996 110.150001)
		(width 0.15)
		(layer "F.Cu")
		(net 339)
	)
	(segment
		(start 157.949999 110.149999)
		(end 157.1 109.3)
		(width 0.1)
		(layer "F.Cu")
		(net 339)
	)
	(segment
		(start 158.769997 110.149999)
		(end 157.949999 110.149999)
		(width 0.1)
		(layer "F.Cu")
		(net 339)
	)
	(segment
		(start 158.769996 110.150001)
		(end 158.769999 110.149998)
		(width 0.15)
		(layer "F.Cu")
		(net 339)
	)
	(segment
		(start 157.1 109.3)
		(end 157.1 105.1)
		(width 0.1)
		(layer "F.Cu")
		(net 339)
	)
	(via
		(at 162.5 104.5)
		(size 0.45)
		(drill 0.2)
		(layers "F.Cu" "B.Cu")
		(remove_unused_layers yes)
		(keep_end_layers yes)
		(zone_layer_connections)
		(net 339)
	)
	(via
		(at 177.3 72.302)
		(size 0.45)
		(drill 0.2)
		(layers "F.Cu" "B.Cu")
		(remove_unused_layers yes)
		(keep_end_layers yes)
		(zone_layer_connections)
		(net 339)
	)
	(segment
		(start 177.302 72.3)
		(end 177.3 72.302)
		(width 0.1)
		(layer "B.Cu")
		(net 339)
	)
	(segment
		(start 162.6 104.52)
		(end 162.58 104.5)
		(width 0.1)
		(layer "B.Cu")
		(net 339)
	)
	(segment
		(start 162.58 104.5)
		(end 162.5 104.5)
		(width 0.1)
		(layer "B.Cu")
		(net 339)
	)
	(segment
		(start 178 72.3)
		(end 177.302 72.3)
		(width 0.1)
		(layer "B.Cu")
		(net 339)
	)
	(segment
		(start 176.551 93.414686)
		(end 169.282843 100.682843)
		(width 0.1)
		(layer "In5.Cu")
		(net 339)
	)
	(segment
		(start 162.5 103.7)
		(end 162.5 104.5)
		(width 0.1)
		(layer "In5.Cu")
		(net 339)
	)
	(segment
		(start 177.3 72.302)
		(end 176.551 73.051)
		(width 0.1)
		(layer "In5.Cu")
		(net 339)
	)
	(segment
		(start 169.282843 100.682843)
		(end 165.517157 100.682843)
		(width 0.1)
		(layer "In5.Cu")
		(net 339)
	)
	(segment
		(start 176.551 73.051)
		(end 176.551 93.414686)
		(width 0.1)
		(layer "In5.Cu")
		(net 339)
	)
	(segment
		(start 165.517157 100.682843)
		(end 162.5 103.7)
		(width 0.1)
		(layer "In5.Cu")
		(net 339)
	)
	(segment
		(start 159.729997 110.149997)
		(end 159.729999 111.149999)
		(width 0.15)
		(layer "F.Cu")
		(net 340)
	)
	(segment
		(start 159.729997 110.149997)
		(end 161.224998 110.149998)
		(width 0.15)
		(layer "F.Cu")
		(net 340)
	)
	(segment
		(start 159.729997 112.149999)
		(end 159.729999 111.149999)
		(width 0.15)
		(layer "F.Cu")
		(net 340)
	)
	(segment
		(start 142 104.9)
		(end 142.000003 104.900003)
		(width 0.1)
		(layer "F.Cu")
		(net 341)
	)
	(segment
		(start 141.8 105.1)
		(end 142 104.9)
		(width 0.1)
		(layer "F.Cu")
		(net 341)
	)
	(segment
		(start 143.369998 110.15)
		(end 142.75 110.15)
		(width 0.1)
		(layer "F.Cu")
		(net 341)
	)
	(segment
		(start 142.000003 104.900003)
		(end 142.799999 104.900003)
		(width 0.1)
		(layer "F.Cu")
		(net 341)
	)
	(segment
		(start 141.8 109.2)
		(end 141.8 105.1)
		(width 0.1)
		(layer "F.Cu")
		(net 341)
	)
	(segment
		(start 142.75 110.15)
		(end 141.8 109.2)
		(width 0.1)
		(layer "F.Cu")
		(net 341)
	)
	(segment
		(start 143.369999 111.149999)
		(end 143.369999 110.15)
		(width 0.15)
		(layer "F.Cu")
		(net 341)
	)
	(via
		(at 146 104.5)
		(size 0.45)
		(drill 0.2)
		(layers "F.Cu" "B.Cu")
		(remove_unused_layers yes)
		(keep_end_layers yes)
		(zone_layer_connections)
		(net 341)
	)
	(via
		(at 148.4 105.2)
		(size 0.45)
		(drill 0.2)
		(layers "F.Cu" "B.Cu")
		(remove_unused_layers yes)
		(keep_end_layers yes)
		(zone_layer_connections)
		(net 341)
	)
	(via
		(at 177.3 74.9)
		(size 0.45)
		(drill 0.2)
		(layers "F.Cu" "B.Cu")
		(remove_unused_layers yes)
		(keep_end_layers yes)
		(zone_layer_connections)
		(net 341)
	)
	(segment
		(start 146 104.52)
		(end 146 104.5)
		(width 0.1)
		(layer "B.Cu")
		(net 341)
	)
	(segment
		(start 178 74.898)
		(end 177.302 74.898)
		(width 0.1)
		(layer "B.Cu")
		(net 341)
	)
	(segment
		(start 177.302 74.898)
		(end 177.3 74.9)
		(width 0.1)
		(layer "B.Cu")
		(net 341)
	)
	(segment
		(start 177.4 93.13137)
		(end 169.565685 100.965685)
		(width 0.1)
		(layer "In5.Cu")
		(net 341)
	)
	(segment
		(start 169.565685 100.965685)
		(end 166.684315 100.965685)
		(width 0.1)
		(layer "In5.Cu")
		(net 341)
	)
	(segment
		(start 150.35 105.2)
		(end 148.4 105.2)
		(width 0.1)
		(layer "In5.Cu")
		(net 341)
	)
	(segment
		(start 177.4 75.3)
		(end 177.4 93.13137)
		(width 0.1)
		(layer "In5.Cu")
		(net 341)
	)
	(segment
		(start 177.3 75.2)
		(end 177.4 75.3)
		(width 0.1)
		(layer "In5.Cu")
		(net 341)
	)
	(segment
		(start 150.5 105.05)
		(end 150.35 105.2)
		(width 0.1)
		(layer "In5.Cu")
		(net 341)
	)
	(segment
		(start 177.3 74.9)
		(end 177.3 75.2)
		(width 0.1)
		(layer "In5.Cu")
		(net 341)
	)
	(segment
		(start 166.684315 100.965685)
		(end 162.6 105.05)
		(width 0.1)
		(layer "In5.Cu")
		(net 341)
	)
	(segment
		(start 162.6 105.05)
		(end 150.5 105.05)
		(width 0.1)
		(layer "In5.Cu")
		(net 341)
	)
	(segment
		(start 144.329999 110.149998)
		(end 145.824999 110.149998)
		(width 0.15)
		(layer "F.Cu")
		(net 342)
	)
	(segment
		(start 144.329999 110.149998)
		(end 144.33 111.15)
		(width 0.15)
		(layer "F.Cu")
		(net 342)
	)
	(segment
		(start 144.329999 112.15)
		(end 144.33 111.15)
		(width 0.15)
		(layer "F.Cu")
		(net 342)
	)
	(segment
		(start 129.72 73.275)
		(end 129.845 73.4)
		(width 0.25)
		(layer "F.Cu")
		(net 343)
	)
	(segment
		(start 125.28 83.28)
		(end 132.4 83.28)
		(width 0.1)
		(layer "F.Cu")
		(net 343)
	)
	(segment
		(start 128.8 71.4)
		(end 129.72 71.4)
		(width 0.25)
		(layer "F.Cu")
		(net 343)
	)
	(segment
		(start 126.65 74.45)
		(end 127.95 74.45)
		(width 0.25)
		(layer "F.Cu")
		(net 343)
	)
	(segment
		(start 127.95 74.45)
		(end 128.4 74)
		(width 0.25)
		(layer "F.Cu")
		(net 343)
	)
	(segment
		(start 132.32 71.4)
		(end 132.32 70.92)
		(width 0.1)
		(layer "F.Cu")
		(net 343)
	)
	(segment
		(start 128.4 71.8)
		(end 128.8 71.4)
		(width 0.25)
		(layer "F.Cu")
		(net 343)
	)
	(segment
		(start 128.4 74)
		(end 128.4 71.8)
		(width 0.25)
		(layer "F.Cu")
		(net 343)
	)
	(segment
		(start 129.499 70.2)
		(end 129.499 70.8)
		(width 0.25)
		(layer "F.Cu")
		(net 343)
	)
	(segment
		(start 126.65 74.45)
		(end 124.55 74.45)
		(width 0.1)
		(layer "F.Cu")
		(net 343)
	)
	(segment
		(start 132.2 70.8)
		(end 129.499 70.8)
		(width 0.1)
		(layer "F.Cu")
		(net 343)
	)
	(segment
		(start 132.32 70.92)
		(end 132.2 70.8)
		(width 0.1)
		(layer "F.Cu")
		(net 343)
	)
	(segment
		(start 129.499 71.179)
		(end 129.72 71.4)
		(width 0.25)
		(layer "F.Cu")
		(net 343)
	)
	(segment
		(start 129.72 71.4)
		(end 129.72 73.275)
		(width 0.25)
		(layer "F.Cu")
		(net 343)
	)
	(segment
		(start 129.499 70.8)
		(end 129.499 71.179)
		(width 0.25)
		(layer "F.Cu")
		(net 343)
	)
	(segment
		(start 123.6 81.6)
		(end 125.28 83.28)
		(width 0.1)
		(layer "F.Cu")
		(net 343)
	)
	(segment
		(start 123.6 75.4)
		(end 123.6 81.6)
		(width 0.1)
		(layer "F.Cu")
		(net 343)
	)
	(segment
		(start 124.55 74.45)
		(end 123.6 75.4)
		(width 0.1)
		(layer "F.Cu")
		(net 343)
	)
	(via
		(at 126.65 74.45)
		(size 0.45)
		(drill 0.2)
		(layers "F.Cu" "B.Cu")
		(remove_unused_layers yes)
		(keep_end_layers yes)
		(zone_layer_connections)
		(net 343)
	)
	(segment
		(start 126.654 74.46)
		(end 126.654 74.454)
		(width 0.25)
		(layer "B.Cu")
		(net 343)
	)
	(segment
		(start 126.654 74.454)
		(end 126.65 74.45)
		(width 0.25)
		(layer "B.Cu")
		(net 343)
	)
	(segment
		(start 154.3 48.7)
		(end 154.3 45.92)
		(width 0.1)
		(layer "F.Cu")
		(net 344)
	)
	(segment
		(start 159.025 47.725)
		(end 159.05 47.7)
		(width 0.1)
		(layer "F.Cu")
		(net 344)
	)
	(segment
		(start 159.025 48.26)
		(end 159.025 47.725)
		(width 0.1)
		(layer "F.Cu")
		(net 344)
	)
	(segment
		(start 154.3 45.92)
		(end 154.28 45.9)
		(width 0.1)
		(layer "F.Cu")
		(net 344)
	)
	(via
		(at 154.3 48.7)
		(size 0.45)
		(drill 0.2)
		(layers "F.Cu" "B.Cu")
		(remove_unused_layers yes)
		(keep_end_layers yes)
		(zone_layer_connections)
		(net 344)
	)
	(via
		(at 159.05 47.7)
		(size 0.45)
		(drill 0.2)
		(layers "F.Cu" "B.Cu")
		(remove_unused_layers yes)
		(keep_end_layers yes)
		(zone_layer_connections)
		(net 344)
	)
	(segment
		(start 159.05 47.7)
		(end 155.4 47.7)
		(width 0.1)
		(layer "B.Cu")
		(net 344)
	)
	(segment
		(start 155.4 47.7)
		(end 154.3 48.8)
		(width 0.1)
		(layer "B.Cu")
		(net 344)
	)
	(segment
		(start 162.28 49.98)
		(end 162.3 50)
		(width 0.25)
		(layer "F.Cu")
		(net 345)
	)
	(segment
		(start 161.4 49.98)
		(end 162.28 49.98)
		(width 0.25)
		(layer "F.Cu")
		(net 345)
	)
	(segment
		(start 161.355 50.025)
		(end 161.4 49.98)
		(width 0.25)
		(layer "F.Cu")
		(net 345)
	)
	(segment
		(start 160.68 49.98)
		(end 161.4 49.98)
		(width 0.25)
		(layer "F.Cu")
		(net 345)
	)
	(segment
		(start 158 45.82)
		(end 157.22 45.82)
		(width 0.1)
		(layer "F.Cu")
		(net 345)
	)
	(segment
		(start 159.94 49.825)
		(end 160.525 49.825)
		(width 0.25)
		(layer "F.Cu")
		(net 345)
	)
	(segment
		(start 160.525 49.825)
		(end 160.68 49.98)
		(width 0.25)
		(layer "F.Cu")
		(net 345)
	)
	(segment
		(start 157.22 45.82)
		(end 157.2 45.8)
		(width 0.1)
		(layer "F.Cu")
		(net 345)
	)
	(via
		(at 157.2 45.8)
		(size 0.45)
		(drill 0.2)
		(layers "F.Cu" "B.Cu")
		(remove_unused_layers yes)
		(keep_end_layers yes)
		(zone_layer_connections)
		(net 345)
	)
	(via
		(at 162.3 50)
		(size 0.45)
		(drill 0.2)
		(layers "F.Cu" "B.Cu")
		(remove_unused_layers yes)
		(keep_end_layers yes)
		(zone_layer_connections)
		(net 345)
	)
	(segment
		(start 161.2 46.8)
		(end 158.1 46.8)
		(width 0.25)
		(layer "B.Cu")
		(net 345)
	)
	(segment
		(start 158.1 46.8)
		(end 157.2 45.9)
		(width 0.25)
		(layer "B.Cu")
		(net 345)
	)
	(segment
		(start 162.3 50.1)
		(end 162.3 47.9)
		(width 0.25)
		(layer "B.Cu")
		(net 345)
	)
	(segment
		(start 162.3 47.9)
		(end 161.2 46.8)
		(width 0.25)
		(layer "B.Cu")
		(net 345)
	)
	(segment
		(start 160.795 51.375)
		(end 160.575 51.375)
		(width 0.25)
		(layer "F.Cu")
		(net 346)
	)
	(segment
		(start 160.575 51.375)
		(end 160.375 51.175)
		(width 0.25)
		(layer "F.Cu")
		(net 346)
	)
	(segment
		(start 160.375 51.175)
		(end 159.94 51.175)
		(width 0.25)
		(layer "F.Cu")
		(net 346)
	)
	(segment
		(start 161.4 51.98)
		(end 160.795 51.375)
		(width 0.25)
		(layer "F.Cu")
		(net 346)
	)
	(segment
		(start 156.975 46.905)
		(end 156.98 46.9)
		(width 0.25)
		(layer "F.Cu")
		(net 347)
	)
	(segment
		(start 156.975 48.26)
		(end 156.975 46.905)
		(width 0.25)
		(layer "F.Cu")
		(net 347)
	)
	(segment
		(start 156.02 47.52)
		(end 156.02 46.9)
		(width 0.25)
		(layer "F.Cu")
		(net 348)
	)
	(segment
		(start 156.15 47.65)
		(end 156.02 47.52)
		(width 0.25)
		(layer "F.Cu")
		(net 348)
	)
	(segment
		(start 156.525 48.26)
		(end 156.525 47.775)
		(width 0.25)
		(layer "F.Cu")
		(net 348)
	)
	(segment
		(start 156.525 47.775)
		(end 156.4 47.65)
		(width 0.25)
		(layer "F.Cu")
		(net 348)
	)
	(segment
		(start 156.4 47.65)
		(end 156.15 47.65)
		(width 0.25)
		(layer "F.Cu")
		(net 348)
	)
	(segment
		(start 159.475 48.26)
		(end 159.475 48.025)
		(width 0.25)
		(layer "F.Cu")
		(net 349)
	)
	(segment
		(start 160.18 47.6)
		(end 161 46.78)
		(width 0.25)
		(layer "F.Cu")
		(net 349)
	)
	(segment
		(start 159.475 48.025)
		(end 159.9 47.6)
		(width 0.25)
		(layer "F.Cu")
		(net 349)
	)
	(segment
		(start 125.48 54.5)
		(end 126.5 54.5)
		(width 0.1)
		(layer "F.Cu")
		(net 349)
	)
	(segment
		(start 159.9 47.6)
		(end 160.18 47.6)
		(width 0.25)
		(layer "F.Cu")
		(net 349)
	)
	(via
		(at 126.5 54.5)
		(size 0.45)
		(drill 0.2)
		(layers "F.Cu" "B.Cu")
		(remove_unused_layers yes)
		(keep_end_layers yes)
		(zone_layer_connections)
		(net 349)
	)
	(via
		(at 146.2 58.5)
		(size 0.45)
		(drill 0.2)
		(layers "F.Cu" "B.Cu")
		(remove_unused_layers yes)
		(keep_end_layers yes)
		(zone_layer_connections)
		(net 349)
	)
	(via
		(at 159.9 47.6)
		(size 0.45)
		(drill 0.2)
		(layers "F.Cu" "B.Cu")
		(remove_unused_layers yes)
		(keep_end_layers yes)
		(zone_layer_connections)
		(net 349)
	)
	(via
		(at 146.2 57.6)
		(size 0.45)
		(drill 0.2)
		(layers "F.Cu" "B.Cu")
		(remove_unused_layers yes)
		(keep_end_layers yes)
		(zone_layer_connections)
		(net 349)
	)
	(segment
		(start 139.3 54.5)
		(end 142.4 57.6)
		(width 0.1)
		(layer "B.Cu")
		(net 349)
	)
	(segment
		(start 133.6 58.8)
		(end 136 56.4)
		(width 0.1)
		(layer "B.Cu")
		(net 349)
	)
	(segment
		(start 136 56.4)
		(end 136 55.7)
		(width 0.1)
		(layer "B.Cu")
		(net 349)
	)
	(segment
		(start 126.5 54.5)
		(end 126.5 55.9)
		(width 0.1)
		(layer "B.Cu")
		(net 349)
	)
	(segment
		(start 159.9 54.8)
		(end 156.2 58.5)
		(width 0.25)
		(layer "B.Cu")
		(net 349)
	)
	(segment
		(start 142.4 57.6)
		(end 146.2 57.6)
		(width 0.1)
		(layer "B.Cu")
		(net 349)
	)
	(segment
		(start 137.2 54.5)
		(end 139.3 54.5)
		(width 0.1)
		(layer "B.Cu")
		(net 349)
	)
	(segment
		(start 129.4 58.8)
		(end 133.6 58.8)
		(width 0.1)
		(layer "B.Cu")
		(net 349)
	)
	(segment
		(start 126.5 55.9)
		(end 129.4 58.8)
		(width 0.1)
		(layer "B.Cu")
		(net 349)
	)
	(segment
		(start 136 55.7)
		(end 137.2 54.5)
		(width 0.1)
		(layer "B.Cu")
		(net 349)
	)
	(segment
		(start 156.2 58.5)
		(end 146.2 58.5)
		(width 0.25)
		(layer "B.Cu")
		(net 349)
	)
	(segment
		(start 159.9 47.7)
		(end 159.9 54.8)
		(width 0.25)
		(layer "B.Cu")
		(net 349)
	)
	(segment
		(start 125.2 76.4)
		(end 124.7 76.9)
		(width 0.1)
		(layer "F.Cu")
		(net 350)
	)
	(segment
		(start 147.4 91.6)
		(end 147.4 92.8)
		(width 0.1)
		(layer "F.Cu")
		(net 350)
	)
	(segment
		(start 128.3 80)
		(end 128.8 79.5)
		(width 0.1)
		(layer "F.Cu")
		(net 350)
	)
	(segment
		(start 125.1 80)
		(end 128.3 80)
		(width 0.1)
		(layer "F.Cu")
		(net 350)
	)
	(segment
		(start 147.4 92.8)
		(end 145.525001 94.674999)
		(width 0.1)
		(layer "F.Cu")
		(net 350)
	)
	(segment
		(start 147.750001 91.249999)
		(end 147.4 91.6)
		(width 0.1)
		(layer "F.Cu")
		(net 350)
	)
	(segment
		(start 126.65 75.75)
		(end 126 76.4)
		(width 0.1)
		(layer "F.Cu")
		(net 350)
	)
	(segment
		(start 148.845 91.249999)
		(end 147.750001 91.249999)
		(width 0.1)
		(layer "F.Cu")
		(net 350)
	)
	(segment
		(start 128.8 79.5)
		(end 129.7 79.5)
		(width 0.1)
		(layer "F.Cu")
		(net 350)
	)
	(segment
		(start 124.7 76.9)
		(end 124.7 79.6)
		(width 0.1)
		(layer "F.Cu")
		(net 350)
	)
	(segment
		(start 126 76.4)
		(end 125.2 76.4)
		(width 0.1)
		(layer "F.Cu")
		(net 350)
	)
	(segment
		(start 129.845 79.645)
		(end 129.845 80.601)
		(width 0.1)
		(layer "F.Cu")
		(net 350)
	)
	(segment
		(start 124.7 79.6)
		(end 125.1 80)
		(width 0.1)
		(layer "F.Cu")
		(net 350)
	)
	(segment
		(start 129.7 79.5)
		(end 129.845 79.645)
		(width 0.1)
		(layer "F.Cu")
		(net 350)
	)
	(segment
		(start 145.525001 94.674999)
		(end 142.790001 94.674999)
		(width 0.1)
		(layer "F.Cu")
		(net 350)
	)
	(via
		(at 144 94.674999)
		(size 0.45)
		(drill 0.2)
		(layers "F.Cu" "B.Cu")
		(remove_unused_layers yes)
		(keep_end_layers yes)
		(zone_layer_connections)
		(net 350)
	)
	(via
		(at 126.65 75.75)
		(size 0.45)
		(drill 0.2)
		(layers "F.Cu" "B.Cu")
		(remove_unused_layers yes)
		(keep_end_layers yes)
		(zone_layer_connections)
		(net 350)
	)
	(segment
		(start 126.654 75.73)
		(end 126.654 75.746)
		(width 0.25)
		(layer "B.Cu")
		(net 350)
	)
	(segment
		(start 126.654 75.746)
		(end 126.65 75.75)
		(width 0.25)
		(layer "B.Cu")
		(net 350)
	)
	(segment
		(start 141.474999 94.674999)
		(end 144 94.674999)
		(width 0.1)
		(layer "In3.Cu")
		(net 350)
	)
	(segment
		(start 138.899999 83.627209)
		(end 138.899999 92.099999)
		(width 0.1)
		(layer "In3.Cu")
		(net 350)
	)
	(segment
		(start 138.899999 92.099999)
		(end 141.474999 94.674999)
		(width 0.1)
		(layer "In3.Cu")
		(net 350)
	)
	(segment
		(start 126.1 76.3)
		(end 126.1 77.3)
		(width 0.1)
		(layer "In3.Cu")
		(net 350)
	)
	(segment
		(start 126.6 77.8)
		(end 130.87279 77.8)
		(width 0.1)
		(layer "In3.Cu")
		(net 350)
	)
	(segment
		(start 126.1 77.3)
		(end 126.6 77.8)
		(width 0.1)
		(layer "In3.Cu")
		(net 350)
	)
	(segment
		(start 137.572792 82.300002)
		(end 138.899999 83.627209)
		(width 0.1)
		(layer "In3.Cu")
		(net 350)
	)
	(segment
		(start 130.87279 77.8)
		(end 135.372792 82.300002)
		(width 0.1)
		(layer "In3.Cu")
		(net 350)
	)
	(segment
		(start 135.372792 82.300002)
		(end 137.572792 82.300002)
		(width 0.1)
		(layer "In3.Cu")
		(net 350)
	)
	(segment
		(start 126.65 75.75)
		(end 126.1 76.3)
		(width 0.1)
		(layer "In3.Cu")
		(net 350)
	)
	(segment
		(start 144.8 95.2)
		(end 145.4 95.2)
		(width 0.1)
		(layer "F.Cu")
		(net 351)
	)
	(segment
		(start 125.875 79.075)
		(end 130.79 79.075)
		(width 0.1)
		(layer "F.Cu")
		(net 351)
	)
	(segment
		(start 130.79 79.075)
		(end 131.115 79.4)
		(width 0.1)
		(layer "F.Cu")
		(net 351)
	)
	(segment
		(start 145.4 95.2)
		(end 147.98 92.62)
		(width 0.1)
		(layer "F.Cu")
		(net 351)
	)
	(segment
		(start 131.115 80.601)
		(end 131.115 79.4)
		(width 0.1)
		(layer "F.Cu")
		(net 351)
	)
	(segment
		(start 125.4 79.55)
		(end 125.875 79.075)
		(width 0.1)
		(layer "F.Cu")
		(net 351)
	)
	(segment
		(start 147.98 92.62)
		(end 147.98 91.749999)
		(width 0.1)
		(layer "F.Cu")
		(net 351)
	)
	(via
		(at 144.8 95.2)
		(size 0.45)
		(drill 0.2)
		(layers "F.Cu" "B.Cu")
		(remove_unused_layers yes)
		(keep_end_layers yes)
		(zone_layer_connections)
		(net 351)
	)
	(via
		(at 125.4 79.55)
		(size 0.45)
		(drill 0.2)
		(layers "F.Cu" "B.Cu")
		(remove_unused_layers yes)
		(keep_end_layers yes)
		(zone_layer_connections)
		(net 351)
	)
	(segment
		(start 125.385 79.539)
		(end 125.389 79.539)
		(width 0.25)
		(layer "B.Cu")
		(net 351)
	)
	(segment
		(start 125.389 79.539)
		(end 125.4 79.55)
		(width 0.25)
		(layer "B.Cu")
		(net 351)
	)
	(segment
		(start 125.85 79.1)
		(end 130.334314 79.1)
		(width 0.1)
		(layer "In3.Cu")
		(net 351)
	)
	(segment
		(start 125.4 79.55)
		(end 125.85 79.1)
		(width 0.1)
		(layer "In3.Cu")
		(net 351)
	)
	(segment
		(start 144.3 97)
		(end 144.8 96.5)
		(width 0.1)
		(layer "In3.Cu")
		(net 351)
	)
	(segment
		(start 134.834314 83.6)
		(end 137.034314 83.6)
		(width 0.1)
		(layer "In3.Cu")
		(net 351)
	)
	(segment
		(start 137.6 93.7)
		(end 140.9 97)
		(width 0.1)
		(layer "In3.Cu")
		(net 351)
	)
	(segment
		(start 140.9 97)
		(end 144.3 97)
		(width 0.1)
		(layer "In3.Cu")
		(net 351)
	)
	(segment
		(start 144.8 96.5)
		(end 144.8 95.2)
		(width 0.1)
		(layer "In3.Cu")
		(net 351)
	)
	(segment
		(start 130.334314 79.1)
		(end 134.834314 83.6)
		(width 0.1)
		(layer "In3.Cu")
		(net 351)
	)
	(segment
		(start 137.6 84.165686)
		(end 137.6 93.7)
		(width 0.1)
		(layer "In3.Cu")
		(net 351)
	)
	(segment
		(start 137.034314 83.6)
		(end 137.6 84.165686)
		(width 0.1)
		(layer "In3.Cu")
		(net 351)
	)
	(segment
		(start 131.7 78.7)
		(end 133.654 76.746)
		(width 0.1)
		(layer "F.Cu")
		(net 352)
	)
	(segment
		(start 133.654 76.746)
		(end 133.654 73.4)
		(width 0.1)
		(layer "F.Cu")
		(net 352)
	)
	(segment
		(start 145.2 96.2)
		(end 144 96.2)
		(width 0.1)
		(layer "F.Cu")
		(net 352)
	)
	(segment
		(start 149.71 91.749999)
		(end 149.650001 91.749999)
		(width 0.1)
		(layer "F.Cu")
		(net 352)
	)
	(segment
		(start 125.4 77)
		(end 125.4 77.9)
		(width 0.1)
		(layer "F.Cu")
		(net 352)
	)
	(segment
		(start 125.4 77.9)
		(end 126.2 78.7)
		(width 0.1)
		(layer "F.Cu")
		(net 352)
	)
	(segment
		(start 126.2 78.7)
		(end 131.7 78.7)
		(width 0.1)
		(layer "F.Cu")
		(net 352)
	)
	(segment
		(start 149.650001 91.749999)
		(end 145.2 96.2)
		(width 0.1)
		(layer "F.Cu")
		(net 352)
	)
	(via
		(at 144 96.2)
		(size 0.45)
		(drill 0.2)
		(layers "F.Cu" "B.Cu")
		(remove_unused_layers yes)
		(keep_end_layers yes)
		(zone_layer_connections)
		(net 352)
	)
	(via
		(at 125.4 77)
		(size 0.45)
		(drill 0.2)
		(layers "F.Cu" "B.Cu")
		(remove_unused_layers yes)
		(keep_end_layers yes)
		(zone_layer_connections)
		(net 352)
	)
	(segment
		(start 125.385 77)
		(end 125.4 77)
		(width 0.25)
		(layer "B.Cu")
		(net 352)
	)
	(segment
		(start 138 84)
		(end 138 93.5)
		(width 0.1)
		(layer "In3.Cu")
		(net 352)
	)
	(segment
		(start 140.7 96.2)
		(end 144 96.2)
		(width 0.1)
		(layer "In3.Cu")
		(net 352)
	)
	(segment
		(start 125.4 77)
		(end 125.4 78.1)
		(width 0.1)
		(layer "In3.Cu")
		(net 352)
	)
	(segment
		(start 138 93.5)
		(end 140.7 96.2)
		(width 0.1)
		(layer "In3.Cu")
		(net 352)
	)
	(segment
		(start 125.4 78.1)
		(end 126 78.7)
		(width 0.1)
		(layer "In3.Cu")
		(net 352)
	)
	(segment
		(start 135 83.2)
		(end 137.2 83.2)
		(width 0.1)
		(layer "In3.Cu")
		(net 352)
	)
	(segment
		(start 126 78.7)
		(end 130.5 78.7)
		(width 0.1)
		(layer "In3.Cu")
		(net 352)
	)
	(segment
		(start 130.5 78.7)
		(end 135 83.2)
		(width 0.1)
		(layer "In3.Cu")
		(net 352)
	)
	(segment
		(start 137.2 83.2)
		(end 138 84)
		(width 0.1)
		(layer "In3.Cu")
		(net 352)
	)
	(segment
		(start 126.65 78.25)
		(end 130.85 78.25)
		(width 0.1)
		(layer "F.Cu")
		(net 353)
	)
	(segment
		(start 141.074999 95.674999)
		(end 141 95.6)
		(width 0.1)
		(layer "F.Cu")
		(net 353)
	)
	(segment
		(start 141.83 95.674999)
		(end 141.074999 95.674999)
		(width 0.1)
		(layer "F.Cu")
		(net 353)
	)
	(segment
		(start 141.83 96.674999)
		(end 141.83 95.674999)
		(width 0.1)
		(layer "F.Cu")
		(net 353)
	)
	(segment
		(start 130.85 78.25)
		(end 132.383 76.717)
		(width 0.1)
		(layer "F.Cu")
		(net 353)
	)
	(segment
		(start 132.383 76.717)
		(end 132.383 73.4)
		(width 0.1)
		(layer "F.Cu")
		(net 353)
	)
	(via
		(at 126.65 78.25)
		(size 0.45)
		(drill 0.2)
		(layers "F.Cu" "B.Cu")
		(remove_unused_layers yes)
		(keep_end_layers yes)
		(zone_layer_connections)
		(net 353)
	)
	(via
		(at 141 95.6)
		(size 0.45)
		(drill 0.2)
		(layers "F.Cu" "B.Cu")
		(remove_unused_layers yes)
		(keep_end_layers yes)
		(zone_layer_connections)
		(net 353)
	)
	(segment
		(start 126.654 78.269)
		(end 126.654 78.254)
		(width 0.25)
		(layer "B.Cu")
		(net 353)
	)
	(segment
		(start 126.654 78.254)
		(end 126.65 78.25)
		(width 0.25)
		(layer "B.Cu")
		(net 353)
	)
	(segment
		(start 135.186396 82.750002)
		(end 137.386396 82.750002)
		(width 0.1)
		(layer "In3.Cu")
		(net 353)
	)
	(segment
		(start 126.65 78.25)
		(end 130.686394 78.25)
		(width 0.1)
		(layer "In3.Cu")
		(net 353)
	)
	(segment
		(start 137.386396 82.750002)
		(end 138.449999 83.813605)
		(width 0.1)
		(layer "In3.Cu")
		(net 353)
	)
	(segment
		(start 130.686394 78.25)
		(end 135.186396 82.750002)
		(width 0.1)
		(layer "In3.Cu")
		(net 353)
	)
	(segment
		(start 138.449999 93.049999)
		(end 141 95.6)
		(width 0.1)
		(layer "In3.Cu")
		(net 353)
	)
	(segment
		(start 138.449999 83.813605)
		(end 138.449999 93.049999)
		(width 0.1)
		(layer "In3.Cu")
		(net 353)
	)
	(segment
		(start 144.9 109.099999)
		(end 144.9 108.300001)
		(width 0.15)
		(layer "F.Cu")
		(net 355)
	)
	(segment
		(start 144.749999 108.149999)
		(end 144.33 108.149999)
		(width 0.15)
		(layer "F.Cu")
		(net 355)
	)
	(segment
		(start 146.430001 109.28)
		(end 145.080002 109.279999)
		(width 0.15)
		(layer "F.Cu")
		(net 355)
	)
	(segment
		(start 146.499999 109.349999)
		(end 146.430001 109.28)
		(width 0.15)
		(layer "F.Cu")
		(net 355)
	)
	(segment
		(start 156.1 117.4)
		(end 156.1 118.451)
		(width 0.1)
		(layer "F.Cu")
		(net 355)
	)
	(segment
		(start 145.080002 109.279999)
		(end 144.9 109.099999)
		(width 0.15)
		(layer "F.Cu")
		(net 355)
	)
	(segment
		(start 146.499999 109.474999)
		(end 146.499999 109.349999)
		(width 0.15)
		(layer "F.Cu")
		(net 355)
	)
	(segment
		(start 144.329998 108.15)
		(end 143.8 107.620002)
		(width 0.1)
		(layer "F.Cu")
		(net 355)
	)
	(segment
		(start 143.8 107.620002)
		(end 143.8 107.5)
		(width 0.1)
		(layer "F.Cu")
		(net 355)
	)
	(segment
		(start 144.9 108.300001)
		(end 144.749999 108.149999)
		(width 0.15)
		(layer "F.Cu")
		(net 355)
	)
	(via
		(at 143.8 107.5)
		(size 0.45)
		(drill 0.2)
		(layers "F.Cu" "B.Cu")
		(remove_unused_layers yes)
		(keep_end_layers yes)
		(zone_layer_connections)
		(net 355)
	)
	(via
		(at 156.1 117.4)
		(size 0.45)
		(drill 0.2)
		(layers "F.Cu" "B.Cu")
		(remove_unused_layers yes)
		(keep_end_layers yes)
		(zone_layer_connections)
		(net 355)
	)
	(segment
		(start 143.8 108.4)
		(end 143.8 107.5)
		(width 0.1)
		(layer "B.Cu")
		(net 355)
	)
	(segment
		(start 151.55 112.45)
		(end 149.3 110.2)
		(width 0.1)
		(layer "B.Cu")
		(net 355)
	)
	(segment
		(start 151.55 114.95)
		(end 151.55 112.45)
		(width 0.1)
		(layer "B.Cu")
		(net 355)
	)
	(segment
		(start 149.3 110.2)
		(end 145.6 110.2)
		(width 0.1)
		(layer "B.Cu")
		(net 355)
	)
	(segment
		(start 145.6 110.2)
		(end 143.8 108.4)
		(width 0.1)
		(layer "B.Cu")
		(net 355)
	)
	(segment
		(start 154 117.4)
		(end 151.55 114.95)
		(width 0.1)
		(layer "B.Cu")
		(net 355)
	)
	(segment
		(start 156.1 117.4)
		(end 154 117.4)
		(width 0.1)
		(layer "B.Cu")
		(net 355)
	)
	(segment
		(start 133.3 94.4)
		(end 132.6 94.4)
		(width 0.1)
		(layer "F.Cu")
		(net 356)
	)
	(segment
		(start 119 87.6)
		(end 119 87.3)
		(width 0.1)
		(layer "F.Cu")
		(net 356)
	)
	(segment
		(start 133.450001 94.874998)
		(end 133.450001 94.550001)
		(width 0.1)
		(layer "F.Cu")
		(net 356)
	)
	(segment
		(start 117.649 88.049)
		(end 118.551 88.049)
		(width 0.1)
		(layer "F.Cu")
		(net 356)
	)
	(segment
		(start 118.551 88.049)
		(end 119 87.6)
		(width 0.1)
		(layer "F.Cu")
		(net 356)
	)
	(segment
		(start 133.450001 94.550001)
		(end 133.3 94.4)
		(width 0.1)
		(layer "F.Cu")
		(net 356)
	)
	(via
		(at 132.6 94.4)
		(size 0.45)
		(drill 0.2)
		(layers "F.Cu" "B.Cu")
		(remove_unused_layers yes)
		(keep_end_layers yes)
		(zone_layer_connections)
		(net 356)
	)
	(via
		(at 119 87.3)
		(size 0.45)
		(drill 0.2)
		(layers "F.Cu" "B.Cu")
		(remove_unused_layers yes)
		(keep_end_layers yes)
		(zone_layer_connections)
		(net 356)
	)
	(via
		(at 128.3 91.9)
		(size 0.45)
		(drill 0.2)
		(layers "F.Cu" "B.Cu")
		(remove_unused_layers yes)
		(keep_end_layers yes)
		(zone_layer_connections)
		(net 356)
	)
	(segment
		(start 120.500001 88.400001)
		(end 119.4 87.3)
		(width 0.1)
		(layer "B.Cu")
		(net 356)
	)
	(segment
		(start 116 87.8)
		(end 116.5 87.3)
		(width 0.1)
		(layer "B.Cu")
		(net 356)
	)
	(segment
		(start 120.500001 89.269998)
		(end 120.500001 88.400001)
		(width 0.1)
		(layer "B.Cu")
		(net 356)
	)
	(segment
		(start 116.52 91.22)
		(end 116 90.7)
		(width 0.1)
		(layer "B.Cu")
		(net 356)
	)
	(segment
		(start 117.5 91.22)
		(end 116.52 91.22)
		(width 0.1)
		(layer "B.Cu")
		(net 356)
	)
	(segment
		(start 116.5 87.3)
		(end 119 87.3)
		(width 0.1)
		(layer "B.Cu")
		(net 356)
	)
	(segment
		(start 116 90.7)
		(end 116 87.8)
		(width 0.1)
		(layer "B.Cu")
		(net 356)
	)
	(segment
		(start 119.4 87.3)
		(end 119 87.3)
		(width 0.1)
		(layer "B.Cu")
		(net 356)
	)
	(segment
		(start 127.9 92.3)
		(end 128.3 91.9)
		(width 0.1)
		(layer "In3.Cu")
		(net 356)
	)
	(segment
		(start 127.9 92.83033)
		(end 127.9 92.3)
		(width 0.1)
		(layer "In3.Cu")
		(net 356)
	)
	(segment
		(start 127.9 92.83033)
		(end 128.169669 93.1)
		(width 0.1)
		(layer "In3.Cu")
		(net 356)
	)
	(segment
		(start 131.3 93.1)
		(end 128.169669 93.1)
		(width 0.1)
		(layer "In3.Cu")
		(net 356)
	)
	(segment
		(start 132.6 94.4)
		(end 131.3 93.1)
		(width 0.1)
		(layer "In3.Cu")
		(net 356)
	)
	(segment
		(start 125.4 90.8)
		(end 127.2 90.8)
		(width 0.1)
		(layer "In5.Cu")
		(net 356)
	)
	(segment
		(start 119 87.3)
		(end 121.9 87.3)
		(width 0.1)
		(layer "In5.Cu")
		(net 356)
	)
	(segment
		(start 121.9 87.3)
		(end 125.4 90.8)
		(width 0.1)
		(layer "In5.Cu")
		(net 356)
	)
	(segment
		(start 127.2 90.8)
		(end 128.3 91.9)
		(width 0.1)
		(layer "In5.Cu")
		(net 356)
	)
	(segment
		(start 132.1 114.4)
		(end 132.1 117.8)
		(width 0.1)
		(layer "F.Cu")
		(net 357)
	)
	(segment
		(start 142.8 133.55)
		(end 142.8 129.565686)
		(width 0.1)
		(layer "F.Cu")
		(net 357)
	)
	(segment
		(start 141.372183 134.977817)
		(end 142.8 133.55)
		(width 0.1)
		(layer "F.Cu")
		(net 357)
	)
	(segment
		(start 147.165 127.655)
		(end 147.1 127.72)
		(width 0.1)
		(layer "F.Cu")
		(net 357)
	)
	(segment
		(start 132.25 113.65)
		(end 132.25 114.25)
		(width 0.1)
		(layer "F.Cu")
		(net 357)
	)
	(segment
		(start 142.8 129.565686)
		(end 144.182843 128.182843)
		(width 0.1)
		(layer "F.Cu")
		(net 357)
	)
	(segment
		(start 139.35 135.5)
		(end 139.872183 134.977817)
		(width 0.1)
		(layer "F.Cu")
		(net 357)
	)
	(segment
		(start 137.5 135.5)
		(end 139.35 135.5)
		(width 0.1)
		(layer "F.Cu")
		(net 357)
	)
	(segment
		(start 144.182843 128.182843)
		(end 146.637157 128.182843)
		(width 0.1)
		(layer "F.Cu")
		(net 357)
	)
	(segment
		(start 132.25 114.25)
		(end 132.1 114.4)
		(width 0.1)
		(layer "F.Cu")
		(net 357)
	)
	(segment
		(start 132.18 117.88)
		(end 132.18 118.89)
		(width 0.1)
		(layer "F.Cu")
		(net 357)
	)
	(segment
		(start 147.165 125.801)
		(end 147.165 127.655)
		(width 0.1)
		(layer "F.Cu")
		(net 357)
	)
	(segment
		(start 132.1 117.8)
		(end 132.18 117.88)
		(width 0.1)
		(layer "F.Cu")
		(net 357)
	)
	(segment
		(start 139.872183 134.977817)
		(end 141.372183 134.977817)
		(width 0.1)
		(layer "F.Cu")
		(net 357)
	)
	(segment
		(start 146.637157 128.182843)
		(end 147.1 127.72)
		(width 0.1)
		(layer "F.Cu")
		(net 357)
	)
	(via
		(at 147.165 127)
		(size 0.45)
		(drill 0.2)
		(layers "F.Cu" "B.Cu")
		(remove_unused_layers yes)
		(keep_end_layers yes)
		(zone_layer_connections)
		(net 357)
	)
	(via
		(at 132.25 113.65)
		(size 0.45)
		(drill 0.2)
		(layers "F.Cu" "B.Cu")
		(remove_unused_layers yes)
		(keep_end_layers yes)
		(zone_layer_connections)
		(net 357)
	)
	(segment
		(start 133.3 112.3)
		(end 135.3 112.3)
		(width 0.1)
		(layer "In3.Cu")
		(net 357)
	)
	(segment
		(start 132.25 113.65)
		(end 132.25 113.35)
		(width 0.1)
		(layer "In3.Cu")
		(net 357)
	)
	(segment
		(start 132.25 113.35)
		(end 133.3 112.3)
		(width 0.1)
		(layer "In3.Cu")
		(net 357)
	)
	(segment
		(start 135.3 112.3)
		(end 136 113)
		(width 0.1)
		(layer "In3.Cu")
		(net 357)
	)
	(segment
		(start 149.1 123.4)
		(end 147.165 125.335)
		(width 0.1)
		(layer "In3.Cu")
		(net 357)
	)
	(segment
		(start 147.165 125.335)
		(end 147.165 127)
		(width 0.1)
		(layer "In3.Cu")
		(net 357)
	)
	(segment
		(start 149.1 119.9)
		(end 149.1 123.4)
		(width 0.1)
		(layer "In3.Cu")
		(net 357)
	)
	(segment
		(start 148 118.8)
		(end 149.1 119.9)
		(width 0.1)
		(layer "In3.Cu")
		(net 357)
	)
	(segment
		(start 137.625 113)
		(end 138.225 113.6)
		(width 0.1)
		(layer "In3.Cu")
		(net 357)
	)
	(segment
		(start 148 117.4)
		(end 148 118.8)
		(width 0.1)
		(layer "In3.Cu")
		(net 357)
	)
	(segment
		(start 144.2 113.6)
		(end 148 117.4)
		(width 0.1)
		(layer "In3.Cu")
		(net 357)
	)
	(segment
		(start 138.225 113.6)
		(end 144.2 113.6)
		(width 0.1)
		(layer "In3.Cu")
		(net 357)
	)
	(segment
		(start 136 113)
		(end 137.625 113)
		(width 0.1)
		(layer "In3.Cu")
		(net 357)
	)
	(segment
		(start 134.9 120.8)
		(end 134.6 120.8)
		(width 0.1)
		(layer "F.Cu")
		(net 358)
	)
	(segment
		(start 148.4 127.72)
		(end 148.4 125.834)
		(width 0.1)
		(layer "F.Cu")
		(net 358)
	)
	(segment
		(start 134.21 121.19)
		(end 133.56 121.19)
		(width 0.1)
		(layer "F.Cu")
		(net 358)
	)
	(segment
		(start 134.6 120.8)
		(end 134.21 121.19)
		(width 0.1)
		(layer "F.Cu")
		(net 358)
	)
	(segment
		(start 148.4 125.834)
		(end 148.433 125.801)
		(width 0.1)
		(layer "F.Cu")
		(net 358)
	)
	(via
		(at 134.9 120.8)
		(size 0.45)
		(drill 0.2)
		(layers "F.Cu" "B.Cu")
		(remove_unused_layers yes)
		(keep_end_layers yes)
		(zone_layer_connections)
		(net 358)
	)
	(via
		(at 148.4 127)
		(size 0.45)
		(drill 0.2)
		(layers "F.Cu" "B.Cu")
		(remove_unused_layers yes)
		(keep_end_layers yes)
		(zone_layer_connections)
		(net 358)
	)
	(segment
		(start 144.1 126.95)
		(end 145.1 126.95)
		(width 0.1)
		(layer "B.Cu")
		(net 358)
	)
	(segment
		(start 135.6 125.7)
		(end 142.85 125.7)
		(width 0.1)
		(layer "B.Cu")
		(net 358)
	)
	(segment
		(start 135.35 125.45)
		(end 135.6 125.7)
		(width 0.1)
		(layer "B.Cu")
		(net 358)
	)
	(segment
		(start 147.8 127.6)
		(end 148.4 127)
		(width 0.1)
		(layer "B.Cu")
		(net 358)
	)
	(segment
		(start 142.85 125.7)
		(end 144.1 126.95)
		(width 0.1)
		(layer "B.Cu")
		(net 358)
	)
	(segment
		(start 145.1 126.95)
		(end 145.75 127.6)
		(width 0.1)
		(layer "B.Cu")
		(net 358)
	)
	(segment
		(start 145.75 127.6)
		(end 147.8 127.6)
		(width 0.1)
		(layer "B.Cu")
		(net 358)
	)
	(segment
		(start 134.9 120.8)
		(end 135.35 121.25)
		(width 0.1)
		(layer "B.Cu")
		(net 358)
	)
	(segment
		(start 135.35 121.25)
		(end 135.35 125.45)
		(width 0.1)
		(layer "B.Cu")
		(net 358)
	)
	(segment
		(start 137.25 134.75)
		(end 139 134.75)
		(width 0.1)
		(layer "F.Cu")
		(net 359)
	)
	(segment
		(start 133.15 114.45)
		(end 133.15 113.65)
		(width 0.1)
		(layer "F.Cu")
		(net 359)
	)
	(segment
		(start 144.034315 125.834315)
		(end 144 125.8)
		(width 0.1)
		(layer "F.Cu")
		(net 359)
	)
	(segment
		(start 145.8 127.72)
		(end 145.8 125.896)
		(width 0.1)
		(layer "F.Cu")
		(net 359)
	)
	(segment
		(start 133.35 114.65)
		(end 133.15 114.45)
		(width 0.1)
		(layer "F.Cu")
		(net 359)
	)
	(segment
		(start 132.64 118.89)
		(end 132.64 118.36)
		(width 0.1)
		(layer "F.Cu")
		(net 359)
	)
	(segment
		(start 132.64 118.36)
		(end 133.35 117.65)
		(width 0.1)
		(layer "F.Cu")
		(net 359)
	)
	(segment
		(start 133.35 117.65)
		(end 133.35 114.65)
		(width 0.1)
		(layer "F.Cu")
		(net 359)
	)
	(segment
		(start 139 134.75)
		(end 139.55 134.2)
		(width 0.1)
		(layer "F.Cu")
		(net 359)
	)
	(segment
		(start 141.05 134.2)
		(end 141.6 133.65)
		(width 0.1)
		(layer "F.Cu")
		(net 359)
	)
	(segment
		(start 141.6 133.65)
		(end 141.6 129.06863)
		(width 0.1)
		(layer "F.Cu")
		(net 359)
	)
	(segment
		(start 144.034315 126.634315)
		(end 144.034315 125.834315)
		(width 0.1)
		(layer "F.Cu")
		(net 359)
	)
	(segment
		(start 141.6 129.06863)
		(end 144.034315 126.634315)
		(width 0.1)
		(layer "F.Cu")
		(net 359)
	)
	(segment
		(start 145.8 125.896)
		(end 145.895 125.801)
		(width 0.1)
		(layer "F.Cu")
		(net 359)
	)
	(segment
		(start 139.55 134.2)
		(end 141.05 134.2)
		(width 0.1)
		(layer "F.Cu")
		(net 359)
	)
	(segment
		(start 137 135)
		(end 137.25 134.75)
		(width 0.1)
		(layer "F.Cu")
		(net 359)
	)
	(via
		(at 144 125.8)
		(size 0.45)
		(drill 0.2)
		(layers "F.Cu" "B.Cu")
		(remove_unused_layers yes)
		(keep_end_layers yes)
		(zone_layer_connections)
		(net 359)
	)
	(via
		(at 133.15 113.65)
		(size 0.45)
		(drill 0.2)
		(layers "F.Cu" "B.Cu")
		(remove_unused_layers yes)
		(keep_end_layers yes)
		(zone_layer_connections)
		(net 359)
	)
	(via
		(at 145.8 127)
		(size 0.45)
		(drill 0.2)
		(layers "F.Cu" "B.Cu")
		(remove_unused_layers yes)
		(keep_end_layers yes)
		(zone_layer_connections)
		(net 359)
	)
	(segment
		(start 144.6 125.8)
		(end 145.8 127)
		(width 0.1)
		(layer "B.Cu")
		(net 359)
	)
	(segment
		(start 144 125.8)
		(end 144.6 125.8)
		(width 0.1)
		(layer "B.Cu")
		(net 359)
	)
	(segment
		(start 135.4 113.6)
		(end 137.4 113.6)
		(width 0.1)
		(layer "In3.Cu")
		(net 359)
	)
	(segment
		(start 145.8 125)
		(end 145.8 127)
		(width 0.1)
		(layer "In3.Cu")
		(net 359)
	)
	(segment
		(start 142.3 114.3)
		(end 144.4 116.4)
		(width 0.1)
		(layer "In3.Cu")
		(net 359)
	)
	(segment
		(start 138.1 114.3)
		(end 142.3 114.3)
		(width 0.1)
		(layer "In3.Cu")
		(net 359)
	)
	(segment
		(start 147.2 118.2)
		(end 147.2 121.2)
		(width 0.1)
		(layer "In3.Cu")
		(net 359)
	)
	(segment
		(start 148.4 122.4)
		(end 148.4 123.2)
		(width 0.1)
		(layer "In3.Cu")
		(net 359)
	)
	(segment
		(start 145.4 116.4)
		(end 147.2 118.2)
		(width 0.1)
		(layer "In3.Cu")
		(net 359)
	)
	(segment
		(start 147.2 121.2)
		(end 148.4 122.4)
		(width 0.1)
		(layer "In3.Cu")
		(net 359)
	)
	(segment
		(start 147.4 124.2)
		(end 146.6 124.2)
		(width 0.1)
		(layer "In3.Cu")
		(net 359)
	)
	(segment
		(start 137.4 113.6)
		(end 138.1 114.3)
		(width 0.1)
		(layer "In3.Cu")
		(net 359)
	)
	(segment
		(start 146.6 124.2)
		(end 145.8 125)
		(width 0.1)
		(layer "In3.Cu")
		(net 359)
	)
	(segment
		(start 133.85 112.95)
		(end 134.75 112.95)
		(width 0.1)
		(layer "In3.Cu")
		(net 359)
	)
	(segment
		(start 144.4 116.4)
		(end 145.4 116.4)
		(width 0.1)
		(layer "In3.Cu")
		(net 359)
	)
	(segment
		(start 134.75 112.95)
		(end 135.4 113.6)
		(width 0.1)
		(layer "In3.Cu")
		(net 359)
	)
	(segment
		(start 148.4 123.2)
		(end 147.4 124.2)
		(width 0.1)
		(layer "In3.Cu")
		(net 359)
	)
	(segment
		(start 133.15 113.65)
		(end 133.85 112.95)
		(width 0.1)
		(layer "In3.Cu")
		(net 359)
	)
	(segment
		(start 124.185 130.567512)
		(end 123.575 131.177512)
		(width 0.19)
		(layer "F.Cu")
		(net 360)
	)
	(segment
		(start 124.13 129.52)
		(end 124.13 128.942634)
		(width 0.1)
		(layer "F.Cu")
		(net 360)
	)
	(segment
		(start 124.13 129.52)
		(end 124.13 129.695)
		(width 0.19)
		(layer "F.Cu")
		(net 360)
	)
	(segment
		(start 123.575 131.177512)
		(end 123.575 132.125)
		(width 0.19)
		(layer "F.Cu")
		(net 360)
	)
	(segment
		(start 124.245 128.665)
		(end 124.36 128.55)
		(width 0.1)
		(layer "F.Cu")
		(net 360)
	)
	(segment
		(start 124.185 129.75)
		(end 124.185 130.567512)
		(width 0.19)
		(layer "F.Cu")
		(net 360)
	)
	(segment
		(start 124.13 129.695)
		(end 124.185 129.75)
		(width 0.19)
		(layer "F.Cu")
		(net 360)
	)
	(segment
		(start 123.575 132.125)
		(end 123.45 132.25)
		(width 0.19)
		(layer "F.Cu")
		(net 360)
	)
	(via
		(at 123.45 132.25)
		(size 0.45)
		(drill 0.2)
		(layers "F.Cu" "B.Cu")
		(remove_unused_layers yes)
		(keep_end_layers yes)
		(zone_layer_connections)
		(net 360)
	)
	(via
		(at 120 148.85)
		(size 0.45)
		(drill 0.2)
		(layers "F.Cu" "B.Cu")
		(remove_unused_layers yes)
		(keep_end_layers yes)
		(zone_layer_connections)
		(net 360)
	)
	(arc
		(start 124.13 128.942634)
		(mid 124.159888 128.792379)
		(end 124.245 128.665)
		(width 0.1)
		(layer "F.Cu")
		(net 360)
	)
	(segment
		(start 122.575 138.677512)
		(end 124.325 136.927512)
		(width 0.19)
		(layer "B.Cu")
		(net 360)
	)
	(segment
		(start 124.325 133.822488)
		(end 123.575 133.072488)
		(width 0.19)
		(layer "B.Cu")
		(net 360)
	)
	(segment
		(start 122.575 141.427512)
		(end 122.575 138.677512)
		(width 0.19)
		(layer "B.Cu")
		(net 360)
	)
	(segment
		(start 120.525 148.527512)
		(end 120.525 147.772488)
		(width 0.19)
		(layer "B.Cu")
		(net 360)
	)
	(segment
		(start 123.575 133.072488)
		(end 123.575 132.375)
		(width 0.19)
		(layer "B.Cu")
		(net 360)
	)
	(segment
		(start 120.05 148.8)
		(end 120.252512 148.8)
		(width 0.19)
		(layer "B.Cu")
		(net 360)
	)
	(segment
		(start 124.325 136.927512)
		(end 124.325 133.822488)
		(width 0.19)
		(layer "B.Cu")
		(net 360)
	)
	(segment
		(start 120.225 143.777512)
		(end 122.575 141.427512)
		(width 0.19)
		(layer "B.Cu")
		(net 360)
	)
	(segment
		(start 119.99878 145.762874)
		(end 119.99878 145.589094)
		(width 0.19)
		(layer "B.Cu")
		(net 360)
	)
	(segment
		(start 120.252512 148.8)
		(end 120.525 148.527512)
		(width 0.19)
		(layer "B.Cu")
		(net 360)
	)
	(segment
		(start 120.225 145.362874)
		(end 120.225 143.777512)
		(width 0.19)
		(layer "B.Cu")
		(net 360)
	)
	(segment
		(start 123.575 132.375)
		(end 123.45 132.25)
		(width 0.19)
		(layer "B.Cu")
		(net 360)
	)
	(segment
		(start 120.225 147.472488)
		(end 120.225 145.989094)
		(width 0.19)
		(layer "B.Cu")
		(net 360)
	)
	(segment
		(start 120 148.85)
		(end 120.05 148.8)
		(width 0.19)
		(layer "B.Cu")
		(net 360)
	)
	(segment
		(start 120.525 147.772488)
		(end 120.225 147.472488)
		(width 0.19)
		(layer "B.Cu")
		(net 360)
	)
	(arc
		(start 120.11189 145.875984)
		(mid 120.031909 145.842855)
		(end 119.99878 145.762874)
		(width 0.19)
		(layer "B.Cu")
		(net 360)
	)
	(arc
		(start 120.11189 145.475984)
		(mid 120.191871 145.442855)
		(end 120.225 145.362874)
		(width 0.19)
		(layer "B.Cu")
		(net 360)
	)
	(arc
		(start 120.225 145.989094)
		(mid 120.191871 145.909113)
		(end 120.11189 145.875984)
		(width 0.19)
		(layer "B.Cu")
		(net 360)
	)
	(arc
		(start 119.99878 145.589094)
		(mid 120.031909 145.509113)
		(end 120.11189 145.475984)
		(width 0.19)
		(layer "B.Cu")
		(net 360)
	)
	(segment
		(start 132.18 137.5)
		(end 132.5 137.5)
		(width 0.1)
		(layer "F.Cu")
		(net 361)
	)
	(segment
		(start 121.5 148.525)
		(end 121.4 148.425)
		(width 0.1)
		(layer "F.Cu")
		(net 361)
	)
	(segment
		(start 121.5 149.1)
		(end 121.5 148.525)
		(width 0.1)
		(layer "F.Cu")
		(net 361)
	)
	(segment
		(start 132 137.68)
		(end 132.18 137.5)
		(width 0.1)
		(layer "F.Cu")
		(net 361)
	)
	(via
		(at 132 137.68)
		(size 0.45)
		(drill 0.2)
		(layers "F.Cu" "B.Cu")
		(remove_unused_layers yes)
		(keep_end_layers yes)
		(zone_layer_connections)
		(net 361)
	)
	(via
		(at 121.4 148.425)
		(size 0.45)
		(drill 0.2)
		(layers "F.Cu" "B.Cu")
		(remove_unused_layers yes)
		(keep_end_layers yes)
		(zone_layer_connections)
		(net 361)
	)
	(segment
		(start 131.9 139.2)
		(end 132.3 138.8)
		(width 0.1)
		(layer "In3.Cu")
		(net 361)
	)
	(segment
		(start 124.1 147.3)
		(end 125.2 146.2)
		(width 0.1)
		(layer "In3.Cu")
		(net 361)
	)
	(segment
		(start 127.4 144.7)
		(end 127.4 143.1)
		(width 0.1)
		(layer "In3.Cu")
		(net 361)
	)
	(segment
		(start 127.4 143.1)
		(end 129.6 140.9)
		(width 0.1)
		(layer "In3.Cu")
		(net 361)
	)
	(segment
		(start 132.3 137.98)
		(end 132 137.68)
		(width 0.1)
		(layer "In3.Cu")
		(net 361)
	)
	(segment
		(start 125.9 146.2)
		(end 127.4 144.7)
		(width 0.1)
		(layer "In3.Cu")
		(net 361)
	)
	(segment
		(start 122.1 147.3)
		(end 124.1 147.3)
		(width 0.1)
		(layer "In3.Cu")
		(net 361)
	)
	(segment
		(start 129.6 140.9)
		(end 129.6 140.1)
		(width 0.1)
		(layer "In3.Cu")
		(net 361)
	)
	(segment
		(start 130.5 139.2)
		(end 131.9 139.2)
		(width 0.1)
		(layer "In3.Cu")
		(net 361)
	)
	(segment
		(start 129.6 140.1)
		(end 130.5 139.2)
		(width 0.1)
		(layer "In3.Cu")
		(net 361)
	)
	(segment
		(start 121.4 148.425)
		(end 121.4 148)
		(width 0.1)
		(layer "In3.Cu")
		(net 361)
	)
	(segment
		(start 125.2 146.2)
		(end 125.9 146.2)
		(width 0.1)
		(layer "In3.Cu")
		(net 361)
	)
	(segment
		(start 121.4 148)
		(end 122.1 147.3)
		(width 0.1)
		(layer "In3.Cu")
		(net 361)
	)
	(segment
		(start 132.3 138.8)
		(end 132.3 137.98)
		(width 0.1)
		(layer "In3.Cu")
		(net 361)
	)
	(segment
		(start 127.3 130.802512)
		(end 127.3 129.75)
		(width 0.19)
		(layer "F.Cu")
		(net 362)
	)
	(segment
		(start 124.749 147.498)
		(end 124.749 146.822999)
		(width 0.19)
		(layer "F.Cu")
		(net 362)
	)
	(segment
		(start 127.35 128.927426)
		(end 127.35 129.52)
		(width 0.1)
		(layer "F.Cu")
		(net 362)
	)
	(segment
		(start 124.674 146.747999)
		(end 124.674 139.073488)
		(width 0.19)
		(layer "F.Cu")
		(net 362)
	)
	(segment
		(start 124.749 146.822999)
		(end 124.674 146.747999)
		(width 0.19)
		(layer "F.Cu")
		(net 362)
	)
	(segment
		(start 127.247574 128.825)
		(end 127.222427 128.825)
		(width 0.1)
		(layer "F.Cu")
		(net 362)
	)
	(segment
		(start 128.175 135.572488)
		(end 128.175 131.677512)
		(width 0.19)
		(layer "F.Cu")
		(net 362)
	)
	(segment
		(start 127.355 129.695)
		(end 127.355 129.52)
		(width 0.19)
		(layer "F.Cu")
		(net 362)
	)
	(segment
		(start 127.3 129.75)
		(end 127.355 129.695)
		(width 0.19)
		(layer "F.Cu")
		(net 362)
	)
	(segment
		(start 127.12 128.927425)
		(end 127.12 129.01)
		(width 0.1)
		(layer "F.Cu")
		(net 362)
	)
	(segment
		(start 128.175 131.677512)
		(end 127.3 130.802512)
		(width 0.19)
		(layer "F.Cu")
		(net 362)
	)
	(segment
		(start 124.674 139.073488)
		(end 128.175 135.572488)
		(width 0.19)
		(layer "F.Cu")
		(net 362)
	)
	(arc
		(start 127.32 128.855)
		(mid 127.342204 128.888229)
		(end 127.35 128.927426)
		(width 0.1)
		(layer "F.Cu")
		(net 362)
	)
	(arc
		(start 127.15 128.855)
		(mid 127.127797 128.888229)
		(end 127.12 128.927425)
		(width 0.1)
		(layer "F.Cu")
		(net 362)
	)
	(arc
		(start 127.15 128.855)
		(mid 127.183229 128.832796)
		(end 127.222427 128.825)
		(width 0.1)
		(layer "F.Cu")
		(net 362)
	)
	(arc
		(start 127.32 128.855)
		(mid 127.286771 128.832796)
		(end 127.247574 128.825)
		(width 0.1)
		(layer "F.Cu")
		(net 362)
	)
	(segment
		(start 124.59 129.238786)
		(end 124.59 129.51)
		(width 0.1)
		(layer "F.Cu")
		(net 363)
	)
	(segment
		(start 124.535 130.712488)
		(end 123.925 131.322488)
		(width 0.19)
		(layer "F.Cu")
		(net 363)
	)
	(segment
		(start 123.925 131.322488)
		(end 123.925 132.125)
		(width 0.19)
		(layer "F.Cu")
		(net 363)
	)
	(segment
		(start 124.487574 128.825)
		(end 124.462427 128.825)
		(width 0.1)
		(layer "F.Cu")
		(net 363)
	)
	(segment
		(start 124.36 128.927425)
		(end 124.36 129.01)
		(width 0.1)
		(layer "F.Cu")
		(net 363)
	)
	(segment
		(start 123.925 132.125)
		(end 124.05 132.25)
		(width 0.19)
		(layer "F.Cu")
		(net 363)
	)
	(segment
		(start 124.59 129.695)
		(end 124.535 129.75)
		(width 0.19)
		(layer "F.Cu")
		(net 363)
	)
	(segment
		(start 124.59 129.51)
		(end 124.59 129.695)
		(width 0.19)
		(layer "F.Cu")
		(net 363)
	)
	(segment
		(start 124.59 128.927426)
		(end 124.59 129.238786)
		(width 0.1)
		(layer "F.Cu")
		(net 363)
	)
	(segment
		(start 124.535 129.75)
		(end 124.535 130.712488)
		(width 0.19)
		(layer "F.Cu")
		(net 363)
	)
	(via
		(at 120.5 149.3)
		(size 0.45)
		(drill 0.2)
		(layers "F.Cu" "B.Cu")
		(remove_unused_layers yes)
		(keep_end_layers yes)
		(zone_layer_connections)
		(net 363)
	)
	(via
		(at 124.05 132.25)
		(size 0.45)
		(drill 0.2)
		(layers "F.Cu" "B.Cu")
		(remove_unused_layers yes)
		(keep_end_layers yes)
		(zone_layer_connections)
		(net 363)
	)
	(arc
		(start 124.39 128.855)
		(mid 124.423229 128.832796)
		(end 124.462427 128.825)
		(width 0.1)
		(layer "F.Cu")
		(net 363)
	)
	(arc
		(start 124.39 128.855)
		(mid 124.367797 128.888229)
		(end 124.36 128.927425)
		(width 0.1)
		(layer "F.Cu")
		(net 363)
	)
	(arc
		(start 124.56 128.855)
		(mid 124.582204 128.888229)
		(end 124.59 128.927426)
		(width 0.1)
		(layer "F.Cu")
		(net 363)
	)
	(arc
		(start 124.56 128.855)
		(mid 124.526771 128.832796)
		(end 124.487574 128.825)
		(width 0.1)
		(layer "F.Cu")
		(net 363)
	)
	(segment
		(start 122.925 141.572488)
		(end 120.575 143.922488)
		(width 0.19)
		(layer "B.Cu")
		(net 363)
	)
	(segment
		(start 124.675 133.677512)
		(end 124.675 137.072488)
		(width 0.19)
		(layer "B.Cu")
		(net 363)
	)
	(segment
		(start 120.875 148.672488)
		(end 120.5 149.047488)
		(width 0.19)
		(layer "B.Cu")
		(net 363)
	)
	(segment
		(start 120.575 143.922488)
		(end 120.575 147.327512)
		(width 0.19)
		(layer "B.Cu")
		(net 363)
	)
	(segment
		(start 122.925 138.822488)
		(end 122.925 141.572488)
		(width 0.19)
		(layer "B.Cu")
		(net 363)
	)
	(segment
		(start 124.675 137.072488)
		(end 122.925 138.822488)
		(width 0.19)
		(layer "B.Cu")
		(net 363)
	)
	(segment
		(start 123.925 132.927512)
		(end 124.675 133.677512)
		(width 0.19)
		(layer "B.Cu")
		(net 363)
	)
	(segment
		(start 120.875 147.627512)
		(end 120.875 148.672488)
		(width 0.19)
		(layer "B.Cu")
		(net 363)
	)
	(segment
		(start 120.5 149.047488)
		(end 120.5 149.3)
		(width 0.19)
		(layer "B.Cu")
		(net 363)
	)
	(segment
		(start 123.925 132.375)
		(end 123.925 132.927512)
		(width 0.19)
		(layer "B.Cu")
		(net 363)
	)
	(segment
		(start 124.05 132.25)
		(end 123.925 132.375)
		(width 0.19)
		(layer "B.Cu")
		(net 363)
	)
	(segment
		(start 120.575 147.327512)
		(end 120.875 147.627512)
		(width 0.19)
		(layer "B.Cu")
		(net 363)
	)
	(segment
		(start 126.95 129.75)
		(end 126.895 129.695)
		(width 0.19)
		(layer "F.Cu")
		(net 364)
	)
	(segment
		(start 124.324 146.747999)
		(end 124.324 138.928512)
		(width 0.19)
		(layer "F.Cu")
		(net 364)
	)
	(segment
		(start 126.95 130.947488)
		(end 126.95 129.75)
		(width 0.19)
		(layer "F.Cu")
		(net 364)
	)
	(segment
		(start 127.825 131.822488)
		(end 126.95 130.947488)
		(width 0.19)
		(layer "F.Cu")
		(net 364)
	)
	(segment
		(start 124.324 138.928512)
		(end 127.825 135.427512)
		(width 0.19)
		(layer "F.Cu")
		(net 364)
	)
	(segment
		(start 127.005 128.665)
		(end 127.12 128.55)
		(width 0.1)
		(layer "F.Cu")
		(net 364)
	)
	(segment
		(start 124.249 147.498)
		(end 124.249 146.822999)
		(width 0.19)
		(layer "F.Cu")
		(net 364)
	)
	(segment
		(start 126.89 128.942634)
		(end 126.89 129.52)
		(width 0.1)
		(layer "F.Cu")
		(net 364)
	)
	(segment
		(start 126.895 129.695)
		(end 126.895 129.52)
		(width 0.19)
		(layer "F.Cu")
		(net 364)
	)
	(segment
		(start 127.825 135.427512)
		(end 127.825 131.822488)
		(width 0.19)
		(layer "F.Cu")
		(net 364)
	)
	(segment
		(start 124.249 146.822999)
		(end 124.324 146.747999)
		(width 0.19)
		(layer "F.Cu")
		(net 364)
	)
	(arc
		(start 127.005 128.665)
		(mid 126.919888 128.792379)
		(end 126.89 128.942634)
		(width 0.1)
		(layer "F.Cu")
		(net 364)
	)
	(segment
		(start 132.2625 136.725)
		(end 132.3 136.7625)
		(width 0.1)
		(layer "F.Cu")
		(net 365)
	)
	(segment
		(start 133 137)
		(end 132.88125 136.88125)
		(width 0.1)
		(layer "F.Cu")
		(net 365)
	)
	(segment
		(start 130.35 136.575)
		(end 130.5 136.725)
		(width 0.16)
		(layer "F.Cu")
		(net 365)
	)
	(segment
		(start 122.3995 148.7)
		(end 122.399501 148.699999)
		(width 0.16)
		(layer "F.Cu")
		(net 365)
	)
	(segment
		(start 132.594563 136.7625)
		(end 132.3 136.7625)
		(width 0.1)
		(layer "F.Cu")
		(net 365)
	)
	(segment
		(start 122.399501 148.549999)
		(end 122.5495 148.4)
		(width 0.16)
		(layer "F.Cu")
		(net 365)
	)
	(segment
		(start 122.499 148.835)
		(end 122.3995 148.7355)
		(width 0.16)
		(layer "F.Cu")
		(net 365)
	)
	(segment
		(start 122.399501 148.699999)
		(end 122.399501 148.549999)
		(width 0.16)
		(layer "F.Cu")
		(net 365)
	)
	(segment
		(start 122.3995 148.7355)
		(end 122.3995 148.7)
		(width 0.16)
		(layer "F.Cu")
		(net 365)
	)
	(segment
		(start 130.5 136.725)
		(end 131.85 136.725)
		(width 0.16)
		(layer "F.Cu")
		(net 365)
	)
	(segment
		(start 122.499 149.1)
		(end 122.499 148.835)
		(width 0.16)
		(layer "F.Cu")
		(net 365)
	)
	(segment
		(start 131.85 136.725)
		(end 132.2625 136.725)
		(width 0.1)
		(layer "F.Cu")
		(net 365)
	)
	(via
		(at 130.35 136.575)
		(size 0.45)
		(drill 0.2)
		(layers "F.Cu" "B.Cu")
		(remove_unused_layers yes)
		(keep_end_layers yes)
		(zone_layer_connections)
		(net 365)
	)
	(via
		(at 122.5495 148.4)
		(size 0.45)
		(drill 0.2)
		(layers "F.Cu" "B.Cu")
		(remove_unused_layers yes)
		(keep_end_layers yes)
		(zone_layer_connections)
		(net 365)
	)
	(arc
		(start 132.88125 136.88125)
		(mid 132.749717 136.793362)
		(end 132.594563 136.7625)
		(width 0.1)
		(layer "F.Cu")
		(net 365)
	)
	(segment
		(start 122.3995 148.55)
		(end 122.3995 148.787368)
		(width 0.16)
		(layer "In5.Cu")
		(net 365)
	)
	(segment
		(start 122.937868 149.05)
		(end 123.65 148.337868)
		(width 0.16)
		(layer "In5.Cu")
		(net 365)
	)
	(segment
		(start 124.3 147.087868)
		(end 124.3 141.987868)
		(width 0.16)
		(layer "In5.Cu")
		(net 365)
	)
	(segment
		(start 129.562869 136.724999)
		(end 130.200001 136.724999)
		(width 0.16)
		(layer "In5.Cu")
		(net 365)
	)
	(segment
		(start 122.5495 148.4)
		(end 122.3995 148.55)
		(width 0.16)
		(layer "In5.Cu")
		(net 365)
	)
	(segment
		(start 124.3 141.987868)
		(end 129.562869 136.724999)
		(width 0.16)
		(layer "In5.Cu")
		(net 365)
	)
	(segment
		(start 122.3995 148.787368)
		(end 122.662132 149.05)
		(width 0.16)
		(layer "In5.Cu")
		(net 365)
	)
	(segment
		(start 123.65 147.737868)
		(end 124.3 147.087868)
		(width 0.16)
		(layer "In5.Cu")
		(net 365)
	)
	(segment
		(start 123.65 148.337868)
		(end 123.65 147.737868)
		(width 0.16)
		(layer "In5.Cu")
		(net 365)
	)
	(segment
		(start 122.662132 149.05)
		(end 122.937868 149.05)
		(width 0.16)
		(layer "In5.Cu")
		(net 365)
	)
	(segment
		(start 130.200001 136.724999)
		(end 130.35 136.575)
		(width 0.16)
		(layer "In5.Cu")
		(net 365)
	)
	(segment
		(start 131.95 136.5)
		(end 131.85 136.4)
		(width 0.1)
		(layer "F.Cu")
		(net 366)
	)
	(segment
		(start 122.649501 146.949999)
		(end 122.7995 146.8)
		(width 0.16)
		(layer "F.Cu")
		(net 366)
	)
	(segment
		(start 132.5 136.5)
		(end 131.95 136.5)
		(width 0.1)
		(layer "F.Cu")
		(net 366)
	)
	(segment
		(start 131.85 136.4)
		(end 131.65 136.4)
		(width 0.1)
		(layer "F.Cu")
		(net 366)
	)
	(segment
		(start 122.749 147.498)
		(end 122.649501 147.398501)
		(width 0.16)
		(layer "F.Cu")
		(net 366)
	)
	(segment
		(start 129.05 135.95)
		(end 129.199999 135.800001)
		(width 0.16)
		(layer "F.Cu")
		(net 366)
	)
	(segment
		(start 131.037868 136.45)
		(end 131.6 136.45)
		(width 0.16)
		(layer "F.Cu")
		(net 366)
	)
	(segment
		(start 122.649501 147.398501)
		(end 122.649501 146.949999)
		(width 0.16)
		(layer "F.Cu")
		(net 366)
	)
	(segment
		(start 130.387869 135.800001)
		(end 131.037868 136.45)
		(width 0.16)
		(layer "F.Cu")
		(net 366)
	)
	(segment
		(start 131.65 136.4)
		(end 131.6 136.45)
		(width 0.1)
		(layer "F.Cu")
		(net 366)
	)
	(segment
		(start 129.199999 135.800001)
		(end 130.387869 135.800001)
		(width 0.16)
		(layer "F.Cu")
		(net 366)
	)
	(via
		(at 122.7995 146.8)
		(size 0.45)
		(drill 0.2)
		(layers "F.Cu" "B.Cu")
		(remove_unused_layers yes)
		(keep_end_layers yes)
		(zone_layer_connections)
		(net 366)
	)
	(via
		(at 129.05 135.95)
		(size 0.45)
		(drill 0.2)
		(layers "F.Cu" "B.Cu")
		(remove_unused_layers yes)
		(keep_end_layers yes)
		(zone_layer_connections)
		(net 366)
	)
	(segment
		(start 123.637794 140.574337)
		(end 128.412131 135.800001)
		(width 0.16)
		(layer "In5.Cu")
		(net 366)
	)
	(segment
		(start 123.776121 141.306634)
		(end 123.825618 141.257136)
		(width 0.16)
		(layer "In5.Cu")
		(net 366)
	)
	(segment
		(start 128.900001 135.800001)
		(end 129.05 135.95)
		(width 0.16)
		(layer "In5.Cu")
		(net 366)
	)
	(segment
		(start 122.649501 141.562631)
		(end 123.14282 141.069312)
		(width 0.16)
		(layer "In5.Cu")
		(net 366)
	)
	(segment
		(start 122.649501 146.650001)
		(end 122.649501 141.562631)
		(width 0.16)
		(layer "In5.Cu")
		(net 366)
	)
	(segment
		(start 122.7995 146.8)
		(end 122.649501 146.650001)
		(width 0.16)
		(layer "In5.Cu")
		(net 366)
	)
	(segment
		(start 123.340809 141.069312)
		(end 123.578131 141.306634)
		(width 0.16)
		(layer "In5.Cu")
		(net 366)
	)
	(segment
		(start 123.825618 141.059146)
		(end 123.588295 140.821823)
		(width 0.16)
		(layer "In5.Cu")
		(net 366)
	)
	(segment
		(start 123.588295 140.623833)
		(end 123.637794 140.574337)
		(width 0.16)
		(layer "In5.Cu")
		(net 366)
	)
	(segment
		(start 128.412131 135.800001)
		(end 128.900001 135.800001)
		(width 0.16)
		(layer "In5.Cu")
		(net 366)
	)
	(arc
		(start 123.825618 141.257136)
		(mid 123.866623 141.158141)
		(end 123.825618 141.059146)
		(width 0.16)
		(layer "In5.Cu")
		(net 366)
	)
	(arc
		(start 123.14282 141.069312)
		(mid 123.241814 141.028307)
		(end 123.340809 141.069312)
		(width 0.16)
		(layer "In5.Cu")
		(net 366)
	)
	(arc
		(start 123.588295 140.821823)
		(mid 123.54729 140.722828)
		(end 123.588295 140.623833)
		(width 0.16)
		(layer "In5.Cu")
		(net 366)
	)
	(arc
		(start 123.578131 141.306634)
		(mid 123.677126 141.347639)
		(end 123.776121 141.306634)
		(width 0.16)
		(layer "In5.Cu")
		(net 366)
	)
	(segment
		(start 130.5 137.025)
		(end 131.85 137.025)
		(width 0.16)
		(layer "F.Cu")
		(net 367)
	)
	(segment
		(start 122 149.1)
		(end 122 148.835)
		(width 0.16)
		(layer "F.Cu")
		(net 367)
	)
	(segment
		(start 122 148.835)
		(end 122.0995 148.7355)
		(width 0.16)
		(layer "F.Cu")
		(net 367)
	)
	(segment
		(start 122.099499 148.699999)
		(end 122.099499 148.549999)
		(width 0.16)
		(layer "F.Cu")
		(net 367)
	)
	(segment
		(start 122.0995 148.7)
		(end 122.099499 148.699999)
		(width 0.16)
		(layer "F.Cu")
		(net 367)
	)
	(segment
		(start 130.35 137.175)
		(end 130.5 137.025)
		(width 0.16)
		(layer "F.Cu")
		(net 367)
	)
	(segment
		(start 131.875 137)
		(end 131.85 137.025)
		(width 0.1)
		(layer "F.Cu")
		(net 367)
	)
	(segment
		(start 132.5 137)
		(end 131.875 137)
		(width 0.1)
		(layer "F.Cu")
		(net 367)
	)
	(segment
		(start 122.0995 148.7355)
		(end 122.0995 148.7)
		(width 0.16)
		(layer "F.Cu")
		(net 367)
	)
	(segment
		(start 122.099499 148.549999)
		(end 121.9495 148.4)
		(width 0.16)
		(layer "F.Cu")
		(net 367)
	)
	(via
		(at 130.35 137.175)
		(size 0.45)
		(drill 0.2)
		(layers "F.Cu" "B.Cu")
		(remove_unused_layers yes)
		(keep_end_layers yes)
		(zone_layer_connections)
		(net 367)
	)
	(via
		(at 121.9495 148.4)
		(size 0.45)
		(drill 0.2)
		(layers "F.Cu" "B.Cu")
		(remove_unused_layers yes)
		(keep_end_layers yes)
		(zone_layer_connections)
		(net 367)
	)
	(segment
		(start 124.6 147.212132)
		(end 124.6 142.112132)
		(width 0.16)
		(layer "In5.Cu")
		(net 367)
	)
	(segment
		(start 122.0995 148.55)
		(end 122.0995 148.911632)
		(width 0.16)
		(layer "In5.Cu")
		(net 367)
	)
	(segment
		(start 121.9495 148.4)
		(end 122.0995 148.55)
		(width 0.16)
		(layer "In5.Cu")
		(net 367)
	)
	(segment
		(start 123.95 148.462132)
		(end 123.95 147.862132)
		(width 0.16)
		(layer "In5.Cu")
		(net 367)
	)
	(segment
		(start 122.537868 149.35)
		(end 123.062132 149.35)
		(width 0.16)
		(layer "In5.Cu")
		(net 367)
	)
	(segment
		(start 130.200001 137.025001)
		(end 130.35 137.175)
		(width 0.16)
		(layer "In5.Cu")
		(net 367)
	)
	(segment
		(start 129.687131 137.025001)
		(end 130.200001 137.025001)
		(width 0.16)
		(layer "In5.Cu")
		(net 367)
	)
	(segment
		(start 123.95 147.862132)
		(end 124.6 147.212132)
		(width 0.16)
		(layer "In5.Cu")
		(net 367)
	)
	(segment
		(start 122.0995 148.911632)
		(end 122.537868 149.35)
		(width 0.16)
		(layer "In5.Cu")
		(net 367)
	)
	(segment
		(start 123.062132 149.35)
		(end 123.95 148.462132)
		(width 0.16)
		(layer "In5.Cu")
		(net 367)
	)
	(segment
		(start 124.6 142.112132)
		(end 129.687131 137.025001)
		(width 0.16)
		(layer "In5.Cu")
		(net 367)
	)
	(segment
		(start 130.512131 135.499999)
		(end 131.162132 136.15)
		(width 0.16)
		(layer "F.Cu")
		(net 368)
	)
	(segment
		(start 122.25 147.498)
		(end 122.349499 147.398501)
		(width 0.16)
		(layer "F.Cu")
		(net 368)
	)
	(segment
		(start 122.349499 147.398501)
		(end 122.349499 146.949999)
		(width 0.16)
		(layer "F.Cu")
		(net 368)
	)
	(segment
		(start 122.349499 146.949999)
		(end 122.1995 146.8)
		(width 0.16)
		(layer "F.Cu")
		(net 368)
	)
	(segment
		(start 132.59883 136.265)
		(end 132.04 136.265)
		(width 0.1)
		(layer "F.Cu")
		(net 368)
	)
	(segment
		(start 131.162132 136.15)
		(end 131.6 136.15)
		(width 0.16)
		(layer "F.Cu")
		(net 368)
	)
	(segment
		(start 132.04 136.265)
		(end 131.975 136.2)
		(width 0.1)
		(layer "F.Cu")
		(net 368)
	)
	(segment
		(start 131.65 136.2)
		(end 131.6 136.15)
		(width 0.1)
		(layer "F.Cu")
		(net 368)
	)
	(segment
		(start 129.199999 135.499999)
		(end 130.512131 135.499999)
		(width 0.16)
		(layer "F.Cu")
		(net 368)
	)
	(segment
		(start 131.975 136.2)
		(end 131.65 136.2)
		(width 0.1)
		(layer "F.Cu")
		(net 368)
	)
	(segment
		(start 129.05 135.35)
		(end 129.199999 135.499999)
		(width 0.16)
		(layer "F.Cu")
		(net 368)
	)
	(segment
		(start 133 136.5)
		(end 132.8825 136.3825)
		(width 0.1)
		(layer "F.Cu")
		(net 368)
	)
	(via
		(at 122.1995 146.8)
		(size 0.45)
		(drill 0.2)
		(layers "F.Cu" "B.Cu")
		(remove_unused_layers yes)
		(keep_end_layers yes)
		(zone_layer_connections)
		(net 368)
	)
	(via
		(at 129.05 135.35)
		(size 0.45)
		(drill 0.2)
		(layers "F.Cu" "B.Cu")
		(remove_unused_layers yes)
		(keep_end_layers yes)
		(zone_layer_connections)
		(net 368)
	)
	(arc
		(start 132.8825 136.3825)
		(mid 132.752352 136.295537)
		(end 132.59883 136.265)
		(width 0.1)
		(layer "F.Cu")
		(net 368)
	)
	(segment
		(start 122.1995 146.8)
		(end 122.349499 146.650001)
		(width 0.16)
		(layer "In5.Cu")
		(net 368)
	)
	(segment
		(start 128.900001 135.499999)
		(end 129.05 135.35)
		(width 0.16)
		(layer "In5.Cu")
		(net 368)
	)
	(segment
		(start 128.287869 135.499999)
		(end 128.900001 135.499999)
		(width 0.16)
		(layer "In5.Cu")
		(net 368)
	)
	(segment
		(start 122.349499 146.650001)
		(end 122.349499 141.438369)
		(width 0.16)
		(layer "In5.Cu")
		(net 368)
	)
	(segment
		(start 122.349499 141.438369)
		(end 128.287869 135.499999)
		(width 0.16)
		(layer "In5.Cu")
		(net 368)
	)
	(segment
		(start 132.765 137.265)
		(end 133 137.5)
		(width 0.1)
		(layer "F.Cu")
		(net 369)
	)
	(segment
		(start 123.249 146.451)
		(end 123.25 146.45)
		(width 0.1)
		(layer "F.Cu")
		(net 369)
	)
	(segment
		(start 131.480289 137.66938)
		(end 131.884669 137.265)
		(width 0.1)
		(layer "F.Cu")
		(net 369)
	)
	(segment
		(start 131.884669 137.265)
		(end 132.765 137.265)
		(width 0.1)
		(layer "F.Cu")
		(net 369)
	)
	(segment
		(start 131.4 137.7)
		(end 131.43062 137.66938)
		(width 0.1)
		(layer "F.Cu")
		(net 369)
	)
	(segment
		(start 123.249 147.498)
		(end 123.249 146.451)
		(width 0.1)
		(layer "F.Cu")
		(net 369)
	)
	(segment
		(start 131.43062 137.66938)
		(end 131.480289 137.66938)
		(width 0.1)
		(layer "F.Cu")
		(net 369)
	)
	(via
		(at 131.4 137.7)
		(size 0.45)
		(drill 0.2)
		(layers "F.Cu" "B.Cu")
		(remove_unused_layers yes)
		(keep_end_layers yes)
		(zone_layer_connections)
		(net 369)
	)
	(via
		(at 123.25 146.45)
		(size 0.45)
		(drill 0.2)
		(layers "F.Cu" "B.Cu")
		(remove_unused_layers yes)
		(keep_end_layers yes)
		(zone_layer_connections)
		(net 369)
	)
	(segment
		(start 130.382843 138.917159)
		(end 131.582841 138.917159)
		(width 0.1)
		(layer "In3.Cu")
		(net 369)
	)
	(segment
		(start 124.5 145.8)
		(end 124.6 145.9)
		(width 0.1)
		(layer "In3.Cu")
		(net 369)
	)
	(segment
		(start 131.582841 138.917159)
		(end 131.8 138.7)
		(width 0.1)
		(layer "In3.Cu")
		(net 369)
	)
	(segment
		(start 123.25 146.05)
		(end 123.5 145.8)
		(width 0.1)
		(layer "In3.Cu")
		(net 369)
	)
	(segment
		(start 129.317158 140.782842)
		(end 129.317158 139.982844)
		(width 0.1)
		(layer "In3.Cu")
		(net 369)
	)
	(segment
		(start 123.25 146.45)
		(end 123.25 146.05)
		(width 0.1)
		(layer "In3.Cu")
		(net 369)
	)
	(segment
		(start 123.5 145.8)
		(end 124.5 145.8)
		(width 0.1)
		(layer "In3.Cu")
		(net 369)
	)
	(segment
		(start 127.2 142.9)
		(end 129.317158 140.782842)
		(width 0.1)
		(layer "In3.Cu")
		(net 369)
	)
	(segment
		(start 131.8 138.1)
		(end 131.4 137.7)
		(width 0.1)
		(layer "In3.Cu")
		(net 369)
	)
	(segment
		(start 129.317158 139.982844)
		(end 130.382843 138.917159)
		(width 0.1)
		(layer "In3.Cu")
		(net 369)
	)
	(segment
		(start 131.8 138.7)
		(end 131.8 138.1)
		(width 0.1)
		(layer "In3.Cu")
		(net 369)
	)
	(segment
		(start 127.2 144.2)
		(end 127.2 142.9)
		(width 0.1)
		(layer "In3.Cu")
		(net 369)
	)
	(segment
		(start 124.6 145.9)
		(end 125.5 145.9)
		(width 0.1)
		(layer "In3.Cu")
		(net 369)
	)
	(segment
		(start 125.5 145.9)
		(end 127.2 144.2)
		(width 0.1)
		(layer "In3.Cu")
		(net 369)
	)
	(segment
		(start 147.165 116.915)
		(end 147.2 116.88)
		(width 0.1)
		(layer "F.Cu")
		(net 370)
	)
	(segment
		(start 147.165 118.6)
		(end 147.165 116.915)
		(width 0.1)
		(layer "F.Cu")
		(net 370)
	)
	(segment
		(start 134.9 125.6)
		(end 134.9 123.55)
		(width 0.1)
		(layer "F.Cu")
		(net 371)
	)
	(segment
		(start 133.1 126.71)
		(end 133.3311 126.4789)
		(width 0.1)
		(layer "F.Cu")
		(net 371)
	)
	(segment
		(start 134.0211 126.4789)
		(end 134.9 125.6)
		(width 0.1)
		(layer "F.Cu")
		(net 371)
	)
	(segment
		(start 135.4 123.05)
		(end 135.4 122.35)
		(width 0.1)
		(layer "F.Cu")
		(net 371)
	)
	(segment
		(start 135.575 122.175)
		(end 135.575 121.575)
		(width 0.1)
		(layer "F.Cu")
		(net 371)
	)
	(segment
		(start 135.4 122.35)
		(end 135.575 122.175)
		(width 0.1)
		(layer "F.Cu")
		(net 371)
	)
	(segment
		(start 133.3311 126.4789)
		(end 134.0211 126.4789)
		(width 0.1)
		(layer "F.Cu")
		(net 371)
	)
	(segment
		(start 134.9 123.55)
		(end 135.4 123.05)
		(width 0.1)
		(layer "F.Cu")
		(net 371)
	)
	(segment
		(start 135.575 121.575)
		(end 136 121.15)
		(width 0.1)
		(layer "F.Cu")
		(net 371)
	)
	(via
		(at 136 121.15)
		(size 0.45)
		(drill 0.2)
		(layers "F.Cu" "B.Cu")
		(remove_unused_layers yes)
		(keep_end_layers yes)
		(zone_layer_connections)
		(net 371)
	)
	(via
		(at 140 71.2)
		(size 0.45)
		(drill 0.2)
		(layers "F.Cu" "B.Cu")
		(remove_unused_layers yes)
		(keep_end_layers yes)
		(zone_layer_connections)
		(net 371)
	)
	(via
		(at 149.7 71.75)
		(size 0.45)
		(drill 0.2)
		(layers "F.Cu" "B.Cu")
		(remove_unused_layers yes)
		(keep_end_layers yes)
		(zone_layer_connections)
		(net 371)
	)
	(segment
		(start 137.2 102.8)
		(end 139.35 102.8)
		(width 0.1)
		(layer "B.Cu")
		(net 371)
	)
	(segment
		(start 140.6 99)
		(end 142.2 97.4)
		(width 0.1)
		(layer "B.Cu")
		(net 371)
	)
	(segment
		(start 140.6 71.8)
		(end 140 71.2)
		(width 0.1)
		(layer "B.Cu")
		(net 371)
	)
	(segment
		(start 135.4 113.4)
		(end 134 112)
		(width 0.1)
		(layer "B.Cu")
		(net 371)
	)
	(segment
		(start 135.4 120.53)
		(end 135.4 113.4)
		(width 0.1)
		(layer "B.Cu")
		(net 371)
	)
	(segment
		(start 140.6 92.6)
		(end 140.6 71.8)
		(width 0.1)
		(layer "B.Cu")
		(net 371)
	)
	(segment
		(start 134 106)
		(end 137.2 102.8)
		(width 0.1)
		(layer "B.Cu")
		(net 371)
	)
	(segment
		(start 142.2 97.4)
		(end 142.2 94.2)
		(width 0.1)
		(layer "B.Cu")
		(net 371)
	)
	(segment
		(start 134 112)
		(end 134 106)
		(width 0.1)
		(layer "B.Cu")
		(net 371)
	)
	(segment
		(start 139.35 102.8)
		(end 140.6 101.55)
		(width 0.1)
		(layer "B.Cu")
		(net 371)
	)
	(segment
		(start 136.02 121.15)
		(end 135.4 120.53)
		(width 0.1)
		(layer "B.Cu")
		(net 371)
	)
	(segment
		(start 142.2 94.2)
		(end 140.6 92.6)
		(width 0.1)
		(layer "B.Cu")
		(net 371)
	)
	(segment
		(start 140.6 101.55)
		(end 140.6 99)
		(width 0.1)
		(layer "B.Cu")
		(net 371)
	)
	(segment
		(start 149.7 71.3)
		(end 148.8 70.4)
		(width 0.1)
		(layer "In3.Cu")
		(net 371)
	)
	(segment
		(start 140.8 70.4)
		(end 140 71.2)
		(width 0.1)
		(layer "In3.Cu")
		(net 371)
	)
	(segment
		(start 148.8 70.4)
		(end 140.8 70.4)
		(width 0.1)
		(layer "In3.Cu")
		(net 371)
	)
	(segment
		(start 149.7 71.75)
		(end 149.7 71.3)
		(width 0.1)
		(layer "In3.Cu")
		(net 371)
	)
	(segment
		(start 139.017158 133.1)
		(end 139.517158 133.6)
		(width 0.1)
		(layer "F.Cu")
		(net 372)
	)
	(segment
		(start 139.517158 133.6)
		(end 140.35 133.6)
		(width 0.1)
		(layer "F.Cu")
		(net 372)
	)
	(segment
		(start 136.5 134)
		(end 136.5 133.3)
		(width 0.1)
		(layer "F.Cu")
		(net 372)
	)
	(segment
		(start 136.7 133.1)
		(end 139.017158 133.1)
		(width 0.1)
		(layer "F.Cu")
		(net 372)
	)
	(segment
		(start 136.5 133.3)
		(end 136.7 133.1)
		(width 0.1)
		(layer "F.Cu")
		(net 372)
	)
	(via
		(at 132.625 125.25)
		(size 0.45)
		(drill 0.2)
		(layers "F.Cu" "B.Cu")
		(remove_unused_layers yes)
		(keep_end_layers yes)
		(zone_layer_connections)
		(net 372)
	)
	(via
		(at 140.35 133.6)
		(size 0.45)
		(drill 0.2)
		(layers "F.Cu" "B.Cu")
		(remove_unused_layers yes)
		(keep_end_layers yes)
		(zone_layer_connections)
		(net 372)
	)
	(segment
		(start 139.68 133.6)
		(end 139.679999 133.600001)
		(width 0.1)
		(layer "B.Cu")
		(net 372)
	)
	(segment
		(start 140.35 133.6)
		(end 139.68 133.6)
		(width 0.1)
		(layer "B.Cu")
		(net 372)
	)
	(segment
		(start 135.373223 125.901777)
		(end 133.951777 125.901777)
		(width 0.1)
		(layer "In3.Cu")
		(net 372)
	)
	(segment
		(start 135.971446 126.5)
		(end 135.373223 125.901777)
		(width 0.1)
		(layer "In3.Cu")
		(net 372)
	)
	(segment
		(start 140.5 129.55)
		(end 140.35 129.4)
		(width 0.1)
		(layer "In3.Cu")
		(net 372)
	)
	(segment
		(start 138.721446 126.5)
		(end 135.971446 126.5)
		(width 0.1)
		(layer "In3.Cu")
		(net 372)
	)
	(segment
		(start 140.35 132.55)
		(end 140.5 132.4)
		(width 0.1)
		(layer "In3.Cu")
		(net 372)
	)
	(segment
		(start 140.5 132.4)
		(end 140.5 129.55)
		(width 0.1)
		(layer "In3.Cu")
		(net 372)
	)
	(segment
		(start 140.35 133.6)
		(end 140.35 132.55)
		(width 0.1)
		(layer "In3.Cu")
		(net 372)
	)
	(segment
		(start 133.951777 125.901777)
		(end 133.3 125.25)
		(width 0.1)
		(layer "In3.Cu")
		(net 372)
	)
	(segment
		(start 140.35 129.4)
		(end 140.35 128.128554)
		(width 0.1)
		(layer "In3.Cu")
		(net 372)
	)
	(segment
		(start 140.35 128.128554)
		(end 138.721446 126.5)
		(width 0.1)
		(layer "In3.Cu")
		(net 372)
	)
	(segment
		(start 133.3 125.25)
		(end 132.625 125.25)
		(width 0.1)
		(layer "In3.Cu")
		(net 372)
	)
	(segment
		(start 133.3289 121.4211)
		(end 133.1 121.65)
		(width 0.1)
		(layer "F.Cu")
		(net 373)
	)
	(segment
		(start 136.25 134.25)
		(end 136.25 133.25)
		(width 0.1)
		(layer "F.Cu")
		(net 373)
	)
	(segment
		(start 134.775 121.35)
		(end 134.35 121.35)
		(width 0.1)
		(layer "F.Cu")
		(net 373)
	)
	(segment
		(start 136.25 133.25)
		(end 136.6 132.9)
		(width 0.1)
		(layer "F.Cu")
		(net 373)
	)
	(segment
		(start 140.45 132.9)
		(end 140.85 133.3)
		(width 0.1)
		(layer "F.Cu")
		(net 373)
	)
	(segment
		(start 134.35 121.35)
		(end 134.2789 121.4211)
		(width 0.1)
		(layer "F.Cu")
		(net 373)
	)
	(segment
		(start 136.6 132.9)
		(end 140.45 132.9)
		(width 0.1)
		(layer "F.Cu")
		(net 373)
	)
	(segment
		(start 136 134.5)
		(end 136.25 134.25)
		(width 0.1)
		(layer "F.Cu")
		(net 373)
	)
	(segment
		(start 134.2789 121.4211)
		(end 133.3289 121.4211)
		(width 0.1)
		(layer "F.Cu")
		(net 373)
	)
	(via
		(at 134.775 121.35)
		(size 0.45)
		(drill 0.2)
		(layers "F.Cu" "B.Cu")
		(remove_unused_layers yes)
		(keep_end_layers yes)
		(zone_layer_connections)
		(net 373)
	)
	(via
		(at 140.85 133.3)
		(size 0.45)
		(drill 0.2)
		(layers "F.Cu" "B.Cu")
		(remove_unused_layers yes)
		(keep_end_layers yes)
		(zone_layer_connections)
		(net 373)
	)
	(segment
		(start 139.679998 132.600001)
		(end 140.150001 132.600001)
		(width 0.1)
		(layer "B.Cu")
		(net 373)
	)
	(segment
		(start 140.150001 132.600001)
		(end 140.85 133.3)
		(width 0.1)
		(layer "B.Cu")
		(net 373)
	)
	(segment
		(start 138.825 126.25)
		(end 136.075 126.25)
		(width 0.1)
		(layer "In3.Cu")
		(net 373)
	)
	(segment
		(start 133.45 122.225)
		(end 133.45 121.725)
		(width 0.1)
		(layer "In3.Cu")
		(net 373)
	)
	(segment
		(start 133.825 121.35)
		(end 134.775 121.35)
		(width 0.1)
		(layer "In3.Cu")
		(net 373)
	)
	(segment
		(start 140.6 128.025)
		(end 138.825 126.25)
		(width 0.1)
		(layer "In3.Cu")
		(net 373)
	)
	(segment
		(start 134.25 123.025)
		(end 133.45 122.225)
		(width 0.1)
		(layer "In3.Cu")
		(net 373)
	)
	(segment
		(start 136.075 126.25)
		(end 134.25 124.425)
		(width 0.1)
		(layer "In3.Cu")
		(net 373)
	)
	(segment
		(start 134.25 124.425)
		(end 134.25 123.025)
		(width 0.1)
		(layer "In3.Cu")
		(net 373)
	)
	(segment
		(start 140.6 129.3)
		(end 140.6 128.025)
		(width 0.1)
		(layer "In3.Cu")
		(net 373)
	)
	(segment
		(start 140.8 133.25)
		(end 140.8 129.5)
		(width 0.1)
		(layer "In3.Cu")
		(net 373)
	)
	(segment
		(start 133.45 121.725)
		(end 133.825 121.35)
		(width 0.1)
		(layer "In3.Cu")
		(net 373)
	)
	(segment
		(start 140.85 133.3)
		(end 140.8 133.25)
		(width 0.1)
		(layer "In3.Cu")
		(net 373)
	)
	(segment
		(start 140.8 129.5)
		(end 140.6 129.3)
		(width 0.1)
		(layer "In3.Cu")
		(net 373)
	)
	(segment
		(start 140.88 139.55)
		(end 140.88 138.55)
		(width 0.1)
		(layer "F.Cu")
		(net 374)
	)
	(segment
		(start 141.65 138.55)
		(end 141.7 138.5)
		(width 0.1)
		(layer "F.Cu")
		(net 374)
	)
	(segment
		(start 140.88 138.55)
		(end 141.65 138.55)
		(width 0.1)
		(layer "F.Cu")
		(net 374)
	)
	(via
		(at 141.7 138.5)
		(size 0.45)
		(drill 0.2)
		(layers "F.Cu" "B.Cu")
		(remove_unused_layers yes)
		(keep_end_layers yes)
		(zone_layer_connections)
		(net 374)
	)
	(via
		(at 132.625 123.95)
		(size 0.45)
		(drill 0.2)
		(layers "F.Cu" "B.Cu")
		(remove_unused_layers yes)
		(keep_end_layers yes)
		(zone_layer_connections)
		(net 374)
	)
	(segment
		(start 133.5 133.1)
		(end 134.4 132.2)
		(width 0.1)
		(layer "In5.Cu")
		(net 374)
	)
	(segment
		(start 131.7 132.9)
		(end 131.9 133.1)
		(width 0.1)
		(layer "In5.Cu")
		(net 374)
	)
	(segment
		(start 131.7 131.9)
		(end 131.7 132.9)
		(width 0.1)
		(layer "In5.Cu")
		(net 374)
	)
	(segment
		(start 132.625 123.95)
		(end 133.4 124.725)
		(width 0.1)
		(layer "In5.Cu")
		(net 374)
	)
	(segment
		(start 138.5 132.7)
		(end 141.7 135.9)
		(width 0.1)
		(layer "In5.Cu")
		(net 374)
	)
	(segment
		(start 137.1 132.2)
		(end 137.6 132.7)
		(width 0.1)
		(layer "In5.Cu")
		(net 374)
	)
	(segment
		(start 133.4 124.725)
		(end 133.4 128)
		(width 0.1)
		(layer "In5.Cu")
		(net 374)
	)
	(segment
		(start 131.6 131.8)
		(end 131.7 131.9)
		(width 0.1)
		(layer "In5.Cu")
		(net 374)
	)
	(segment
		(start 137.6 132.7)
		(end 138.5 132.7)
		(width 0.1)
		(layer "In5.Cu")
		(net 374)
	)
	(segment
		(start 131.9 133.1)
		(end 133.5 133.1)
		(width 0.1)
		(layer "In5.Cu")
		(net 374)
	)
	(segment
		(start 141.7 135.9)
		(end 141.7 138.5)
		(width 0.1)
		(layer "In5.Cu")
		(net 374)
	)
	(segment
		(start 133.4 128)
		(end 131.6 129.8)
		(width 0.1)
		(layer "In5.Cu")
		(net 374)
	)
	(segment
		(start 134.4 132.2)
		(end 137.1 132.2)
		(width 0.1)
		(layer "In5.Cu")
		(net 374)
	)
	(segment
		(start 131.6 129.8)
		(end 131.6 131.8)
		(width 0.1)
		(layer "In5.Cu")
		(net 374)
	)
	(segment
		(start 133.56 121.65)
		(end 134.45 121.65)
		(width 0.1)
		(layer "F.Cu")
		(net 375)
	)
	(segment
		(start 136 133.2)
		(end 136 134)
		(width 0.1)
		(layer "F.Cu")
		(net 375)
	)
	(segment
		(start 136.5 132.7)
		(end 136 133.2)
		(width 0.1)
		(layer "F.Cu")
		(net 375)
	)
	(segment
		(start 134.45 121.65)
		(end 134.7 121.9)
		(width 0.1)
		(layer "F.Cu")
		(net 375)
	)
	(segment
		(start 141.2 132.7)
		(end 136.5 132.7)
		(width 0.1)
		(layer "F.Cu")
		(net 375)
	)
	(via
		(at 141.2 132.7)
		(size 0.45)
		(drill 0.2)
		(layers "F.Cu" "B.Cu")
		(remove_unused_layers yes)
		(keep_end_layers yes)
		(zone_layer_connections)
		(net 375)
	)
	(via
		(at 134.7 121.9)
		(size 0.45)
		(drill 0.2)
		(layers "F.Cu" "B.Cu")
		(remove_unused_layers yes)
		(keep_end_layers yes)
		(zone_layer_connections)
		(net 375)
	)
	(segment
		(start 141.2 132.7)
		(end 141 132.5)
		(width 0.1)
		(layer "B.Cu")
		(net 375)
	)
	(segment
		(start 140.55 131.6)
		(end 139.68 131.6)
		(width 0.1)
		(layer "B.Cu")
		(net 375)
	)
	(segment
		(start 141 132.05)
		(end 140.55 131.6)
		(width 0.1)
		(layer "B.Cu")
		(net 375)
	)
	(segment
		(start 141 132.5)
		(end 141 132.05)
		(width 0.1)
		(layer "B.Cu")
		(net 375)
	)
	(segment
		(start 138.938909 125.975001)
		(end 136.188909 125.975001)
		(width 0.1)
		(layer "In3.Cu")
		(net 375)
	)
	(segment
		(start 140.875 129.2)
		(end 140.875 127.911092)
		(width 0.1)
		(layer "In3.Cu")
		(net 375)
	)
	(segment
		(start 140.875 127.911092)
		(end 138.938909 125.975001)
		(width 0.1)
		(layer "In3.Cu")
		(net 375)
	)
	(segment
		(start 134.7 122.85)
		(end 134.7 121.9)
		(width 0.1)
		(layer "In3.Cu")
		(net 375)
	)
	(segment
		(start 141.2 129.525)
		(end 140.875 129.2)
		(width 0.1)
		(layer "In3.Cu")
		(net 375)
	)
	(segment
		(start 135.075 123.225)
		(end 134.7 122.85)
		(width 0.1)
		(layer "In3.Cu")
		(net 375)
	)
	(segment
		(start 135.075 124.861092)
		(end 135.075 123.225)
		(width 0.1)
		(layer "In3.Cu")
		(net 375)
	)
	(segment
		(start 141.2 132.7)
		(end 141.2 129.525)
		(width 0.1)
		(layer "In3.Cu")
		(net 375)
	)
	(segment
		(start 136.188909 125.975001)
		(end 135.075 124.861092)
		(width 0.1)
		(layer "In3.Cu")
		(net 375)
	)
	(segment
		(start 132.35 135.25)
		(end 132.75 135.25)
		(width 0.1)
		(layer "F.Cu")
		(net 376)
	)
	(segment
		(start 130.9 130.6)
		(end 132.18 129.32)
		(width 0.1)
		(layer "F.Cu")
		(net 376)
	)
	(segment
		(start 133 135.5)
		(end 132.75 135.25)
		(width 0.1)
		(layer "F.Cu")
		(net 376)
	)
	(segment
		(start 132.35 135.25)
		(end 132 134.9)
		(width 0.1)
		(layer "F.Cu")
		(net 376)
	)
	(segment
		(start 132.18 129.32)
		(end 132.18 129.01)
		(width 0.1)
		(layer "F.Cu")
		(net 376)
	)
	(via
		(at 132 134.9)
		(size 0.45)
		(drill 0.2)
		(layers "F.Cu" "B.Cu")
		(remove_unused_layers yes)
		(keep_end_layers yes)
		(zone_layer_connections)
		(net 376)
	)
	(via
		(at 130.9 130.6)
		(size 0.45)
		(drill 0.2)
		(layers "F.Cu" "B.Cu")
		(remove_unused_layers yes)
		(keep_end_layers yes)
		(zone_layer_connections)
		(net 376)
	)
	(segment
		(start 130.9 130.62)
		(end 130.9 130.6)
		(width 0.1)
		(layer "B.Cu")
		(net 376)
	)
	(segment
		(start 130.5 130.2)
		(end 130.9 130.6)
		(width 0.1)
		(layer "In3.Cu")
		(net 376)
	)
	(segment
		(start 129.7 130.2)
		(end 130.5 130.2)
		(width 0.1)
		(layer "In3.Cu")
		(net 376)
	)
	(segment
		(start 130.8 134.9)
		(end 129.4 133.5)
		(width 0.1)
		(layer "In3.Cu")
		(net 376)
	)
	(segment
		(start 129.4 133.5)
		(end 129.4 130.5)
		(width 0.1)
		(layer "In3.Cu")
		(net 376)
	)
	(segment
		(start 129.4 130.5)
		(end 129.7 130.2)
		(width 0.1)
		(layer "In3.Cu")
		(net 376)
	)
	(segment
		(start 132 134.9)
		(end 130.8 134.9)
		(width 0.1)
		(layer "In3.Cu")
		(net 376)
	)
	(segment
		(start 135 139)
		(end 135 139.65)
		(width 0.1)
		(layer "F.Cu")
		(net 377)
	)
	(segment
		(start 135 139.65)
		(end 135.75 140.4)
		(width 0.1)
		(layer "F.Cu")
		(net 377)
	)
	(via
		(at 132.625 126.55)
		(size 0.45)
		(drill 0.2)
		(layers "F.Cu" "B.Cu")
		(remove_unused_layers yes)
		(keep_end_layers yes)
		(zone_layer_connections)
		(net 377)
	)
	(via
		(at 135.75 140.4)
		(size 0.45)
		(drill 0.2)
		(layers "F.Cu" "B.Cu")
		(remove_unused_layers yes)
		(keep_end_layers yes)
		(zone_layer_connections)
		(net 377)
	)
	(segment
		(start 133 126.925)
		(end 133 130.4)
		(width 0.1)
		(layer "In3.Cu")
		(net 377)
	)
	(segment
		(start 133.4 133.4)
		(end 133.4 133.8)
		(width 0.1)
		(layer "In3.Cu")
		(net 377)
	)
	(segment
		(start 134.8 134.2)
		(end 135.2 134.6)
		(width 0.1)
		(layer "In3.Cu")
		(net 377)
	)
	(segment
		(start 135.5 137.75)
		(end 135.75 137.5)
		(width 0.1)
		(layer "In3.Cu")
		(net 377)
	)
	(segment
		(start 133.8 134.2)
		(end 134.8 134.2)
		(width 0.1)
		(layer "In3.Cu")
		(net 377)
	)
	(segment
		(start 135.5 140.15)
		(end 135.5 137.75)
		(width 0.1)
		(layer "In3.Cu")
		(net 377)
	)
	(segment
		(start 135.2 134.6)
		(end 135.2 135.45)
		(width 0.1)
		(layer "In3.Cu")
		(net 377)
	)
	(segment
		(start 135.2 135.45)
		(end 135.75 136)
		(width 0.1)
		(layer "In3.Cu")
		(net 377)
	)
	(segment
		(start 134.2 132.6)
		(end 133.4 133.4)
		(width 0.1)
		(layer "In3.Cu")
		(net 377)
	)
	(segment
		(start 135.75 140.4)
		(end 135.5 140.15)
		(width 0.1)
		(layer "In3.Cu")
		(net 377)
	)
	(segment
		(start 133 130.4)
		(end 134.2 131.6)
		(width 0.1)
		(layer "In3.Cu")
		(net 377)
	)
	(segment
		(start 134.2 131.6)
		(end 134.2 132.6)
		(width 0.1)
		(layer "In3.Cu")
		(net 377)
	)
	(segment
		(start 135.75 137.5)
		(end 135.75 136)
		(width 0.1)
		(layer "In3.Cu")
		(net 377)
	)
	(segment
		(start 132.625 126.55)
		(end 133 126.925)
		(width 0.1)
		(layer "In3.Cu")
		(net 377)
	)
	(segment
		(start 133.4 133.8)
		(end 133.8 134.2)
		(width 0.1)
		(layer "In3.Cu")
		(net 377)
	)
	(segment
		(start 135.1 95.2)
		(end 134.750002 95.549998)
		(width 0.1)
		(layer "F.Cu")
		(net 378)
	)
	(segment
		(start 133.4 111.4)
		(end 133.4 110.1)
		(width 0.1)
		(layer "F.Cu")
		(net 378)
	)
	(segment
		(start 134.750002 95.549998)
		(end 134.625001 95.549998)
		(width 0.1)
		(layer "F.Cu")
		(net 378)
	)
	(segment
		(start 135.15 113.15)
		(end 133.4 111.4)
		(width 0.1)
		(layer "F.Cu")
		(net 378)
	)
	(segment
		(start 135.67 113.15)
		(end 135.15 113.15)
		(width 0.1)
		(layer "F.Cu")
		(net 378)
	)
	(via
		(at 133.4 110.1)
		(size 0.45)
		(drill 0.2)
		(layers "F.Cu" "B.Cu")
		(remove_unused_layers yes)
		(keep_end_layers yes)
		(zone_layer_connections)
		(net 378)
	)
	(via
		(at 135.1 95.2)
		(size 0.45)
		(drill 0.2)
		(layers "F.Cu" "B.Cu")
		(remove_unused_layers yes)
		(keep_end_layers yes)
		(zone_layer_connections)
		(net 378)
	)
	(via
		(at 136.8 98.2)
		(size 0.45)
		(drill 0.2)
		(layers "F.Cu" "B.Cu")
		(remove_unused_layers yes)
		(keep_end_layers yes)
		(zone_layer_connections)
		(net 378)
	)
	(segment
		(start 135.7 98.8)
		(end 136.3 98.2)
		(width 0.1)
		(layer "B.Cu")
		(net 378)
	)
	(segment
		(start 135.1 95.2)
		(end 135.1 93.98)
		(width 0.1)
		(layer "B.Cu")
		(net 378)
	)
	(segment
		(start 135.7 102.2)
		(end 135.7 98.8)
		(width 0.1)
		(layer "B.Cu")
		(net 378)
	)
	(segment
		(start 136.3 98.2)
		(end 136.8 98.2)
		(width 0.1)
		(layer "B.Cu")
		(net 378)
	)
	(segment
		(start 133.4 110.1)
		(end 133.4 104.5)
		(width 0.1)
		(layer "B.Cu")
		(net 378)
	)
	(segment
		(start 135.1 93.98)
		(end 135 93.88)
		(width 0.1)
		(layer "B.Cu")
		(net 378)
	)
	(segment
		(start 133.4 104.5)
		(end 135.7 102.2)
		(width 0.1)
		(layer "B.Cu")
		(net 378)
	)
	(segment
		(start 136.8 96.9)
		(end 135.1 95.2)
		(width 0.1)
		(layer "In3.Cu")
		(net 378)
	)
	(segment
		(start 136.8 98.2)
		(end 136.8 96.9)
		(width 0.1)
		(layer "In3.Cu")
		(net 378)
	)
	(segment
		(start 136.4 107.92)
		(end 136.4 107.5)
		(width 0.1)
		(layer "F.Cu")
		(net 379)
	)
	(segment
		(start 137.200001 108.299999)
		(end 137.200001 109.099997)
		(width 0.15)
		(layer "F.Cu")
		(net 379)
	)
	(segment
		(start 151.070002 113.150002)
		(end 150.249998 113.150002)
		(width 0.1)
		(layer "F.Cu")
		(net 379)
	)
	(segment
		(start 138.799999 109.349998)
		(end 138.799999 109.474998)
		(width 0.15)
		(layer "F.Cu")
		(net 379)
	)
	(segment
		(start 136.63 108.149998)
		(end 137.049999 108.149998)
		(width 0.15)
		(layer "F.Cu")
		(net 379)
	)
	(segment
		(start 136.63 108.15)
		(end 136.4 107.92)
		(width 0.1)
		(layer "F.Cu")
		(net 379)
	)
	(segment
		(start 137.380002 109.279998)
		(end 138.730001 109.279999)
		(width 0.15)
		(layer "F.Cu")
		(net 379)
	)
	(segment
		(start 137.200001 109.099997)
		(end 137.380002 109.279998)
		(width 0.15)
		(layer "F.Cu")
		(net 379)
	)
	(segment
		(start 138.730001 109.279999)
		(end 138.799999 109.349998)
		(width 0.15)
		(layer "F.Cu")
		(net 379)
	)
	(segment
		(start 150.249998 113.150002)
		(end 150.2 113.2)
		(width 0.1)
		(layer "F.Cu")
		(net 379)
	)
	(segment
		(start 137.049999 108.149998)
		(end 137.200001 108.299999)
		(width 0.15)
		(layer "F.Cu")
		(net 379)
	)
	(via
		(at 136.4 107.5)
		(size 0.45)
		(drill 0.2)
		(layers "F.Cu" "B.Cu")
		(remove_unused_layers yes)
		(keep_end_layers yes)
		(zone_layer_connections)
		(net 379)
	)
	(via
		(at 150.2 113.2)
		(size 0.45)
		(drill 0.2)
		(layers "F.Cu" "B.Cu")
		(remove_unused_layers yes)
		(keep_end_layers yes)
		(zone_layer_connections)
		(net 379)
	)
	(segment
		(start 139 107.5)
		(end 144.7 113.2)
		(width 0.1)
		(layer "B.Cu")
		(net 379)
	)
	(segment
		(start 136.4 107.5)
		(end 139 107.5)
		(width 0.1)
		(layer "B.Cu")
		(net 379)
	)
	(segment
		(start 144.7 113.2)
		(end 150.2 113.2)
		(width 0.1)
		(layer "B.Cu")
		(net 379)
	)
	(segment
		(start 152.030002 108.15)
		(end 152.030002 107.519998)
		(width 0.1)
		(layer "F.Cu")
		(net 380)
	)
	(segment
		(start 158.05 113.15)
		(end 158.769999 113.15)
		(width 0.1)
		(layer "F.Cu")
		(net 380)
	)
	(segment
		(start 154.200001 109.349999)
		(end 154.200002 109.474999)
		(width 0.15)
		(layer "F.Cu")
		(net 380)
	)
	(segment
		(start 152.450001 108.149999)
		(end 152.600002 108.3)
		(width 0.15)
		(layer "F.Cu")
		(net 380)
	)
	(segment
		(start 152.030002 107.519998)
		(end 152.05 107.5)
		(width 0.1)
		(layer "F.Cu")
		(net 380)
	)
	(segment
		(start 152.030002 108.149999)
		(end 152.450001 108.149999)
		(width 0.15)
		(layer "F.Cu")
		(net 380)
	)
	(segment
		(start 152.600002 108.3)
		(end 152.600002 109.099998)
		(width 0.15)
		(layer "F.Cu")
		(net 380)
	)
	(segment
		(start 152.600002 109.099998)
		(end 152.780004 109.279999)
		(width 0.15)
		(layer "F.Cu")
		(net 380)
	)
	(segment
		(start 154.130003 109.279999)
		(end 154.200001 109.349999)
		(width 0.15)
		(layer "F.Cu")
		(net 380)
	)
	(segment
		(start 152.780004 109.279999)
		(end 154.130003 109.279999)
		(width 0.15)
		(layer "F.Cu")
		(net 380)
	)
	(via
		(at 158.05 113.15)
		(size 0.45)
		(drill 0.2)
		(layers "F.Cu" "B.Cu")
		(remove_unused_layers yes)
		(keep_end_layers yes)
		(zone_layer_connections)
		(net 380)
	)
	(via
		(at 152.05 107.5)
		(size 0.45)
		(drill 0.2)
		(layers "F.Cu" "B.Cu")
		(remove_unused_layers yes)
		(keep_end_layers yes)
		(zone_layer_connections)
		(net 380)
	)
	(segment
		(start 157.25 112.35)
		(end 158.05 113.15)
		(width 0.1)
		(layer "B.Cu")
		(net 380)
	)
	(segment
		(start 156.45 110.2)
		(end 157.25 111)
		(width 0.1)
		(layer "B.Cu")
		(net 380)
	)
	(segment
		(start 157.25 111)
		(end 157.25 112.35)
		(width 0.1)
		(layer "B.Cu")
		(net 380)
	)
	(segment
		(start 152.05 108.55)
		(end 153.7 110.2)
		(width 0.1)
		(layer "B.Cu")
		(net 380)
	)
	(segment
		(start 152.05 107.5)
		(end 152.05 108.55)
		(width 0.1)
		(layer "B.Cu")
		(net 380)
	)
	(segment
		(start 153.7 110.2)
		(end 156.45 110.2)
		(width 0.1)
		(layer "B.Cu")
		(net 380)
	)
	(segment
		(start 143.369999 113.150002)
		(end 143.319997 113.1)
		(width 0.1)
		(layer "F.Cu")
		(net 381)
	)
	(segment
		(start 159.75 107.5)
		(end 159.75 108.13)
		(width 0.1)
		(layer "F.Cu")
		(net 381)
	)
	(segment
		(start 160.299999 108.299999)
		(end 160.149998 108.149998)
		(width 0.15)
		(layer "F.Cu")
		(net 381)
	)
	(segment
		(start 161.899998 109.349997)
		(end 161.83 109.28)
		(width 0.15)
		(layer "F.Cu")
		(net 381)
	)
	(segment
		(start 160.299999 109.099997)
		(end 160.299999 108.299999)
		(width 0.15)
		(layer "F.Cu")
		(net 381)
	)
	(segment
		(start 160.480001 109.279997)
		(end 160.299999 109.099997)
		(width 0.15)
		(layer "F.Cu")
		(net 381)
	)
	(segment
		(start 161.83 109.28)
		(end 160.480001 109.279997)
		(width 0.15)
		(layer "F.Cu")
		(net 381)
	)
	(segment
		(start 143.319997 113.1)
		(end 142.5 113.1)
		(width 0.1)
		(layer "F.Cu")
		(net 381)
	)
	(segment
		(start 160.149998 108.149998)
		(end 159.729999 108.149998)
		(width 0.15)
		(layer "F.Cu")
		(net 381)
	)
	(segment
		(start 161.899998 109.474998)
		(end 161.899998 109.349997)
		(width 0.15)
		(layer "F.Cu")
		(net 381)
	)
	(segment
		(start 159.75 108.13)
		(end 159.73 108.15)
		(width 0.1)
		(layer "F.Cu")
		(net 381)
	)
	(via
		(at 159.75 107.5)
		(size 0.45)
		(drill 0.2)
		(layers "F.Cu" "B.Cu")
		(remove_unused_layers yes)
		(keep_end_layers yes)
		(zone_layer_connections)
		(net 381)
	)
	(via
		(at 142.5 113.1)
		(size 0.45)
		(drill 0.2)
		(layers "F.Cu" "B.Cu")
		(remove_unused_layers yes)
		(keep_end_layers yes)
		(zone_layer_connections)
		(net 381)
	)
	(segment
		(start 143.6 114.2)
		(end 149.2 114.2)
		(width 0.1)
		(layer "B.Cu")
		(net 381)
	)
	(segment
		(start 159.75 116.35)
		(end 159.75 107.5)
		(width 0.1)
		(layer "B.Cu")
		(net 381)
	)
	(segment
		(start 158.1 118)
		(end 159.75 116.35)
		(width 0.1)
		(layer "B.Cu")
		(net 381)
	)
	(segment
		(start 153 118)
		(end 158.1 118)
		(width 0.1)
		(layer "B.Cu")
		(net 381)
	)
	(segment
		(start 149.2 114.2)
		(end 153 118)
		(width 0.1)
		(layer "B.Cu")
		(net 381)
	)
	(segment
		(start 142.5 113.1)
		(end 143.6 114.2)
		(width 0.1)
		(layer "B.Cu")
		(net 381)
	)
	(segment
		(start 138.125001 110.649998)
		(end 137.7 110.649998)
		(width 0.15)
		(layer "F.Cu")
		(net 382)
	)
	(segment
		(start 137.299999 111.049999)
		(end 137.299999 112.849997)
		(width 0.15)
		(layer "F.Cu")
		(net 382)
	)
	(segment
		(start 137.7 110.649998)
		(end 137.299999 111.049999)
		(width 0.15)
		(layer "F.Cu")
		(net 382)
	)
	(segment
		(start 136.999998 113.149998)
		(end 136.63 113.149999)
		(width 0.15)
		(layer "F.Cu")
		(net 382)
	)
	(segment
		(start 137.299999 112.849997)
		(end 136.999998 113.149998)
		(width 0.15)
		(layer "F.Cu")
		(net 382)
	)
	(segment
		(start 131.72 129.18)
		(end 131.6 129.3)
		(width 0.1)
		(layer "F.Cu")
		(net 383)
	)
	(segment
		(start 130.5 129.4)
		(end 129.9 130)
		(width 0.1)
		(layer "F.Cu")
		(net 383)
	)
	(segment
		(start 131.72 129.01)
		(end 131.72 129.18)
		(width 0.1)
		(layer "F.Cu")
		(net 383)
	)
	(segment
		(start 131.5 134.930331)
		(end 132.069669 135.5)
		(width 0.1)
		(layer "F.Cu")
		(net 383)
	)
	(segment
		(start 131.5 129.3)
		(end 131.4 129.4)
		(width 0.1)
		(layer "F.Cu")
		(net 383)
	)
	(segment
		(start 131.6 129.3)
		(end 131.5 129.3)
		(width 0.1)
		(layer "F.Cu")
		(net 383)
	)
	(segment
		(start 131.5 134.2)
		(end 131.5 134.930331)
		(width 0.1)
		(layer "F.Cu")
		(net 383)
	)
	(segment
		(start 131.4 129.4)
		(end 130.5 129.4)
		(width 0.1)
		(layer "F.Cu")
		(net 383)
	)
	(segment
		(start 132.069669 135.5)
		(end 132.5 135.5)
		(width 0.1)
		(layer "F.Cu")
		(net 383)
	)
	(segment
		(start 129.9 130)
		(end 129.9 130.6)
		(width 0.1)
		(layer "F.Cu")
		(net 383)
	)
	(via
		(at 131.5 134.2)
		(size 0.45)
		(drill 0.2)
		(layers "F.Cu" "B.Cu")
		(remove_unused_layers yes)
		(keep_end_layers yes)
		(zone_layer_connections)
		(net 383)
	)
	(via
		(at 129.9 130.6)
		(size 0.45)
		(drill 0.2)
		(layers "F.Cu" "B.Cu")
		(remove_unused_layers yes)
		(keep_end_layers yes)
		(zone_layer_connections)
		(net 383)
	)
	(segment
		(start 129.9 130.62)
		(end 129.9 130.6)
		(width 0.1)
		(layer "B.Cu")
		(net 383)
	)
	(segment
		(start 130.3 131)
		(end 129.9 130.6)
		(width 0.1)
		(layer "In3.Cu")
		(net 383)
	)
	(segment
		(start 131.5 134.2)
		(end 130.8 134.2)
		(width 0.1)
		(layer "In3.Cu")
		(net 383)
	)
	(segment
		(start 130.8 134.2)
		(end 130.3 133.7)
		(width 0.1)
		(layer "In3.Cu")
		(net 383)
	)
	(segment
		(start 130.3 133.7)
		(end 130.3 131)
		(width 0.1)
		(layer "In3.Cu")
		(net 383)
	)
	(segment
		(start 152.7 111.05)
		(end 152.700001 112.85)
		(width 0.15)
		(layer "F.Cu")
		(net 384)
	)
	(segment
		(start 152.400001 113.15)
		(end 152.030002 113.15)
		(width 0.15)
		(layer "F.Cu")
		(net 384)
	)
	(segment
		(start 153.525002 110.649999)
		(end 153.100002 110.649999)
		(width 0.15)
		(layer "F.Cu")
		(net 384)
	)
	(segment
		(start 152.700001 112.85)
		(end 152.400001 113.15)
		(width 0.15)
		(layer "F.Cu")
		(net 384)
	)
	(segment
		(start 153.100002 110.649999)
		(end 152.7 111.05)
		(width 0.15)
		(layer "F.Cu")
		(net 384)
	)
	(segment
		(start 161.225 110.649998)
		(end 160.799999 110.649998)
		(width 0.15)
		(layer "F.Cu")
		(net 385)
	)
	(segment
		(start 160.399998 111.05)
		(end 160.399998 112.849999)
		(width 0.15)
		(layer "F.Cu")
		(net 385)
	)
	(segment
		(start 160.799999 110.649998)
		(end 160.399998 111.05)
		(width 0.15)
		(layer "F.Cu")
		(net 385)
	)
	(segment
		(start 160.399998 112.849999)
		(end 160.099998 113.149999)
		(width 0.15)
		(layer "F.Cu")
		(net 385)
	)
	(segment
		(start 160.099998 113.149999)
		(end 159.729999 113.149999)
		(width 0.15)
		(layer "F.Cu")
		(net 385)
	)
	(segment
		(start 144.999999 111.05)
		(end 144.999998 112.85)
		(width 0.15)
		(layer "F.Cu")
		(net 386)
	)
	(segment
		(start 144.699998 113.15)
		(end 144.330001 113.15)
		(width 0.15)
		(layer "F.Cu")
		(net 386)
	)
	(segment
		(start 145.4 110.649999)
		(end 144.999999 111.05)
		(width 0.15)
		(layer "F.Cu")
		(net 386)
	)
	(segment
		(start 144.999998 112.85)
		(end 144.699998 113.15)
		(width 0.15)
		(layer "F.Cu")
		(net 386)
	)
	(segment
		(start 145.825001 110.649999)
		(end 145.4 110.649999)
		(width 0.15)
		(layer "F.Cu")
		(net 386)
	)
	(segment
		(start 131.115 72.485)
		(end 131.4 72.2)
		(width 0.1)
		(layer "F.Cu")
		(net 387)
	)
	(segment
		(start 133.28 71.92)
		(end 133.28 71.4)
		(width 0.1)
		(layer "F.Cu")
		(net 387)
	)
	(segment
		(start 133 72.2)
		(end 133.28 71.92)
		(width 0.1)
		(layer "F.Cu")
		(net 387)
	)
	(segment
		(start 131.4 72.2)
		(end 133 72.2)
		(width 0.1)
		(layer "F.Cu")
		(net 387)
	)
	(segment
		(start 131.115 73.4)
		(end 131.115 72.485)
		(width 0.1)
		(layer "F.Cu")
		(net 387)
	)
	(segment
		(start 132.383 80.601)
		(end 132.383 82.303)
		(width 0.1)
		(layer "F.Cu")
		(net 388)
	)
	(segment
		(start 132.383 82.303)
		(end 132.4 82.32)
		(width 0.1)
		(layer "F.Cu")
		(net 388)
	)
	(segment
		(start 158 46.78)
		(end 159 46.78)
		(width 0.1)
		(layer "F.Cu")
		(net 389)
	)
	(segment
		(start 158.125 48.26)
		(end 158.125 47.625)
		(width 0.1)
		(layer "F.Cu")
		(net 389)
	)
	(segment
		(start 158 47.5)
		(end 158 46.78)
		(width 0.1)
		(layer "F.Cu")
		(net 389)
	)
	(segment
		(start 158.125 47.625)
		(end 158 47.5)
		(width 0.1)
		(layer "F.Cu")
		(net 389)
	)
	(segment
		(start 159.48 47.3)
		(end 160 46.78)
		(width 0.1)
		(layer "F.Cu")
		(net 390)
	)
	(segment
		(start 158.575 48.26)
		(end 158.575 47.525)
		(width 0.1)
		(layer "F.Cu")
		(net 390)
	)
	(segment
		(start 158.8 47.3)
		(end 159.48 47.3)
		(width 0.1)
		(layer "F.Cu")
		(net 390)
	)
	(segment
		(start 158.575 47.525)
		(end 158.8 47.3)
		(width 0.1)
		(layer "F.Cu")
		(net 390)
	)
	(segment
		(start 160.65 48.13)
		(end 162 46.78)
		(width 0.1)
		(layer "F.Cu")
		(net 391)
	)
	(segment
		(start 161 45.82)
		(end 161.04 45.82)
		(width 0.1)
		(layer "F.Cu")
		(net 391)
	)
	(segment
		(start 160.525 48.925)
		(end 160.65 48.8)
		(width 0.1)
		(layer "F.Cu")
		(net 391)
	)
	(segment
		(start 159.94 48.925)
		(end 160.525 48.925)
		(width 0.1)
		(layer "F.Cu")
		(net 391)
	)
	(segment
		(start 160.65 48.8)
		(end 160.65 48.13)
		(width 0.1)
		(layer "F.Cu")
		(net 391)
	)
	(segment
		(start 161.04 45.82)
		(end 162 46.78)
		(width 0.1)
		(layer "F.Cu")
		(net 391)
	)
	(segment
		(start 124.3 85.3)
		(end 125.6 84)
		(width 0.1)
		(layer "F.Cu")
		(net 392)
	)
	(segment
		(start 135 85.77)
		(end 134 85.77)
		(width 0.1)
		(layer "F.Cu")
		(net 392)
	)
	(segment
		(start 117.6 85.3)
		(end 124.3 85.3)
		(width 0.1)
		(layer "F.Cu")
		(net 392)
	)
	(segment
		(start 129.5 85.1)
		(end 132 85.1)
		(width 0.1)
		(layer "F.Cu")
		(net 392)
	)
	(segment
		(start 125.6 84)
		(end 128.4 84)
		(width 0.1)
		(layer "F.Cu")
		(net 392)
	)
	(segment
		(start 115.8 87.1)
		(end 117.6 85.3)
		(width 0.1)
		(layer "F.Cu")
		(net 392)
	)
	(segment
		(start 128.4 84)
		(end 129.5 85.1)
		(width 0.1)
		(layer "F.Cu")
		(net 392)
	)
	(segment
		(start 116.9 100.1)
		(end 116.9 91.8)
		(width 0.1)
		(layer "F.Cu")
		(net 392)
	)
	(segment
		(start 132 85.1)
		(end 132.675 85.775)
		(width 0.1)
		(layer "F.Cu")
		(net 392)
	)
	(segment
		(start 132.68 85.77)
		(end 132.675 85.775)
		(width 0.1)
		(layer "F.Cu")
		(net 392)
	)
	(segment
		(start 116.9 91.8)
		(end 115.8 90.7)
		(width 0.1)
		(layer "F.Cu")
		(net 392)
	)
	(segment
		(start 115.8 90.7)
		(end 115.8 87.1)
		(width 0.1)
		(layer "F.Cu")
		(net 392)
	)
	(segment
		(start 134 85.77)
		(end 132.68 85.77)
		(width 0.1)
		(layer "F.Cu")
		(net 392)
	)
	(via
		(at 148.835 71.25)
		(size 0.45)
		(drill 0.2)
		(layers "F.Cu" "B.Cu")
		(remove_unused_layers yes)
		(keep_end_layers yes)
		(zone_layer_connections)
		(net 392)
	)
	(via
		(at 131.7 115.4)
		(size 0.45)
		(drill 0.2)
		(layers "F.Cu" "B.Cu")
		(remove_unused_layers yes)
		(keep_end_layers yes)
		(zone_layer_connections)
		(net 392)
	)
	(via
		(at 132.675 85.775)
		(size 0.45)
		(drill 0.2)
		(layers "F.Cu" "B.Cu")
		(remove_unused_layers yes)
		(keep_end_layers yes)
		(zone_layer_connections)
		(net 392)
	)
	(via
		(at 132.625 124.6)
		(size 0.45)
		(drill 0.2)
		(layers "F.Cu" "B.Cu")
		(remove_unused_layers yes)
		(keep_end_layers yes)
		(zone_layer_connections)
		(net 392)
	)
	(via
		(at 116.9 100.1)
		(size 0.45)
		(drill 0.2)
		(layers "F.Cu" "B.Cu")
		(remove_unused_layers yes)
		(keep_end_layers yes)
		(zone_layer_connections)
		(net 392)
	)
	(segment
		(start 132.625 124.6)
		(end 133.6 124.6)
		(width 0.1)
		(layer "B.Cu")
		(net 392)
	)
	(segment
		(start 133.5 119.7)
		(end 131.9 118.1)
		(width 0.1)
		(layer "B.Cu")
		(net 392)
	)
	(segment
		(start 133.5 122.3)
		(end 133.5 119.7)
		(width 0.1)
		(layer "B.Cu")
		(net 392)
	)
	(segment
		(start 134 124.2)
		(end 134 122.8)
		(width 0.1)
		(layer "B.Cu")
		(net 392)
	)
	(segment
		(start 133.6 124.6)
		(end 134 124.2)
		(width 0.1)
		(layer "B.Cu")
		(net 392)
	)
	(segment
		(start 131.9 115.6)
		(end 131.7 115.4)
		(width 0.1)
		(layer "B.Cu")
		(net 392)
	)
	(segment
		(start 131.9 118.1)
		(end 131.9 115.6)
		(width 0.1)
		(layer "B.Cu")
		(net 392)
	)
	(segment
		(start 134 122.8)
		(end 133.5 122.3)
		(width 0.1)
		(layer "B.Cu")
		(net 392)
	)
	(segment
		(start 125.2 111.5)
		(end 129.9 111.5)
		(width 0.1)
		(layer "In3.Cu")
		(net 392)
	)
	(segment
		(start 116.9 100.1)
		(end 116.9 100.8)
		(width 0.1)
		(layer "In3.Cu")
		(net 392)
	)
	(segment
		(start 148.385 70.8)
		(end 148.835 71.25)
		(width 0.1)
		(layer "In3.Cu")
		(net 392)
	)
	(segment
		(start 124.025 77.775)
		(end 130 71.8)
		(width 0.1)
		(layer "In3.Cu")
		(net 392)
	)
	(segment
		(start 124.025 81.55)
		(end 124.025 77.775)
		(width 0.1)
		(layer "In3.Cu")
		(net 392)
	)
	(segment
		(start 122.5 106.4)
		(end 122.5 108.8)
		(width 0.1)
		(layer "In3.Cu")
		(net 392)
	)
	(segment
		(start 132.675 85.775)
		(end 129 82.1)
		(width 0.1)
		(layer "In3.Cu")
		(net 392)
	)
	(segment
		(start 122.5 108.8)
		(end 125.2 111.5)
		(width 0.1)
		(layer "In3.Cu")
		(net 392)
	)
	(segment
		(start 140.2 71.8)
		(end 141.2 70.8)
		(width 0.1)
		(layer "In3.Cu")
		(net 392)
	)
	(segment
		(start 130 71.8)
		(end 140.2 71.8)
		(width 0.1)
		(layer "In3.Cu")
		(net 392)
	)
	(segment
		(start 124.575 82.1)
		(end 124.025 81.55)
		(width 0.1)
		(layer "In3.Cu")
		(net 392)
	)
	(segment
		(start 131.2 114.9)
		(end 131.7 115.4)
		(width 0.1)
		(layer "In3.Cu")
		(net 392)
	)
	(segment
		(start 129.9 111.5)
		(end 131.2 112.8)
		(width 0.1)
		(layer "In3.Cu")
		(net 392)
	)
	(segment
		(start 141.2 70.8)
		(end 148.385 70.8)
		(width 0.1)
		(layer "In3.Cu")
		(net 392)
	)
	(segment
		(start 116.9 100.8)
		(end 122.5 106.4)
		(width 0.1)
		(layer "In3.Cu")
		(net 392)
	)
	(segment
		(start 129 82.1)
		(end 124.575 82.1)
		(width 0.1)
		(layer "In3.Cu")
		(net 392)
	)
	(segment
		(start 131.2 112.8)
		(end 131.2 114.9)
		(width 0.1)
		(layer "In3.Cu")
		(net 392)
	)
	(segment
		(start 124.175 95.425)
		(end 124.3 95.3)
		(width 0.19)
		(layer "F.Cu")
		(net 393)
	)
	(segment
		(start 138.219999 67.85)
		(end 135.897488 67.85)
		(width 0.19)
		(layer "F.Cu")
		(net 393)
	)
	(segment
		(start 126.975 101.6)
		(end 126.975 100.699999)
		(width 0.19)
		(layer "F.Cu")
		(net 393)
	)
	(segment
		(start 126.825 100.549999)
		(end 126.825 99.677512)
		(width 0.19)
		(layer "F.Cu")
		(net 393)
	)
	(segment
		(start 138.52 67.549999)
		(end 138.219999 67.85)
		(width 0.19)
		(layer "F.Cu")
		(net 393)
	)
	(segment
		(start 135.897488 67.85)
		(end 135.212132 67.164644)
		(width 0.19)
		(layer "F.Cu")
		(net 393)
	)
	(segment
		(start 126.975 100.699999)
		(end 126.825 100.549999)
		(width 0.19)
		(layer "F.Cu")
		(net 393)
	)
	(segment
		(start 126.825 99.677512)
		(end 124.175 97.027512)
		(width 0.19)
		(layer "F.Cu")
		(net 393)
	)
	(segment
		(start 124.175 97.027512)
		(end 124.175 95.425)
		(width 0.19)
		(layer "F.Cu")
		(net 393)
	)
	(segment
		(start 135.212132 67.164644)
		(end 135.212132 66.987868)
		(width 0.19)
		(layer "F.Cu")
		(net 393)
	)
	(via
		(at 124.3 95.3)
		(size 0.45)
		(drill 0.2)
		(layers "F.Cu" "B.Cu")
		(remove_unused_layers yes)
		(keep_end_layers yes)
		(zone_layer_connections)
		(net 393)
	)
	(via
		(at 135.212132 66.987868)
		(size 0.45)
		(drill 0.2)
		(layers "F.Cu" "B.Cu")
		(remove_unused_layers yes)
		(keep_end_layers yes)
		(zone_layer_connections)
		(net 393)
	)
	(segment
		(start 135.575 67.527512)
		(end 135.212132 67.164644)
		(width 0.19)
		(layer "B.Cu")
		(net 393)
	)
	(segment
		(start 123.675 91.572488)
		(end 124.175 91.072488)
		(width 0.19)
		(layer "B.Cu")
		(net 393)
	)
	(segment
		(start 124.175 93.427512)
		(end 123.675 92.927512)
		(width 0.19)
		(layer "B.Cu")
		(net 393)
	)
	(segment
		(start 125.472488 83.275)
		(end 127.672488 83.275)
		(width 0.19)
		(layer "B.Cu")
		(net 393)
	)
	(segment
		(start 123.675 92.927512)
		(end 123.675 91.572488)
		(width 0.19)
		(layer "B.Cu")
		(net 393)
	)
	(segment
		(start 129.175 75.072488)
		(end 135.575 68.672488)
		(width 0.19)
		(layer "B.Cu")
		(net 393)
	)
	(segment
		(start 135.575 68.672488)
		(end 135.575 67.527512)
		(width 0.19)
		(layer "B.Cu")
		(net 393)
	)
	(segment
		(start 124.175 91.072488)
		(end 124.175 84.572488)
		(width 0.19)
		(layer "B.Cu")
		(net 393)
	)
	(segment
		(start 129.175 81.772488)
		(end 129.175 75.072488)
		(width 0.19)
		(layer "B.Cu")
		(net 393)
	)
	(segment
		(start 127.672488 83.275)
		(end 129.175 81.772488)
		(width 0.19)
		(layer "B.Cu")
		(net 393)
	)
	(segment
		(start 124.175 84.572488)
		(end 125.472488 83.275)
		(width 0.19)
		(layer "B.Cu")
		(net 393)
	)
	(segment
		(start 135.212132 67.164644)
		(end 135.212132 66.987868)
		(width 0.19)
		(layer "B.Cu")
		(net 393)
	)
	(segment
		(start 124.3 95.3)
		(end 124.175 95.175)
		(width 0.19)
		(layer "B.Cu")
		(net 393)
	)
	(segment
		(start 124.175 95.175)
		(end 124.175 93.427512)
		(width 0.19)
		(layer "B.Cu")
		(net 393)
	)
	(segment
		(start 138.22 68.2)
		(end 135.752512 68.2)
		(width 0.19)
		(layer "F.Cu")
		(net 394)
	)
	(segment
		(start 134.964644 67.412132)
		(end 134.787868 67.412132)
		(width 0.19)
		(layer "F.Cu")
		(net 394)
	)
	(segment
		(start 126.475 100.549999)
		(end 126.475 99.822488)
		(width 0.19)
		(layer "F.Cu")
		(net 394)
	)
	(segment
		(start 126.475 99.822488)
		(end 123.825 97.172488)
		(width 0.19)
		(layer "F.Cu")
		(net 394)
	)
	(segment
		(start 135.752512 68.2)
		(end 134.964644 67.412132)
		(width 0.19)
		(layer "F.Cu")
		(net 394)
	)
	(segment
		(start 123.825 95.425)
		(end 123.7 95.3)
		(width 0.19)
		(layer "F.Cu")
		(net 394)
	)
	(segment
		(start 123.825 97.172488)
		(end 123.825 95.425)
		(width 0.19)
		(layer "F.Cu")
		(net 394)
	)
	(segment
		(start 126.325 100.699999)
		(end 126.475 100.549999)
		(width 0.19)
		(layer "F.Cu")
		(net 394)
	)
	(segment
		(start 126.325 101.6)
		(end 126.325 100.699999)
		(width 0.19)
		(layer "F.Cu")
		(net 394)
	)
	(segment
		(start 138.52 68.5)
		(end 138.22 68.2)
		(width 0.19)
		(layer "F.Cu")
		(net 394)
	)
	(via
		(at 123.7 95.3)
		(size 0.45)
		(drill 0.2)
		(layers "F.Cu" "B.Cu")
		(remove_unused_layers yes)
		(keep_end_layers yes)
		(zone_layer_connections)
		(net 394)
	)
	(via
		(at 134.787868 67.412132)
		(size 0.45)
		(drill 0.2)
		(layers "F.Cu" "B.Cu")
		(remove_unused_layers yes)
		(keep_end_layers yes)
		(zone_layer_connections)
		(net 394)
	)
	(segment
		(start 128.825 74.927512)
		(end 135.225 68.527512)
		(width 0.19)
		(layer "B.Cu")
		(net 394)
	)
	(segment
		(start 123.7 95.3)
		(end 123.825 95.175)
		(width 0.19)
		(layer "B.Cu")
		(net 394)
	)
	(segment
		(start 125.327512 82.925)
		(end 127.527512 82.925)
		(width 0.19)
		(layer "B.Cu")
		(net 394)
	)
	(segment
		(start 135.225 67.672488)
		(end 134.964644 67.412132)
		(width 0.19)
		(layer "B.Cu")
		(net 394)
	)
	(segment
		(start 123.325 91.427512)
		(end 123.825 90.927512)
		(width 0.19)
		(layer "B.Cu")
		(net 394)
	)
	(segment
		(start 123.825 84.427512)
		(end 125.327512 82.925)
		(width 0.19)
		(layer "B.Cu")
		(net 394)
	)
	(segment
		(start 123.825 90.927512)
		(end 123.825 84.427512)
		(width 0.19)
		(layer "B.Cu")
		(net 394)
	)
	(segment
		(start 123.325 93.072488)
		(end 123.325 91.427512)
		(width 0.19)
		(layer "B.Cu")
		(net 394)
	)
	(segment
		(start 135.225 68.527512)
		(end 135.225 67.672488)
		(width 0.19)
		(layer "B.Cu")
		(net 394)
	)
	(segment
		(start 134.964644 67.412132)
		(end 134.787868 67.412132)
		(width 0.19)
		(layer "B.Cu")
		(net 394)
	)
	(segment
		(start 123.825 93.572488)
		(end 123.325 93.072488)
		(width 0.19)
		(layer "B.Cu")
		(net 394)
	)
	(segment
		(start 127.527512 82.925)
		(end 128.825 81.627512)
		(width 0.19)
		(layer "B.Cu")
		(net 394)
	)
	(segment
		(start 128.825 81.627512)
		(end 128.825 74.927512)
		(width 0.19)
		(layer "B.Cu")
		(net 394)
	)
	(segment
		(start 123.825 95.175)
		(end 123.825 93.572488)
		(width 0.19)
		(layer "B.Cu")
		(net 394)
	)
	(segment
		(start 130.762132 134.6)
		(end 131.7 135.537868)
		(width 0.16)
		(layer "F.Cu")
		(net 395)
	)
	(segment
		(start 129.65 134.067976)
		(end 129.65 134.425738)
		(width 0.16)
		(layer "F.Cu")
		(net 395)
	)
	(segment
		(start 124.84 128.09)
		(end 124.6 127.85)
		(width 0.1)
		(layer "F.Cu")
		(net 395)
	)
	(segment
		(start 132.59883 135.765)
		(end 131.865 135.765)
		(width 0.1)
		(layer "F.Cu")
		(net 395)
	)
	(segment
		(start 129.981347 133.717976)
		(end 129.981347 133.787976)
		(width 0.16)
		(layer "F.Cu")
		(net 395)
	)
	(segment
		(start 130.75 133.3)
		(end 130.600001 133.150001)
		(width 0.16)
		(layer "F.Cu")
		(net 395)
	)
	(segment
		(start 133 136)
		(end 132.8825 135.8825)
		(width 0.1)
		(layer "F.Cu")
		(net 395)
	)
	(segment
		(start 129.79 133.577976)
		(end 129.841347 133.577976)
		(width 0.16)
		(layer "F.Cu")
		(net 395)
	)
	(segment
		(start 131.7 135.6)
		(end 131.7 135.537868)
		(width 0.1)
		(layer "F.Cu")
		(net 395)
	)
	(segment
		(start 129.65 133.274262)
		(end 129.65 133.437976)
		(width 0.16)
		(layer "F.Cu")
		(net 395)
	)
	(segment
		(start 130.600001 133.150001)
		(end 129.774261 133.150001)
		(width 0.16)
		(layer "F.Cu")
		(net 395)
	)
	(segment
		(start 131.865 135.765)
		(end 131.7 135.6)
		(width 0.1)
		(layer "F.Cu")
		(net 395)
	)
	(segment
		(start 129.774261 133.150001)
		(end 129.65 133.274262)
		(width 0.16)
		(layer "F.Cu")
		(net 395)
	)
	(segment
		(start 129.65 134.425738)
		(end 129.824262 134.6)
		(width 0.16)
		(layer "F.Cu")
		(net 395)
	)
	(segment
		(start 129.841347 133.927976)
		(end 129.79 133.927976)
		(width 0.16)
		(layer "F.Cu")
		(net 395)
	)
	(segment
		(start 129.824262 134.6)
		(end 130.762132 134.6)
		(width 0.16)
		(layer "F.Cu")
		(net 395)
	)
	(via
		(at 124.84 128.09)
		(size 0.45)
		(drill 0.2)
		(layers "F.Cu" "B.Cu")
		(remove_unused_layers yes)
		(keep_end_layers yes)
		(zone_layer_connections)
		(net 395)
	)
	(via
		(at 130.75 133.3)
		(size 0.45)
		(drill 0.2)
		(layers "F.Cu" "B.Cu")
		(remove_unused_layers yes)
		(keep_end_layers yes)
		(zone_layer_connections)
		(net 395)
	)
	(arc
		(start 129.65 133.437976)
		(mid 129.691005 133.536971)
		(end 129.79 133.577976)
		(width 0.16)
		(layer "F.Cu")
		(net 395)
	)
	(arc
		(start 129.79 133.927976)
		(mid 129.691005 133.968981)
		(end 129.65 134.067976)
		(width 0.16)
		(layer "F.Cu")
		(net 395)
	)
	(arc
		(start 132.8825 135.8825)
		(mid 132.752352 135.795537)
		(end 132.59883 135.765)
		(width 0.1)
		(layer "F.Cu")
		(net 395)
	)
	(arc
		(start 129.981347 133.787976)
		(mid 129.940342 133.886971)
		(end 129.841347 133.927976)
		(width 0.16)
		(layer "F.Cu")
		(net 395)
	)
	(arc
		(start 129.841347 133.577976)
		(mid 129.940342 133.618981)
		(end 129.981347 133.717976)
		(width 0.16)
		(layer "F.Cu")
		(net 395)
	)
	(segment
		(start 124.84 128.09)
		(end 125.014999 127.915001)
		(width 0.16)
		(layer "In5.Cu")
		(net 395)
	)
	(segment
		(start 128.687869 133.150001)
		(end 130.600001 133.150001)
		(width 0.16)
		(layer "In5.Cu")
		(net 395)
	)
	(segment
		(start 125.85 128.312132)
		(end 125.85 131.062132)
		(width 0.16)
		(layer "In5.Cu")
		(net 395)
	)
	(segment
		(start 125.452869 127.915001)
		(end 125.85 128.312132)
		(width 0.16)
		(layer "In5.Cu")
		(net 395)
	)
	(segment
		(start 125.85 131.062132)
		(end 126.687868 131.9)
		(width 0.16)
		(layer "In5.Cu")
		(net 395)
	)
	(segment
		(start 127.437868 131.9)
		(end 128.687869 133.150001)
		(width 0.16)
		(layer "In5.Cu")
		(net 395)
	)
	(segment
		(start 126.687868 131.9)
		(end 127.437868 131.9)
		(width 0.16)
		(layer "In5.Cu")
		(net 395)
	)
	(segment
		(start 125.014999 127.915001)
		(end 125.452869 127.915001)
		(width 0.16)
		(layer "In5.Cu")
		(net 395)
	)
	(segment
		(start 130.600001 133.150001)
		(end 130.75 133.3)
		(width 0.16)
		(layer "In5.Cu")
		(net 395)
	)
	(segment
		(start 131.8 136)
		(end 131.55 135.75)
		(width 0.1)
		(layer "F.Cu")
		(net 396)
	)
	(segment
		(start 131.55 135.75)
		(end 131.487868 135.75)
		(width 0.1)
		(layer "F.Cu")
		(net 396)
	)
	(segment
		(start 130.75 132.7)
		(end 130.600001 132.849999)
		(width 0.16)
		(layer "F.Cu")
		(net 396)
	)
	(segment
		(start 129.35 133.15)
		(end 129.35 134.55)
		(width 0.16)
		(layer "F.Cu")
		(net 396)
	)
	(segment
		(start 129.35 134.55)
		(end 129.7 134.9)
		(width 0.16)
		(layer "F.Cu")
		(net 396)
	)
	(segment
		(start 129.7 134.9)
		(end 130.637868 134.9)
		(width 0.16)
		(layer "F.Cu")
		(net 396)
	)
	(segment
		(start 130.600001 132.849999)
		(end 129.650001 132.849999)
		(width 0.16)
		(layer "F.Cu")
		(net 396)
	)
	(segment
		(start 130.637868 134.9)
		(end 131.487868 135.75)
		(width 0.16)
		(layer "F.Cu")
		(net 396)
	)
	(segment
		(start 124.84 127.44)
		(end 124.6 127.2)
		(width 0.1)
		(layer "F.Cu")
		(net 396)
	)
	(segment
		(start 129.650001 132.849999)
		(end 129.35 133.15)
		(width 0.16)
		(layer "F.Cu")
		(net 396)
	)
	(segment
		(start 132.5 136)
		(end 131.8 136)
		(width 0.1)
		(layer "F.Cu")
		(net 396)
	)
	(via
		(at 130.75 132.7)
		(size 0.45)
		(drill 0.2)
		(layers "F.Cu" "B.Cu")
		(remove_unused_layers yes)
		(keep_end_layers yes)
		(zone_layer_connections)
		(net 396)
	)
	(via
		(at 124.84 127.44)
		(size 0.45)
		(drill 0.2)
		(layers "F.Cu" "B.Cu")
		(remove_unused_layers yes)
		(keep_end_layers yes)
		(zone_layer_connections)
		(net 396)
	)
	(segment
		(start 127.562132 131.6)
		(end 128.812131 132.849999)
		(width 0.16)
		(layer "In5.Cu")
		(net 396)
	)
	(segment
		(start 128.812131 132.849999)
		(end 130.600001 132.849999)
		(width 0.16)
		(layer "In5.Cu")
		(net 396)
	)
	(segment
		(start 124.84 127.44)
		(end 125.014999 127.614999)
		(width 0.16)
		(layer "In5.Cu")
		(net 396)
	)
	(segment
		(start 125.577131 127.614999)
		(end 126.15 128.187868)
		(width 0.16)
		(layer "In5.Cu")
		(net 396)
	)
	(segment
		(start 126.812132 131.6)
		(end 127.562132 131.6)
		(width 0.16)
		(layer "In5.Cu")
		(net 396)
	)
	(segment
		(start 130.600001 132.849999)
		(end 130.75 132.7)
		(width 0.16)
		(layer "In5.Cu")
		(net 396)
	)
	(segment
		(start 126.15 128.187868)
		(end 126.15 130.937868)
		(width 0.16)
		(layer "In5.Cu")
		(net 396)
	)
	(segment
		(start 125.014999 127.614999)
		(end 125.577131 127.614999)
		(width 0.16)
		(layer "In5.Cu")
		(net 396)
	)
	(segment
		(start 126.15 130.937868)
		(end 126.812132 131.6)
		(width 0.16)
		(layer "In5.Cu")
		(net 396)
	)
	(segment
		(start 148.433 121.367)
		(end 148.433 118.6)
		(width 0.1)
		(layer "F.Cu")
		(net 397)
	)
	(segment
		(start 132.4111 118.2389)
		(end 133.05 117.6)
		(width 0.1)
		(layer "F.Cu")
		(net 397)
	)
	(segment
		(start 133.05 117.6)
		(end 133.05 114.85)
		(width 0.1)
		(layer "F.Cu")
		(net 397)
	)
	(segment
		(start 139.1 135)
		(end 139.652513 134.447487)
		(width 0.1)
		(layer "F.Cu")
		(net 397)
	)
	(segment
		(start 132.7 114.5)
		(end 133.05 114.85)
		(width 0.1)
		(layer "F.Cu")
		(net 397)
	)
	(segment
		(start 144.6 126.634314)
		(end 144.6 123.4)
		(width 0.1)
		(layer "F.Cu")
		(net 397)
	)
	(segment
		(start 132.4111 119.1189)
		(end 132.18 119.35)
		(width 0.1)
		(layer "F.Cu")
		(net 397)
	)
	(segment
		(start 137.5 135)
		(end 139.1 135)
		(width 0.1)
		(layer "F.Cu")
		(net 397)
	)
	(segment
		(start 144.6 123.4)
		(end 145.8 122.2)
		(width 0.1)
		(layer "F.Cu")
		(net 397)
	)
	(segment
		(start 132.7 114.5)
		(end 132.7 114.15)
		(width 0.1)
		(layer "F.Cu")
		(net 397)
	)
	(segment
		(start 142 133.6)
		(end 142 129.234314)
		(width 0.1)
		(layer "F.Cu")
		(net 397)
	)
	(segment
		(start 141.152513 134.447487)
		(end 142 133.6)
		(width 0.1)
		(layer "F.Cu")
		(net 397)
	)
	(segment
		(start 145.8 122.2)
		(end 147.6 122.2)
		(width 0.1)
		(layer "F.Cu")
		(net 397)
	)
	(segment
		(start 147.6 122.2)
		(end 148.433 121.367)
		(width 0.1)
		(layer "F.Cu")
		(net 397)
	)
	(segment
		(start 132.4111 119.1189)
		(end 132.4111 118.2389)
		(width 0.1)
		(layer "F.Cu")
		(net 397)
	)
	(segment
		(start 139.652513 134.447487)
		(end 141.152513 134.447487)
		(width 0.1)
		(layer "F.Cu")
		(net 397)
	)
	(segment
		(start 142 129.234314)
		(end 144.6 126.634314)
		(width 0.1)
		(layer "F.Cu")
		(net 397)
	)
	(via
		(at 148.425 121.375)
		(size 0.45)
		(drill 0.2)
		(layers "F.Cu" "B.Cu")
		(remove_unused_layers yes)
		(keep_end_layers yes)
		(zone_layer_connections)
		(net 397)
	)
	(via
		(at 132.7 114.15)
		(size 0.45)
		(drill 0.2)
		(layers "F.Cu" "B.Cu")
		(remove_unused_layers yes)
		(keep_end_layers yes)
		(zone_layer_connections)
		(net 397)
	)
	(segment
		(start 133.55 112.65)
		(end 135.15 112.65)
		(width 0.1)
		(layer "In3.Cu")
		(net 397)
	)
	(segment
		(start 138.25 114.05)
		(end 142.55 114.05)
		(width 0.1)
		(layer "In3.Cu")
		(net 397)
	)
	(segment
		(start 137.5 113.3)
		(end 138.25 114.05)
		(width 0.1)
		(layer "In3.Cu")
		(net 397)
	)
	(segment
		(start 148.425 120.025)
		(end 148.425 121.375)
		(width 0.1)
		(layer "In3.Cu")
		(net 397)
	)
	(segment
		(start 147.6 119.2)
		(end 148.425 120.025)
		(width 0.1)
		(layer "In3.Cu")
		(net 397)
	)
	(segment
		(start 142.7 113.9)
		(end 143.9 113.9)
		(width 0.1)
		(layer "In3.Cu")
		(net 397)
	)
	(segment
		(start 143.9 113.9)
		(end 147.6 117.6)
		(width 0.1)
		(layer "In3.Cu")
		(net 397)
	)
	(segment
		(start 132.7 113.5)
		(end 133.55 112.65)
		(width 0.1)
		(layer "In3.Cu")
		(net 397)
	)
	(segment
		(start 135.8 113.3)
		(end 137.5 113.3)
		(width 0.1)
		(layer "In3.Cu")
		(net 397)
	)
	(segment
		(start 147.6 117.6)
		(end 147.6 119.2)
		(width 0.1)
		(layer "In3.Cu")
		(net 397)
	)
	(segment
		(start 142.55 114.05)
		(end 142.7 113.9)
		(width 0.1)
		(layer "In3.Cu")
		(net 397)
	)
	(segment
		(start 135.15 112.65)
		(end 135.8 113.3)
		(width 0.1)
		(layer "In3.Cu")
		(net 397)
	)
	(segment
		(start 132.7 114.15)
		(end 132.7 113.5)
		(width 0.1)
		(layer "In3.Cu")
		(net 397)
	)
	(segment
		(start 139.755026 134.694974)
		(end 139.2 135.25)
		(width 0.1)
		(layer "F.Cu")
		(net 398)
	)
	(segment
		(start 133.6 117.85)
		(end 133.6 114.2)
		(width 0.1)
		(layer "F.Cu")
		(net 398)
	)
	(segment
		(start 132.87 118.58)
		(end 133.6 117.85)
		(width 0.1)
		(layer "F.Cu")
		(net 398)
	)
	(segment
		(start 141.255026 134.694974)
		(end 139.755026 134.694974)
		(width 0.1)
		(layer "F.Cu")
		(net 398)
	)
	(segment
		(start 145 124)
		(end 145 126.8)
		(width 0.1)
		(layer "F.Cu")
		(net 398)
	)
	(segment
		(start 142.4 129.4)
		(end 142.4 133.55)
		(width 0.1)
		(layer "F.Cu")
		(net 398)
	)
	(segment
		(start 149.704 118.6)
		(end 149.704 121.096)
		(width 0.1)
		(layer "F.Cu")
		(net 398)
	)
	(segment
		(start 132.87 119.12)
		(end 132.87 118.58)
		(width 0.1)
		(layer "F.Cu")
		(net 398)
	)
	(segment
		(start 142.4 133.55)
		(end 141.255026 134.694974)
		(width 0.1)
		(layer "F.Cu")
		(net 398)
	)
	(segment
		(start 146 123)
		(end 145 124)
		(width 0.1)
		(layer "F.Cu")
		(net 398)
	)
	(segment
		(start 132.64 119.35)
		(end 132.87 119.12)
		(width 0.1)
		(layer "F.Cu")
		(net 398)
	)
	(segment
		(start 139.2 135.25)
		(end 137.25 135.25)
		(width 0.1)
		(layer "F.Cu")
		(net 398)
	)
	(segment
		(start 137.25 135.25)
		(end 137 135.5)
		(width 0.1)
		(layer "F.Cu")
		(net 398)
	)
	(segment
		(start 147.8 123)
		(end 149.704 121.096)
		(width 0.1)
		(layer "F.Cu")
		(net 398)
	)
	(segment
		(start 145 126.8)
		(end 142.4 129.4)
		(width 0.1)
		(layer "F.Cu")
		(net 398)
	)
	(segment
		(start 147.8 123)
		(end 146 123)
		(width 0.1)
		(layer "F.Cu")
		(net 398)
	)
	(via
		(at 133.6 114.2)
		(size 0.45)
		(drill 0.2)
		(layers "F.Cu" "B.Cu")
		(remove_unused_layers yes)
		(keep_end_layers yes)
		(zone_layer_connections)
		(net 398)
	)
	(via
		(at 147.8 123)
		(size 0.45)
		(drill 0.2)
		(layers "F.Cu" "B.Cu")
		(remove_unused_layers yes)
		(keep_end_layers yes)
		(zone_layer_connections)
		(net 398)
	)
	(segment
		(start 138 114.6)
		(end 142.1 114.6)
		(width 0.1)
		(layer "In3.Cu")
		(net 398)
	)
	(segment
		(start 137.35 113.95)
		(end 138 114.6)
		(width 0.1)
		(layer "In3.Cu")
		(net 398)
	)
	(segment
		(start 146.800001 119.300001)
		(end 146.800001 122.000001)
		(width 0.1)
		(layer "In3.Cu")
		(net 398)
	)
	(segment
		(start 133.6 114.2)
		(end 133.85 113.95)
		(width 0.1)
		(layer "In3.Cu")
		(net 398)
	)
	(segment
		(start 146.800001 122.000001)
		(end 147.8 123)
		(width 0.1)
		(layer "In3.Cu")
		(net 398)
	)
	(segment
		(start 142.1 114.6)
		(end 146.800001 119.300001)
		(width 0.1)
		(layer "In3.Cu")
		(net 398)
	)
	(segment
		(start 133.85 113.95)
		(end 137.35 113.95)
		(width 0.1)
		(layer "In3.Cu")
		(net 398)
	)
	(segment
		(start 115.92 106.09)
		(end 115.92 105.1)
		(width 0.1)
		(layer "F.Cu")
		(net 399)
	)
	(segment
		(start 116.2 113.7)
		(end 116.2 113)
		(width 0.1)
		(layer "F.Cu")
		(net 399)
	)
	(via
		(at 122 98.4)
		(size 0.45)
		(drill 0.2)
		(layers "F.Cu" "B.Cu")
		(remove_unused_layers yes)
		(keep_end_layers yes)
		(zone_layer_connections)
		(net 399)
	)
	(via
		(at 116.2 113)
		(size 0.45)
		(drill 0.2)
		(layers "F.Cu" "B.Cu")
		(remove_unused_layers yes)
		(keep_end_layers yes)
		(zone_layer_connections)
		(net 399)
	)
	(via
		(at 115.92 105.1)
		(size 0.45)
		(drill 0.2)
		(layers "F.Cu" "B.Cu")
		(remove_unused_layers yes)
		(keep_end_layers yes)
		(zone_layer_connections)
		(net 399)
	)
	(segment
		(start 116.2 113)
		(end 117.8 113)
		(width 0.1)
		(layer "In5.Cu")
		(net 399)
	)
	(segment
		(start 117.9 106.1)
		(end 117.9 105.1)
		(width 0.1)
		(layer "In5.Cu")
		(net 399)
	)
	(segment
		(start 119.6 98.4)
		(end 118.4 99.6)
		(width 0.25)
		(layer "In5.Cu")
		(net 399)
	)
	(segment
		(start 115.92 105.1)
		(end 117.9 105.1)
		(width 0.1)
		(layer "In5.Cu")
		(net 399)
	)
	(segment
		(start 122 98.4)
		(end 119.6 98.4)
		(width 0.25)
		(layer "In5.Cu")
		(net 399)
	)
	(segment
		(start 118.4 104.6)
		(end 117.9 105.1)
		(width 0.25)
		(layer "In5.Cu")
		(net 399)
	)
	(segment
		(start 118.4 112.4)
		(end 118.4 106.6)
		(width 0.1)
		(layer "In5.Cu")
		(net 399)
	)
	(segment
		(start 118.4 99.6)
		(end 118.4 104.6)
		(width 0.25)
		(layer "In5.Cu")
		(net 399)
	)
	(segment
		(start 117.8 113)
		(end 118.4 112.4)
		(width 0.1)
		(layer "In5.Cu")
		(net 399)
	)
	(segment
		(start 118.4 106.6)
		(end 117.9 106.1)
		(width 0.1)
		(layer "In5.Cu")
		(net 399)
	)
	(segment
		(start 130.48 98.7)
		(end 130.48 98.48)
		(width 0.1)
		(layer "F.Cu")
		(net 400)
	)
	(segment
		(start 130.48 98.48)
		(end 130.1 98.1)
		(width 0.1)
		(layer "F.Cu")
		(net 400)
	)
	(segment
		(start 131.201 99.421)
		(end 130.48 98.7)
		(width 0.1)
		(layer "F.Cu")
		(net 400)
	)
	(segment
		(start 130.1 98.1)
		(end 127.1 98.1)
		(width 0.1)
		(layer "F.Cu")
		(net 400)
	)
	(segment
		(start 127.1 98.1)
		(end 126.325 97.325)
		(width 0.1)
		(layer "F.Cu")
		(net 400)
	)
	(segment
		(start 131.201 99.951)
		(end 131.201 99.421)
		(width 0.1)
		(layer "F.Cu")
		(net 400)
	)
	(segment
		(start 126.325 97.325)
		(end 126.325 96.2)
		(width 0.1)
		(layer "F.Cu")
		(net 400)
	)
	(segment
		(start 125.675 97.275)
		(end 127.7 99.3)
		(width 0.1)
		(layer "F.Cu")
		(net 401)
	)
	(segment
		(start 127.7 99.3)
		(end 127.7 101.6)
		(width 0.1)
		(layer "F.Cu")
		(net 401)
	)
	(segment
		(start 127.85 101.75)
		(end 128.901 101.75)
		(width 0.1)
		(layer "F.Cu")
		(net 401)
	)
	(segment
		(start 128.92 103.1)
		(end 128.92 101.769)
		(width 0.1)
		(layer "F.Cu")
		(net 401)
	)
	(segment
		(start 128.92 101.769)
		(end 128.901 101.75)
		(width 0.1)
		(layer "F.Cu")
		(net 401)
	)
	(segment
		(start 127.7 101.6)
		(end 127.85 101.75)
		(width 0.1)
		(layer "F.Cu")
		(net 401)
	)
	(segment
		(start 125.675 96.2)
		(end 125.675 97.275)
		(width 0.1)
		(layer "F.Cu")
		(net 401)
	)
	(segment
		(start 130.45 123.95)
		(end 130.775 124.275)
		(width 0.1)
		(layer "F.Cu")
		(net 402)
	)
	(segment
		(start 128.5 122)
		(end 128.175 121.675)
		(width 0.1)
		(layer "F.Cu")
		(net 402)
	)
	(segment
		(start 131.1 123.95)
		(end 130.775 124.275)
		(width 0.1)
		(layer "F.Cu")
		(net 402)
	)
	(segment
		(start 128.5 122)
		(end 128.825 121.675)
		(width 0.1)
		(layer "F.Cu")
		(net 402)
	)
	(segment
		(start 127.85 121.35)
		(end 128.175 121.025)
		(width 0.1)
		(layer "F.Cu")
		(net 402)
	)
	(segment
		(start 129.15 121.35)
		(end 128.825 121.675)
		(width 0.1)
		(layer "F.Cu")
		(net 402)
	)
	(segment
		(start 129.15 122)
		(end 128.825 121.675)
		(width 0.1)
		(layer "F.Cu")
		(net 402)
	)
	(segment
		(start 129.15 124.6)
		(end 128.825 124.275)
		(width 0.1)
		(layer "F.Cu")
		(net 402)
	)
	(segment
		(start 128.5 121.35)
		(end 128.175 121.025)
		(width 0.1)
		(layer "F.Cu")
		(net 402)
	)
	(segment
		(start 127.85 121.35)
		(end 128.175 121.675)
		(width 0.1)
		(layer "F.Cu")
		(net 402)
	)
	(segment
		(start 128.5 121.35)
		(end 128.825 121.675)
		(width 0.1)
		(layer "F.Cu")
		(net 402)
	)
	(segment
		(start 128.5 121.35)
		(end 128.175 121.675)
		(width 0.1)
		(layer "F.Cu")
		(net 402)
	)
	(segment
		(start 131.1 123.95)
		(end 131.425 124.275)
		(width 0.1)
		(layer "F.Cu")
		(net 402)
	)
	(segment
		(start 130.45 124.6)
		(end 130.775 124.275)
		(width 0.1)
		(layer "F.Cu")
		(net 402)
	)
	(segment
		(start 128.5 124.6)
		(end 128.825 124.275)
		(width 0.1)
		(layer "F.Cu")
		(net 402)
	)
	(segment
		(start 129.15 121.35)
		(end 128.825 121.025)
		(width 0.1)
		(layer "F.Cu")
		(net 402)
	)
	(segment
		(start 131.1 124.6)
		(end 131.425 124.275)
		(width 0.1)
		(layer "F.Cu")
		(net 402)
	)
	(segment
		(start 131.1 124.6)
		(end 130.775 124.275)
		(width 0.1)
		(layer "F.Cu")
		(net 402)
	)
	(segment
		(start 128.5 121.35)
		(end 128.825 121.025)
		(width 0.1)
		(layer "F.Cu")
		(net 402)
	)
	(via
		(at 131.425 124.275)
		(size 0.45)
		(drill 0.2)
		(layers "F.Cu" "B.Cu")
		(remove_unused_layers yes)
		(keep_end_layers yes)
		(zone_layer_connections "In3.Cu")
		(net 402)
	)
	(via
		(at 128.825 121.025)
		(size 0.45)
		(drill 0.2)
		(layers "F.Cu" "B.Cu")
		(remove_unused_layers yes)
		(keep_end_layers yes)
		(zone_layer_connections "In3.Cu")
		(net 402)
	)
	(via
		(at 128.825 124.275)
		(size 0.45)
		(drill 0.2)
		(layers "F.Cu" "B.Cu")
		(remove_unused_layers yes)
		(keep_end_layers yes)
		(zone_layer_connections "In3.Cu")
		(net 402)
	)
	(via
		(at 128.825 121.675)
		(size 0.45)
		(drill 0.2)
		(layers "F.Cu" "B.Cu")
		(remove_unused_layers yes)
		(keep_end_layers yes)
		(zone_layer_connections "In3.Cu")
		(net 402)
	)
	(via
		(at 130.775 124.275)
		(size 0.45)
		(drill 0.2)
		(layers "F.Cu" "B.Cu")
		(remove_unused_layers yes)
		(keep_end_layers yes)
		(zone_layer_connections "In3.Cu")
		(net 402)
	)
	(via
		(at 128.175 121.025)
		(size 0.45)
		(drill 0.2)
		(layers "F.Cu" "B.Cu")
		(remove_unused_layers yes)
		(keep_end_layers yes)
		(zone_layer_connections "In3.Cu")
		(net 402)
	)
	(via
		(at 128.175 121.675)
		(size 0.45)
		(drill 0.2)
		(layers "F.Cu" "B.Cu")
		(remove_unused_layers yes)
		(keep_end_layers yes)
		(zone_layer_connections "In3.Cu")
		(net 402)
	)
	(segment
		(start 127.524999 120.530001)
		(end 127.524999 120.674999)
		(width 0.25)
		(layer "B.Cu")
		(net 402)
	)
	(segment
		(start 128.175 121.195)
		(end 128.5 121.52)
		(width 0.25)
		(layer "B.Cu")
		(net 402)
	)
	(segment
		(start 128.175 121.025)
		(end 128.175 121.195)
		(width 0.25)
		(layer "B.Cu")
		(net 402)
	)
	(segment
		(start 127.875 121.025)
		(end 128.175 121.025)
		(width 0.25)
		(layer "B.Cu")
		(net 402)
	)
	(segment
		(start 128.499999 120.530001)
		(end 127.524999 120.530001)
		(width 0.25)
		(layer "B.Cu")
		(net 402)
	)
	(segment
		(start 127.524999 120.674999)
		(end 127.875 121.025)
		(width 0.25)
		(layer "B.Cu")
		(net 402)
	)
	(segment
		(start 130.775 124.275)
		(end 131.269998 124.275)
		(width 0.25)
		(layer "B.Cu")
		(net 402)
	)
	(segment
		(start 128.825 121.195)
		(end 128.5 121.52)
		(width 0.25)
		(layer "B.Cu")
		(net 402)
	)
	(segment
		(start 128.499999 120.700001)
		(end 128.175 121.025)
		(width 0.25)
		(layer "B.Cu")
		(net 402)
	)
	(segment
		(start 128.499999 120.530001)
		(end 128.499999 120.700001)
		(width 0.25)
		(layer "B.Cu")
		(net 402)
	)
	(segment
		(start 128.825 121.025)
		(end 128.825 120.855002)
		(width 0.25)
		(layer "B.Cu")
		(net 402)
	)
	(segment
		(start 128.825 120.855002)
		(end 128.499999 120.530001)
		(width 0.25)
		(layer "B.Cu")
		(net 402)
	)
	(segment
		(start 128.825 121.025)
		(end 128.825 121.195)
		(width 0.25)
		(layer "B.Cu")
		(net 402)
	)
	(segment
		(start 131.269998 124.275)
		(end 131.424998 124.43)
		(width 0.25)
		(layer "B.Cu")
		(net 402)
	)
	(segment
		(start 127.525 123.625)
		(end 127.85 123.95)
		(width 0.1)
		(layer "F.Cu")
		(net 403)
	)
	(segment
		(start 125.9 123.3)
		(end 125.575 123.625)
		(width 0.1)
		(layer "F.Cu")
		(net 403)
	)
	(segment
		(start 125.9 123.95)
		(end 126.225 123.625)
		(width 0.1)
		(layer "F.Cu")
		(net 403)
	)
	(segment
		(start 125.25 124.6)
		(end 125.575 124.275)
		(width 0.1)
		(layer "F.Cu")
		(net 403)
	)
	(segment
		(start 126.55 123.95)
		(end 126.875 123.625)
		(width 0.1)
		(layer "F.Cu")
		(net 403)
	)
	(segment
		(start 125.9 124.6)
		(end 125.575 124.275)
		(width 0.1)
		(layer "F.Cu")
		(net 403)
	)
	(segment
		(start 125.25 123.3)
		(end 125.9 123.95)
		(width 0.1)
		(layer "F.Cu")
		(net 403)
	)
	(segment
		(start 125.9 123.95)
		(end 126.225 124.275)
		(width 0.1)
		(layer "F.Cu")
		(net 403)
	)
	(segment
		(start 127.2 123.95)
		(end 127.525 123.625)
		(width 0.1)
		(layer "F.Cu")
		(net 403)
	)
	(segment
		(start 125.25 124.6)
		(end 124.925 124.275)
		(width 0.1)
		(layer "F.Cu")
		(net 403)
	)
	(segment
		(start 125.9 124.6)
		(end 126.55 123.95)
		(width 0.1)
		(layer "F.Cu")
		(net 403)
	)
	(segment
		(start 126.55 123.95)
		(end 125.9 123.3)
		(width 0.1)
		(layer "F.Cu")
		(net 403)
	)
	(segment
		(start 127.2 123.95)
		(end 126.875 123.625)
		(width 0.1)
		(layer "F.Cu")
		(net 403)
	)
	(segment
		(start 125.9 123.95)
		(end 125.575 124.275)
		(width 0.1)
		(layer "F.Cu")
		(net 403)
	)
	(via
		(at 125.575 124.275)
		(size 0.45)
		(drill 0.2)
		(layers "F.Cu" "B.Cu")
		(remove_unused_layers yes)
		(keep_end_layers yes)
		(zone_layer_connections)
		(net 403)
	)
	(via
		(at 126.875 123.625)
		(size 0.45)
		(drill 0.2)
		(layers "F.Cu" "B.Cu")
		(remove_unused_layers yes)
		(keep_end_layers yes)
		(zone_layer_connections)
		(net 403)
	)
	(via
		(at 124.925 124.275)
		(size 0.45)
		(drill 0.2)
		(layers "F.Cu" "B.Cu")
		(remove_unused_layers yes)
		(keep_end_layers yes)
		(zone_layer_connections)
		(net 403)
	)
	(via
		(at 127.525 123.625)
		(size 0.45)
		(drill 0.2)
		(layers "F.Cu" "B.Cu")
		(remove_unused_layers yes)
		(keep_end_layers yes)
		(zone_layer_connections)
		(net 403)
	)
	(segment
		(start 127.524999 123.624999)
		(end 127.525 123.625)
		(width 0.25)
		(layer "B.Cu")
		(net 403)
	)
	(segment
		(start 125.575 124.429999)
		(end 125.574999 124.43)
		(width 0.25)
		(layer "B.Cu")
		(net 403)
	)
	(segment
		(start 123.625 124.430002)
		(end 123.624999 124.430001)
		(width 0.25)
		(layer "B.Cu")
		(net 403)
	)
	(segment
		(start 124.925 124.275)
		(end 124.755 124.275)
		(width 0.25)
		(layer "B.Cu")
		(net 403)
	)
	(segment
		(start 126.549999 123.595)
		(end 126.845 123.595)
		(width 0.25)
		(layer "B.Cu")
		(net 403)
	)
	(segment
		(start 127.524999 123.470002)
		(end 127.524999 123.624999)
		(width 0.25)
		(layer "B.Cu")
		(net 403)
	)
	(segment
		(start 124.599998 124.430002)
		(end 123.625 124.430002)
		(width 0.25)
		(layer "B.Cu")
		(net 403)
	)
	(segment
		(start 124.755 124.275)
		(end 124.599998 124.430002)
		(width 0.25)
		(layer "B.Cu")
		(net 403)
	)
	(segment
		(start 125.575 124.275)
		(end 125.575 124.429999)
		(width 0.25)
		(layer "B.Cu")
		(net 403)
	)
	(segment
		(start 126.845 123.595)
		(end 126.875 123.625)
		(width 0.25)
		(layer "B.Cu")
		(net 403)
	)
	(segment
		(start 130.449999 122.65)
		(end 130.125 122.975)
		(width 0.1)
		(layer "F.Cu")
		(net 404)
	)
	(segment
		(start 130.45 122.65)
		(end 130.125 122.325)
		(width 0.1)
		(layer "F.Cu")
		(net 404)
	)
	(segment
		(start 129.8 122.65)
		(end 130.125 122.975)
		(width 0.1)
		(layer "F.Cu")
		(net 404)
	)
	(segment
		(start 129.15 122.65)
		(end 129.475 122.975)
		(width 0.1)
		(layer "F.Cu")
		(net 404)
	)
	(segment
		(start 129.8 122.65)
		(end 129.475 122.325)
		(width 0.1)
		(layer "F.Cu")
		(net 404)
	)
	(segment
		(start 128.5 122.65)
		(end 129.15 122.65)
		(width 0.1)
		(layer "F.Cu")
		(net 404)
	)
	(segment
		(start 129.799999 122.65)
		(end 129.475 122.975)
		(width 0.1)
		(layer "F.Cu")
		(net 404)
	)
	(segment
		(start 129.15 122.65)
		(end 129.475 122.325)
		(width 0.1)
		(layer "F.Cu")
		(net 404)
	)
	(segment
		(start 129.8 122.65)
		(end 130.125 122.325)
		(width 0.1)
		(layer "F.Cu")
		(net 404)
	)
	(via
		(at 130.125 120.375)
		(size 0.45)
		(drill 0.2)
		(layers "F.Cu" "B.Cu")
		(remove_unused_layers yes)
		(keep_end_layers yes)
		(zone_layer_connections)
		(net 404)
	)
	(via
		(at 130.125 122.325)
		(size 0.45)
		(drill 0.2)
		(layers "F.Cu" "B.Cu")
		(remove_unused_layers yes)
		(keep_end_layers yes)
		(zone_layer_connections)
		(net 404)
	)
	(via
		(at 129.475 120.375)
		(size 0.45)
		(drill 0.2)
		(layers "F.Cu" "B.Cu")
		(remove_unused_layers yes)
		(keep_end_layers yes)
		(zone_layer_connections)
		(net 404)
	)
	(via
		(at 129.475 122.325)
		(size 0.45)
		(drill 0.2)
		(layers "F.Cu" "B.Cu")
		(remove_unused_layers yes)
		(keep_end_layers yes)
		(zone_layer_connections)
		(net 404)
	)
	(segment
		(start 130.125 122.325)
		(end 130.125 120.375)
		(width 0.5)
		(layer "In2.Cu")
		(net 404)
	)
	(segment
		(start 129.475 122.325)
		(end 130.125 122.325)
		(width 0.5)
		(layer "In2.Cu")
		(net 404)
	)
	(segment
		(start 130.125 120.375)
		(end 129.475 120.375)
		(width 0.5)
		(layer "In2.Cu")
		(net 404)
	)
	(segment
		(start 126.55 122.65)
		(end 126.225 122.325)
		(width 0.1)
		(layer "F.Cu")
		(net 405)
	)
	(segment
		(start 127.2 122.65)
		(end 126.875 122.325)
		(width 0.1)
		(layer "F.Cu")
		(net 405)
	)
	(segment
		(start 126.55 122.65)
		(end 126.875 122.325)
		(width 0.1)
		(layer "F.Cu")
		(net 405)
	)
	(via
		(at 126.875 122.325)
		(size 0.45)
		(drill 0.2)
		(layers "F.Cu" "B.Cu")
		(remove_unused_layers yes)
		(keep_end_layers yes)
		(zone_layer_connections)
		(net 405)
	)
	(via
		(at 126.225 122.325)
		(size 0.45)
		(drill 0.2)
		(layers "F.Cu" "B.Cu")
		(remove_unused_layers yes)
		(keep_end_layers yes)
		(zone_layer_connections)
		(net 405)
	)
	(segment
		(start 126.875 122.325)
		(end 126.225 122.325)
		(width 0.25)
		(layer "B.Cu")
		(net 405)
	)
	(segment
		(start 125.079999 122.475001)
		(end 126.074999 122.475001)
		(width 0.25)
		(layer "B.Cu")
		(net 405)
	)
	(segment
		(start 126.074999 122.475001)
		(end 126.225 122.325)
		(width 0.25)
		(layer "B.Cu")
		(net 405)
	)
	(segment
		(start 154.58 147.14)
		(end 155.86 147.14)
		(width 0.1)
		(layer "B.Cu")
		(net 406)
	)
	(segment
		(start 159.575 146.25)
		(end 159.6 146.275)
		(width 0.1)
		(layer "B.Cu")
		(net 406)
	)
	(segment
		(start 153.579998 147.14)
		(end 154.58 147.14)
		(width 0.1)
		(layer "B.Cu")
		(net 406)
	)
	(segment
		(start 155.86 147.14)
		(end 156.75 146.25)
		(width 0.1)
		(layer "B.Cu")
		(net 406)
	)
	(segment
		(start 156.75 146.25)
		(end 159.575 146.25)
		(width 0.1)
		(layer "B.Cu")
		(net 406)
	)
	(segment
		(start 177.88 147.15)
		(end 178.77 146.26)
		(width 0.1)
		(layer "B.Cu")
		(net 407)
	)
	(segment
		(start 175.599998 147.15)
		(end 176.6 147.15)
		(width 0.1)
		(layer "B.Cu")
		(net 407)
	)
	(segment
		(start 178.77 146.26)
		(end 181.595 146.26)
		(width 0.1)
		(layer "B.Cu")
		(net 407)
	)
	(segment
		(start 176.6 147.15)
		(end 177.88 147.15)
		(width 0.1)
		(layer "B.Cu")
		(net 407)
	)
	(segment
		(start 155.355 151.355)
		(end 159.6 151.355)
		(width 0.1)
		(layer "B.Cu")
		(net 408)
	)
	(segment
		(start 152.579999 147.139998)
		(end 152.580001 147.14)
		(width 0.1)
		(layer "B.Cu")
		(net 408)
	)
	(segment
		(start 151.58 147.139998)
		(end 152.579999 147.139998)
		(width 0.1)
		(layer "B.Cu")
		(net 408)
	)
	(segment
		(start 152.580001 148.580001)
		(end 155.355 151.355)
		(width 0.1)
		(layer "B.Cu")
		(net 408)
	)
	(segment
		(start 152.580001 147.14)
		(end 152.580001 148.580001)
		(width 0.1)
		(layer "B.Cu")
		(net 408)
	)
	(segment
		(start 174.599999 147.149998)
		(end 174.600001 147.15)
		(width 0.1)
		(layer "B.Cu")
		(net 409)
	)
	(segment
		(start 173.6 147.149998)
		(end 174.599999 147.149998)
		(width 0.1)
		(layer "B.Cu")
		(net 409)
	)
	(segment
		(start 174.600001 147.15)
		(end 174.600001 148.590001)
		(width 0.1)
		(layer "B.Cu")
		(net 409)
	)
	(segment
		(start 174.600001 148.590001)
		(end 177.375 151.365)
		(width 0.1)
		(layer "B.Cu")
		(net 409)
	)
	(segment
		(start 177.375 151.365)
		(end 181.62 151.365)
		(width 0.1)
		(layer "B.Cu")
		(net 409)
	)
	(segment
		(start 144.56 148.815)
		(end 147.905 148.815)
		(width 0.1)
		(layer "B.Cu")
		(net 410)
	)
	(segment
		(start 150.58 147.14)
		(end 149.58 147.14)
		(width 0.1)
		(layer "B.Cu")
		(net 410)
	)
	(segment
		(start 147.905 148.815)
		(end 149.58 147.14)
		(width 0.1)
		(layer "B.Cu")
		(net 410)
	)
	(segment
		(start 169.925 148.825)
		(end 171.6 147.15)
		(width 0.1)
		(layer "B.Cu")
		(net 411)
	)
	(segment
		(start 172.6 147.15)
		(end 171.6 147.15)
		(width 0.1)
		(layer "B.Cu")
		(net 411)
	)
	(segment
		(start 166.58 148.825)
		(end 169.925 148.825)
		(width 0.1)
		(layer "B.Cu")
		(net 411)
	)
	(segment
		(start 152.82 49.72)
		(end 152.6 49.5)
		(width 0.5)
		(layer "F.Cu")
		(net 412)
	)
	(segment
		(start 143 48.45)
		(end 149 48.45)
		(width 0.5)
		(layer "F.Cu")
		(net 412)
	)
	(segment
		(start 152.25 48.45)
		(end 152.8 47.9)
		(width 0.1)
		(layer "F.Cu")
		(net 412)
	)
	(segment
		(start 127.801 55.575)
		(end 129.916439 55.575)
		(width 0.75)
		(layer "F.Cu")
		(net 412)
	)
	(segment
		(start 156.06 49.375)
		(end 155.515 49.375)
		(width 0.25)
		(layer "F.Cu")
		(net 412)
	)
	(segment
		(start 157.425 48.85)
		(end 156.825 49.45)
		(width 0.25)
		(layer "F.Cu")
		(net 412)
	)
	(segment
		(start 155.515 49.375)
		(end 155.17 49.72)
		(width 0.25)
		(layer "F.Cu")
		(net 412)
	)
	(segment
		(start 142.8 48.65)
		(end 143 48.45)
		(width 0.5)
		(layer "F.Cu")
		(net 412)
	)
	(segment
		(start 137.3 53.15)
		(end 137.3 48.65)
		(width 0.5)
		(layer "F.Cu")
		(net 412)
	)
	(segment
		(start 156.06 49.825)
		(end 155.275 49.825)
		(width 0.25)
		(layer "F.Cu")
		(net 412)
	)
	(segment
		(start 157.425 48.26)
		(end 157.425 48.85)
		(width 0.25)
		(layer "F.Cu")
		(net 412)
	)
	(segment
		(start 152.25 48.45)
		(end 152.6 48.8)
		(width 0.5)
		(layer "F.Cu")
		(net 412)
	)
	(segment
		(start 153.8 49.72)
		(end 155.17 49.72)
		(width 0.5)
		(layer "F.Cu")
		(net 412)
	)
	(segment
		(start 131.5 56.126)
		(end 131.375 56.001)
		(width 0.5)
		(layer "F.Cu")
		(net 412)
	)
	(segment
		(start 137.3 48.65)
		(end 142.8 48.65)
		(width 0.5)
		(layer "F.Cu")
		(net 412)
	)
	(segment
		(start 152.6 49.5)
		(end 152.6 48.8)
		(width 0.5)
		(layer "F.Cu")
		(net 412)
	)
	(segment
		(start 155.275 49.825)
		(end 155.17 49.72)
		(width 0.25)
		(layer "F.Cu")
		(net 412)
	)
	(segment
		(start 152.25 48.45)
		(end 149 48.45)
		(width 0.5)
		(layer "F.Cu")
		(net 412)
	)
	(segment
		(start 152.8 47.9)
		(end 153.32 47.9)
		(width 0.1)
		(layer "F.Cu")
		(net 412)
	)
	(segment
		(start 153.8 49.72)
		(end 152.82 49.72)
		(width 0.5)
		(layer "F.Cu")
		(net 412)
	)
	(segment
		(start 129.916439 55.575)
		(end 131.146 56.804561)
		(width 0.75)
		(layer "F.Cu")
		(net 412)
	)
	(via
		(at 137.3 50.2)
		(size 0.45)
		(drill 0.2)
		(layers "F.Cu" "B.Cu")
		(remove_unused_layers yes)
		(keep_end_layers yes)
		(zone_layer_connections)
		(net 412)
	)
	(via
		(at 137.3 51.2)
		(size 0.45)
		(drill 0.2)
		(layers "F.Cu" "B.Cu")
		(remove_unused_layers yes)
		(keep_end_layers yes)
		(zone_layer_connections)
		(net 412)
	)
	(via
		(at 137.3 50.7)
		(size 0.45)
		(drill 0.2)
		(layers "F.Cu" "B.Cu")
		(remove_unused_layers yes)
		(keep_end_layers yes)
		(zone_layer_connections)
		(net 412)
	)
	(via
		(at 137.3 51.7)
		(size 0.45)
		(drill 0.2)
		(layers "F.Cu" "B.Cu")
		(remove_unused_layers yes)
		(keep_end_layers yes)
		(zone_layer_connections)
		(net 412)
	)
	(segment
		(start 131.146 56.804561)
		(end 131.146 54.254)
		(width 0.75)
		(layer "B.Cu")
		(net 412)
	)
	(segment
		(start 131.146 54.254)
		(end 132.2 53.2)
		(width 0.75)
		(layer "B.Cu")
		(net 412)
	)
	(segment
		(start 137.3 50.2)
		(end 137.3 52.3)
		(width 0.75)
		(layer "B.Cu")
		(net 412)
	)
	(segment
		(start 132.2 53.2)
		(end 136.4 53.2)
		(width 0.75)
		(layer "B.Cu")
		(net 412)
	)
	(segment
		(start 137.3 52.3)
		(end 136.4 53.2)
		(width 0.75)
		(layer "B.Cu")
		(net 412)
	)
	(segment
		(start 116.88 108.1)
		(end 117.45 107.53)
		(width 0.1)
		(layer "F.Cu")
		(net 413)
	)
	(segment
		(start 118.15 104.85)
		(end 117.7 104.85)
		(width 0.1)
		(layer "F.Cu")
		(net 413)
	)
	(segment
		(start 117.45 107.53)
		(end 117.45 105.1)
		(width 0.1)
		(layer "F.Cu")
		(net 413)
	)
	(segment
		(start 116.88 108.1)
		(end 116.88 109.1)
		(width 0.1)
		(layer "F.Cu")
		(net 413)
	)
	(segment
		(start 117.7 104.85)
		(end 117.45 105.1)
		(width 0.1)
		(layer "F.Cu")
		(net 413)
	)
	(via
		(at 116.9 109.1)
		(size 0.45)
		(drill 0.2)
		(layers "F.Cu" "B.Cu")
		(remove_unused_layers yes)
		(keep_end_layers yes)
		(zone_layer_connections)
		(net 413)
	)
	(segment
		(start 116.9 108.7)
		(end 116.9 109.1)
		(width 0.1)
		(layer "B.Cu")
		(net 413)
	)
	(segment
		(start 116.749 108.549)
		(end 116.9 108.7)
		(width 0.1)
		(layer "B.Cu")
		(net 413)
	)
	(segment
		(start 116.201 108.549)
		(end 116.749 108.549)
		(width 0.1)
		(layer "B.Cu")
		(net 413)
	)
	(segment
		(start 182.8 70)
		(end 181.8 70)
		(width 0.1)
		(layer "F.Cu")
		(net 414)
	)
	(via
		(at 181.8 70)
		(size 0.45)
		(drill 0.2)
		(layers "F.Cu" "B.Cu")
		(remove_unused_layers yes)
		(keep_end_layers yes)
		(zone_layer_connections)
		(net 414)
	)
	(segment
		(start 181.8 70)
		(end 181.28 70)
		(width 0.5)
		(layer "B.Cu")
		(net 414)
	)
	(segment
		(start 182.8 71.5)
		(end 181.8 71.5)
		(width 0.1)
		(layer "F.Cu")
		(net 415)
	)
	(via
		(at 181.8 71.5)
		(size 0.45)
		(drill 0.2)
		(layers "F.Cu" "B.Cu")
		(remove_unused_layers yes)
		(keep_end_layers yes)
		(zone_layer_connections)
		(net 415)
	)
	(segment
		(start 181.8 71.5)
		(end 181.28 71.5)
		(width 0.5)
		(layer "B.Cu")
		(net 415)
	)
	(segment
		(start 182.8 74.5)
		(end 181.8 74.5)
		(width 0.1)
		(layer "F.Cu")
		(net 416)
	)
	(via
		(at 181.8 74.5)
		(size 0.45)
		(drill 0.2)
		(layers "F.Cu" "B.Cu")
		(remove_unused_layers yes)
		(keep_end_layers yes)
		(zone_layer_connections)
		(net 416)
	)
	(segment
		(start 181.28 74.5)
		(end 181.8 74.5)
		(width 0.5)
		(layer "B.Cu")
		(net 416)
	)
	(segment
		(start 182.8 76)
		(end 181.8 76)
		(width 0.1)
		(layer "F.Cu")
		(net 417)
	)
	(via
		(at 181.8 76)
		(size 0.45)
		(drill 0.2)
		(layers "F.Cu" "B.Cu")
		(remove_unused_layers yes)
		(keep_end_layers yes)
		(zone_layer_connections)
		(net 417)
	)
	(segment
		(start 181.3 76)
		(end 181.8 76)
		(width 0.5)
		(layer "B.Cu")
		(net 417)
	)
	(segment
		(start 135 141.8)
		(end 135.7 141.1)
		(width 0.1)
		(layer "F.Cu")
		(net 418)
	)
	(segment
		(start 135.7 141.1)
		(end 141.4 141.1)
		(width 0.1)
		(layer "F.Cu")
		(net 418)
	)
	(segment
		(start 144.6 131.8)
		(end 146 130.4)
		(width 0.1)
		(layer "F.Cu")
		(net 418)
	)
	(segment
		(start 146 130.4)
		(end 150.3 130.4)
		(width 0.1)
		(layer "F.Cu")
		(net 418)
	)
	(segment
		(start 144.6 137.9)
		(end 144.6 131.8)
		(width 0.1)
		(layer "F.Cu")
		(net 418)
	)
	(segment
		(start 141.4 141.1)
		(end 144.6 137.9)
		(width 0.1)
		(layer "F.Cu")
		(net 418)
	)
	(segment
		(start 135 142.8)
		(end 135 141.8)
		(width 0.1)
		(layer "F.Cu")
		(net 418)
	)
	(segment
		(start 150.3 130.4)
		(end 153.9 126.8)
		(width 0.1)
		(layer "F.Cu")
		(net 418)
	)
	(segment
		(start 153.9 126.8)
		(end 153.9 117.5005)
		(width 0.1)
		(layer "F.Cu")
		(net 418)
	)
	(segment
		(start 134.52 144.68)
		(end 135 144.2)
		(width 0.25)
		(layer "F.Cu")
		(net 419)
	)
	(segment
		(start 134.52 145.5)
		(end 134.52 144.68)
		(width 0.25)
		(layer "F.Cu")
		(net 419)
	)
	(segment
		(start 124.52 55.32)
		(end 125 55.8)
		(width 0.1)
		(layer "F.Cu")
		(net 420)
	)
	(segment
		(start 124.52 54.5)
		(end 124.52 55.32)
		(width 0.1)
		(layer "F.Cu")
		(net 420)
	)
	(segment
		(start 129.92 145.5)
		(end 129.92 144.78)
		(width 0.25)
		(layer "F.Cu")
		(net 421)
	)
	(segment
		(start 129.92 144.78)
		(end 130.4 144.3)
		(width 0.25)
		(layer "F.Cu")
		(net 421)
	)
	(segment
		(start 133.33 127.86)
		(end 133.1 128.09)
		(width 0.1)
		(layer "F.Cu")
		(net 426)
	)
	(segment
		(start 133.56 127.85)
		(end 133.56 127.63)
		(width 0.1)
		(layer "F.Cu")
		(net 426)
	)
	(segment
		(start 133.55 127.86)
		(end 133.56 127.85)
		(width 0.1)
		(layer "F.Cu")
		(net 426)
	)
	(segment
		(start 133.33 127.86)
		(end 133.55 127.86)
		(width 0.1)
		(layer "F.Cu")
		(net 426)
	)
	(segment
		(start 133.56 128.09)
		(end 133.56 127.85)
		(width 0.1)
		(layer "F.Cu")
		(net 426)
	)
	(segment
		(start 179.7 70.88)
		(end 180.32 71.5)
		(width 0.1)
		(layer "B.Cu")
		(net 428)
	)
	(segment
		(start 178.5 68.65)
		(end 179.45 68.65)
		(width 0.1)
		(layer "B.Cu")
		(net 428)
	)
	(segment
		(start 179.45 68.65)
		(end 179.7 68.9)
		(width 0.1)
		(layer "B.Cu")
		(net 428)
	)
	(segment
		(start 179.7 68.9)
		(end 179.7 70.88)
		(width 0.1)
		(layer "B.Cu")
		(net 428)
	)
	(segment
		(start 179.6 71.3)
		(end 179.6 72.28)
		(width 0.1)
		(layer "B.Cu")
		(net 429)
	)
	(segment
		(start 179.45 71.15)
		(end 179.6 71.3)
		(width 0.1)
		(layer "B.Cu")
		(net 429)
	)
	(segment
		(start 179.6 72.28)
		(end 180.32 73)
		(width 0.1)
		(layer "B.Cu")
		(net 429)
	)
	(segment
		(start 178.5 71.15)
		(end 179.45 71.15)
		(width 0.1)
		(layer "B.Cu")
		(net 429)
	)
	(segment
		(start 179.47 73.65)
		(end 180.32 74.5)
		(width 0.1)
		(layer "B.Cu")
		(net 430)
	)
	(segment
		(start 178.5 73.65)
		(end 179.47 73.65)
		(width 0.1)
		(layer "B.Cu")
		(net 430)
	)
	(segment
		(start 178.5 76.2)
		(end 180.14 76.2)
		(width 0.1)
		(layer "B.Cu")
		(net 431)
	)
	(segment
		(start 180.14 76.2)
		(end 180.34 76)
		(width 0.1)
		(layer "B.Cu")
		(net 431)
	)
	(segment
		(start 140 58.8)
		(end 140 61)
		(width 0.1)
		(layer "F.Cu")
		(net 432)
	)
	(segment
		(start 140.119 58.681)
		(end 140 58.8)
		(width 0.1)
		(layer "F.Cu")
		(net 432)
	)
	(segment
		(start 140 61)
		(end 140.253 61.253)
		(width 0.1)
		(layer "F.Cu")
		(net 432)
	)
	(segment
		(start 140.253 61.253)
		(end 141.036 61.253)
		(width 0.1)
		(layer "F.Cu")
		(net 432)
	)
	(segment
		(start 140.807 58.681)
		(end 140.119 58.681)
		(width 0.1)
		(layer "F.Cu")
		(net 432)
	)
	(segment
		(start 137.436 61.812)
		(end 138.088 61.812)
		(width 0.1)
		(layer "F.Cu")
		(net 433)
	)
	(segment
		(start 138.2 60.5)
		(end 138.1 60.4)
		(width 0.1)
		(layer "F.Cu")
		(net 433)
	)
	(segment
		(start 138.1 60.4)
		(end 137.48 60.4)
		(width 0.1)
		(layer "F.Cu")
		(net 433)
	)
	(segment
		(start 138.088 61.812)
		(end 138.2 61.7)
		(width 0.1)
		(layer "F.Cu")
		(net 433)
	)
	(segment
		(start 138.2 61.7)
		(end 138.2 60.5)
		(width 0.1)
		(layer "F.Cu")
		(net 433)
	)
	(segment
		(start 117.546 144.124)
		(end 117.546 145.534)
		(width 0.25)
		(layer "F.Cu")
		(net 434)
	)
	(segment
		(start 117.546 145.534)
		(end 117.48 145.6)
		(width 0.25)
		(layer "F.Cu")
		(net 434)
	)
	(segment
		(start 121.25 90)
		(end 121.199 89.949)
		(width 0.1)
		(layer "F.Cu")
		(net 435)
	)
	(segment
		(start 121.199 89.949)
		(end 120.35 89.949)
		(width 0.1)
		(layer "F.Cu")
		(net 435)
	)
	(via
		(at 121.25 90)
		(size 0.45)
		(drill 0.2)
		(layers "F.Cu" "B.Cu")
		(remove_unused_layers yes)
		(keep_end_layers yes)
		(zone_layer_connections)
		(net 435)
	)
	(via
		(at 116.6 90.3)
		(size 0.45)
		(drill 0.2)
		(layers "F.Cu" "B.Cu")
		(remove_unused_layers yes)
		(keep_end_layers yes)
		(zone_layer_connections)
		(net 435)
	)
	(segment
		(start 117.500002 90.230001)
		(end 116.669999 90.230001)
		(width 0.1)
		(layer "B.Cu")
		(net 435)
	)
	(segment
		(start 116.669999 90.230001)
		(end 116.6 90.3)
		(width 0.1)
		(layer "B.Cu")
		(net 435)
	)
	(segment
		(start 118.499999 90.230001)
		(end 118.5 90.23)
		(width 0.1)
		(layer "B.Cu")
		(net 435)
	)
	(segment
		(start 117.500002 90.230001)
		(end 118.499999 90.230001)
		(width 0.1)
		(layer "B.Cu")
		(net 435)
	)
	(segment
		(start 121.25 90)
		(end 116.9 90)
		(width 0.1)
		(layer "In5.Cu")
		(net 435)
	)
	(segment
		(start 116.9 90)
		(end 116.6 90.3)
		(width 0.1)
		(layer "In5.Cu")
		(net 435)
	)
	(segment
		(start 118.55 89.949)
		(end 117.649 89.949)
		(width 0.1)
		(layer "F.Cu")
		(net 436)
	)
	(segment
		(start 118.85 90.249)
		(end 118.55 89.949)
		(width 0.1)
		(layer "F.Cu")
		(net 436)
	)
	(segment
		(start 118.85 90.95)
		(end 118.85 90.249)
		(width 0.1)
		(layer "F.Cu")
		(net 436)
	)
	(via
		(at 118.85 90.95)
		(size 0.45)
		(drill 0.2)
		(layers "F.Cu" "B.Cu")
		(remove_unused_layers yes)
		(keep_end_layers yes)
		(zone_layer_connections)
		(net 436)
	)
	(segment
		(start 118.85 90.88)
		(end 119.5 90.23)
		(width 0.1)
		(layer "B.Cu")
		(net 436)
	)
	(segment
		(start 120.499999 90.23)
		(end 120.500001 90.229998)
		(width 0.1)
		(layer "B.Cu")
		(net 436)
	)
	(segment
		(start 118.85 90.95)
		(end 118.85 90.88)
		(width 0.1)
		(layer "B.Cu")
		(net 436)
	)
	(segment
		(start 119.5 90.23)
		(end 120.499999 90.23)
		(width 0.1)
		(layer "B.Cu")
		(net 436)
	)
	(segment
		(start 135 87.3)
		(end 135.2 87.5)
		(width 0.1)
		(layer "F.Cu")
		(net 437)
	)
	(segment
		(start 134.52 85.2)
		(end 135.3 85.2)
		(width 0.1)
		(layer "F.Cu")
		(net 437)
	)
	(segment
		(start 137.355 86.524999)
		(end 137.355 87.145)
		(width 0.1)
		(layer "F.Cu")
		(net 437)
	)
	(segment
		(start 135 86.73)
		(end 135.5 86.23)
		(width 0.1)
		(layer "F.Cu")
		(net 437)
	)
	(segment
		(start 135.5 85.4)
		(end 135.5 86.23)
		(width 0.1)
		(layer "F.Cu")
		(net 437)
	)
	(segment
		(start 134 84.68)
		(end 134.52 85.2)
		(width 0.1)
		(layer "F.Cu")
		(net 437)
	)
	(segment
		(start 135.3 85.2)
		(end 135.5 85.4)
		(width 0.1)
		(layer "F.Cu")
		(net 437)
	)
	(segment
		(start 135 86.73)
		(end 135 87.3)
		(width 0.1)
		(layer "F.Cu")
		(net 437)
	)
	(segment
		(start 137.355 87.145)
		(end 137 87.5)
		(width 0.1)
		(layer "F.Cu")
		(net 437)
	)
	(segment
		(start 135.2 87.5)
		(end 137 87.5)
		(width 0.1)
		(layer "F.Cu")
		(net 437)
	)
	(segment
		(start 166.462 69.526999)
		(end 166.462 68.258)
		(width 0.1)
		(layer "F.Cu")
		(net 438)
	)
	(segment
		(start 166.462 68.258)
		(end 166.92 67.8)
		(width 0.1)
		(layer "F.Cu")
		(net 438)
	)
	(segment
		(start 164.5 69.513999)
		(end 164.513 69.526999)
		(width 0.1)
		(layer "F.Cu")
		(net 439)
	)
	(segment
		(start 164.5 68.4)
		(end 164.5 69.513999)
		(width 0.1)
		(layer "F.Cu")
		(net 439)
	)
	(via
		(at 164.5 68.4)
		(size 0.45)
		(drill 0.2)
		(layers "F.Cu" "B.Cu")
		(remove_unused_layers yes)
		(keep_end_layers yes)
		(zone_layer_connections)
		(net 439)
	)
	(segment
		(start 162.991867 69.02)
		(end 163.88 69.02)
		(width 0.1)
		(layer "B.Cu")
		(net 439)
	)
	(segment
		(start 163.88 69.02)
		(end 164.5 68.4)
		(width 0.1)
		(layer "B.Cu")
		(net 439)
	)
	(via
		(at 156.62 72.75)
		(size 0.45)
		(drill 0.2)
		(layers "F.Cu" "B.Cu")
		(remove_unused_layers yes)
		(keep_end_layers yes)
		(zone_layer_connections)
		(net 440)
	)
	(segment
		(start 158.1 71.625)
		(end 158.1 70.505)
		(width 0.1)
		(layer "B.Cu")
		(net 440)
	)
	(segment
		(start 156.625 72.75)
		(end 156.975 72.75)
		(width 0.1)
		(layer "B.Cu")
		(net 440)
	)
	(segment
		(start 156.975 72.75)
		(end 158.1 71.625)
		(width 0.1)
		(layer "B.Cu")
		(net 440)
	)
	(via
		(at 154.025 73.25)
		(size 0.45)
		(drill 0.2)
		(layers "F.Cu" "B.Cu")
		(remove_unused_layers yes)
		(keep_end_layers yes)
		(zone_layer_connections)
		(net 441)
	)
	(segment
		(start 156.446811 72.201)
		(end 156.811811 72.201)
		(width 0.1)
		(layer "B.Cu")
		(net 441)
	)
	(segment
		(start 154.03 73.25)
		(end 155.032811 73.25)
		(width 0.1)
		(layer "B.Cu")
		(net 441)
	)
	(segment
		(start 155.865 72.782811)
		(end 156.446811 72.201)
		(width 0.1)
		(layer "B.Cu")
		(net 441)
	)
	(segment
		(start 155.032811 73.25)
		(end 155.5 72.782811)
		(width 0.1)
		(layer "B.Cu")
		(net 441)
	)
	(segment
		(start 155.5 72.782811)
		(end 155.865 72.782811)
		(width 0.1)
		(layer "B.Cu")
		(net 441)
	)
	(segment
		(start 156.811811 72.201)
		(end 157.1 71.912811)
		(width 0.1)
		(layer "B.Cu")
		(net 441)
	)
	(segment
		(start 157.1 71.912811)
		(end 157.1 70.505)
		(width 0.1)
		(layer "B.Cu")
		(net 441)
	)
	(via
		(at 154.025 71.25)
		(size 0.45)
		(drill 0.2)
		(layers "F.Cu" "B.Cu")
		(remove_unused_layers yes)
		(keep_end_layers yes)
		(zone_layer_connections)
		(net 442)
	)
	(segment
		(start 154.355 71.25)
		(end 154.03 71.25)
		(width 0.1)
		(layer "B.Cu")
		(net 442)
	)
	(segment
		(start 155.1 70.505)
		(end 154.355 71.25)
		(width 0.1)
		(layer "B.Cu")
		(net 442)
	)
	(via
		(at 154.025 72.25)
		(size 0.45)
		(drill 0.2)
		(layers "F.Cu" "B.Cu")
		(remove_unused_layers yes)
		(keep_end_layers yes)
		(zone_layer_connections)
		(net 443)
	)
	(segment
		(start 154.03 72.25)
		(end 155.032811 72.25)
		(width 0.1)
		(layer "B.Cu")
		(net 443)
	)
	(segment
		(start 155.032811 72.25)
		(end 155.581811 71.701)
		(width 0.1)
		(layer "B.Cu")
		(net 443)
	)
	(segment
		(start 156.211 71.436811)
		(end 156.211 70.616)
		(width 0.1)
		(layer "B.Cu")
		(net 443)
	)
	(segment
		(start 155.581811 71.701)
		(end 155.946811 71.701)
		(width 0.1)
		(layer "B.Cu")
		(net 443)
	)
	(segment
		(start 155.946811 71.701)
		(end 156.211 71.436811)
		(width 0.1)
		(layer "B.Cu")
		(net 443)
	)
	(segment
		(start 156.211 70.616)
		(end 156.1 70.505)
		(width 0.1)
		(layer "B.Cu")
		(net 443)
	)
	(via
		(at 148.835 90.25)
		(size 0.45)
		(drill 0.2)
		(layers "F.Cu" "B.Cu")
		(remove_unused_layers yes)
		(keep_end_layers yes)
		(zone_layer_connections)
		(net 444)
	)
	(segment
		(start 151.2 87)
		(end 150.5 87)
		(width 0.1)
		(layer "B.Cu")
		(net 444)
	)
	(segment
		(start 149.95 84.925)
		(end 148.905 84.925)
		(width 0.1)
		(layer "B.Cu")
		(net 444)
	)
	(segment
		(start 150.5 87)
		(end 150.5 85.475)
		(width 0.1)
		(layer "B.Cu")
		(net 444)
	)
	(segment
		(start 150.5 85.475)
		(end 149.95 84.925)
		(width 0.1)
		(layer "B.Cu")
		(net 444)
	)
	(segment
		(start 148.835 89.49)
		(end 150.5 87.825)
		(width 0.1)
		(layer "B.Cu")
		(net 444)
	)
	(segment
		(start 148.835 90.25)
		(end 148.835 89.49)
		(width 0.1)
		(layer "B.Cu")
		(net 444)
	)
	(segment
		(start 150.5 87.825)
		(end 150.5 87)
		(width 0.1)
		(layer "B.Cu")
		(net 444)
	)
	(via
		(at 147.97 90.75)
		(size 0.45)
		(drill 0.2)
		(layers "F.Cu" "B.Cu")
		(remove_unused_layers yes)
		(keep_end_layers yes)
		(zone_layer_connections)
		(net 445)
	)
	(segment
		(start 148.425 89.475)
		(end 149.775 88.125)
		(width 0.1)
		(layer "B.Cu")
		(net 445)
	)
	(segment
		(start 148.22 91)
		(end 147.97 90.75)
		(width 0.1)
		(layer "B.Cu")
		(net 445)
	)
	(segment
		(start 148.9 91)
		(end 148.22 91)
		(width 0.1)
		(layer "B.Cu")
		(net 445)
	)
	(segment
		(start 149.775 88.125)
		(end 149.775 86.175)
		(width 0.1)
		(layer "B.Cu")
		(net 445)
	)
	(segment
		(start 149.525 85.925)
		(end 148.905 85.925)
		(width 0.1)
		(layer "B.Cu")
		(net 445)
	)
	(segment
		(start 148.425 90.295)
		(end 148.425 89.475)
		(width 0.1)
		(layer "B.Cu")
		(net 445)
	)
	(segment
		(start 147.97 90.75)
		(end 148.425 90.295)
		(width 0.1)
		(layer "B.Cu")
		(net 445)
	)
	(segment
		(start 149.775 86.175)
		(end 149.525 85.925)
		(width 0.1)
		(layer "B.Cu")
		(net 445)
	)
	(segment
		(start 137.52 70.2)
		(end 136.6 70.2)
		(width 0.1)
		(layer "F.Cu")
		(net 446)
	)
	(segment
		(start 116.51 72.87)
		(end 117.48 71.9)
		(width 0.1)
		(layer "F.Cu")
		(net 446)
	)
	(segment
		(start 116.51 72.9)
		(end 116.51 72.87)
		(width 0.1)
		(layer "F.Cu")
		(net 446)
	)
	(segment
		(start 115.8 72.9)
		(end 116.51 72.9)
		(width 0.1)
		(layer "F.Cu")
		(net 446)
	)
	(via
		(at 115.8 72.9)
		(size 0.45)
		(drill 0.2)
		(layers "F.Cu" "B.Cu")
		(remove_unused_layers yes)
		(keep_end_layers yes)
		(zone_layer_connections)
		(net 446)
	)
	(via
		(at 136.6 70.2)
		(size 0.45)
		(drill 0.2)
		(layers "F.Cu" "B.Cu")
		(remove_unused_layers yes)
		(keep_end_layers yes)
		(zone_layer_connections)
		(net 446)
	)
	(segment
		(start 135.3 70.2)
		(end 136.6 70.2)
		(width 0.1)
		(layer "In5.Cu")
		(net 446)
	)
	(segment
		(start 115.8 72.9)
		(end 120.3 72.9)
		(width 0.1)
		(layer "In5.Cu")
		(net 446)
	)
	(segment
		(start 129 76.5)
		(end 135.3 70.2)
		(width 0.1)
		(layer "In5.Cu")
		(net 446)
	)
	(segment
		(start 123.9 76.5)
		(end 129 76.5)
		(width 0.1)
		(layer "In5.Cu")
		(net 446)
	)
	(segment
		(start 120.3 72.9)
		(end 123.9 76.5)
		(width 0.1)
		(layer "In5.Cu")
		(net 446)
	)
	(segment
		(start 123.9 125.79)
		(end 123.785 125.905)
		(width 0.1)
		(layer "F.Cu")
		(net 595)
	)
	(segment
		(start 123.175 126.02)
		(end 123.175 126.015)
		(width 0.1)
		(layer "F.Cu")
		(net 595)
	)
	(segment
		(start 123.175 126.015)
		(end 123.125 125.965)
		(width 0.1)
		(layer "F.Cu")
		(net 595)
	)
	(segment
		(start 123.125 125.965)
		(end 121.957488 125.965)
		(width 0.19)
		(layer "F.Cu")
		(net 595)
	)
	(segment
		(start 119.5 126.325)
		(end 119.65 126.175)
		(width 0.19)
		(layer "F.Cu")
		(net 595)
	)
	(segment
		(start 123.507366 126.02)
		(end 123.175 126.02)
		(width 0.1)
		(layer "F.Cu")
		(net 595)
	)
	(segment
		(start 119.65 126.175)
		(end 121.747488 126.175)
		(width 0.19)
		(layer "F.Cu")
		(net 595)
	)
	(segment
		(start 121.957488 125.965)
		(end 121.747488 126.175)
		(width 0.19)
		(layer "F.Cu")
		(net 595)
	)
	(segment
		(start 136.4 81.425)
		(end 137.17 81.425)
		(width 0.19)
		(layer "F.Cu")
		(net 595)
	)
	(segment
		(start 136.25 81.575)
		(end 136.4 81.425)
		(width 0.19)
		(layer "F.Cu")
		(net 595)
	)
	(segment
		(start 137.495 81.75)
		(end 137.52 81.75)
		(width 0.19)
		(layer "F.Cu")
		(net 595)
	)
	(segment
		(start 137.17 81.425)
		(end 137.495 81.75)
		(width 0.19)
		(layer "F.Cu")
		(net 595)
	)
	(via
		(at 136.25 81.575)
		(size 0.45)
		(drill 0.2)
		(layers "F.Cu" "B.Cu")
		(remove_unused_layers yes)
		(keep_end_layers yes)
		(zone_layer_connections)
		(net 595)
	)
	(via
		(at 119.5 126.325)
		(size 0.45)
		(drill 0.2)
		(layers "F.Cu" "B.Cu")
		(remove_unused_layers yes)
		(keep_end_layers yes)
		(zone_layer_connections)
		(net 595)
	)
	(arc
		(start 123.785 125.905)
		(mid 123.657621 125.990112)
		(end 123.507366 126.02)
		(width 0.1)
		(layer "F.Cu")
		(net 595)
	)
	(segment
		(start 121.972488 126.175)
		(end 122.875 125.272488)
		(width 0.19)
		(layer "B.Cu")
		(net 595)
	)
	(segment
		(start 135.447488 81.425)
		(end 136.1 81.425)
		(width 0.19)
		(layer "B.Cu")
		(net 595)
	)
	(segment
		(start 135.199999 81.672489)
		(end 135.447488 81.425)
		(width 0.19)
		(layer "B.Cu")
		(net 595)
	)
	(segment
		(start 134.047488 97.8)
		(end 136.2 97.8)
		(width 0.19)
		(layer "B.Cu")
		(net 595)
	)
	(segment
		(start 119.5 126.325)
		(end 119.65 126.175)
		(width 0.19)
		(layer "B.Cu")
		(net 595)
	)
	(segment
		(start 130.797489 101.049999)
		(end 134.047488 97.8)
		(width 0.19)
		(layer "B.Cu")
		(net 595)
	)
	(segment
		(start 122.875 119.072488)
		(end 124.575 117.372488)
		(width 0.19)
		(layer "B.Cu")
		(net 595)
	)
	(segment
		(start 124.575 117.372488)
		(end 124.575 110.983832)
		(width 0.19)
		(layer "B.Cu")
		(net 595)
	)
	(segment
		(start 127.050001 101.049999)
		(end 130.797489 101.049999)
		(width 0.19)
		(layer "B.Cu")
		(net 595)
	)
	(segment
		(start 137.702512 96.297488)
		(end 137.702512 91.207538)
		(width 0.19)
		(layer "B.Cu")
		(net 595)
	)
	(segment
		(start 123.6 110.008832)
		(end 123.6 104.5)
		(width 0.19)
		(layer "B.Cu")
		(net 595)
	)
	(segment
		(start 122.875 125.272488)
		(end 122.875 119.072488)
		(width 0.19)
		(layer "B.Cu")
		(net 595)
	)
	(segment
		(start 137.702512 91.207538)
		(end 135.199999 88.705025)
		(width 0.19)
		(layer "B.Cu")
		(net 595)
	)
	(segment
		(start 135.199999 88.705025)
		(end 135.199999 81.672489)
		(width 0.19)
		(layer "B.Cu")
		(net 595)
	)
	(segment
		(start 136.2 97.8)
		(end 137.702512 96.297488)
		(width 0.19)
		(layer "B.Cu")
		(net 595)
	)
	(segment
		(start 119.65 126.175)
		(end 121.972488 126.175)
		(width 0.19)
		(layer "B.Cu")
		(net 595)
	)
	(segment
		(start 136.1 81.425)
		(end 136.25 81.575)
		(width 0.19)
		(layer "B.Cu")
		(net 595)
	)
	(segment
		(start 124.575 110.983832)
		(end 123.6 110.008832)
		(width 0.19)
		(layer "B.Cu")
		(net 595)
	)
	(segment
		(start 123.6 104.5)
		(end 127.050001 101.049999)
		(width 0.19)
		(layer "B.Cu")
		(net 595)
	)
	(segment
		(start 122.75 118.727512)
		(end 120.847488 116.825)
		(width 0.19)
		(layer "F.Cu")
		(net 596)
	)
	(segment
		(start 119.65 116.825)
		(end 119.5 116.675)
		(width 0.19)
		(layer "F.Cu")
		(net 596)
	)
	(segment
		(start 137.17 72.575)
		(end 137.495 72.25)
		(width 0.19)
		(layer "F.Cu")
		(net 596)
	)
	(segment
		(start 123.625 120.142426)
		(end 123.625 120.167573)
		(width 0.1)
		(layer "F.Cu")
		(net 596)
	)
	(segment
		(start 122.987488 120.04)
		(end 123.522574 120.04)
		(width 0.1)
		(layer "F.Cu")
		(net 596)
	)
	(segment
		(start 123.522574 120.27)
		(end 123.44 120.27)
		(width 0.1)
		(layer "F.Cu")
		(net 596)
	)
	(segment
		(start 122.75 119.802512)
		(end 122.75 118.727512)
		(width 0.19)
		(layer "F.Cu")
		(net 596)
	)
	(segment
		(start 136.405 72.575)
		(end 137.17 72.575)
		(width 0.19)
		(layer "F.Cu")
		(net 596)
	)
	(segment
		(start 120.847488 116.825)
		(end 119.65 116.825)
		(width 0.19)
		(layer "F.Cu")
		(net 596)
	)
	(segment
		(start 137.495 72.25)
		(end 137.52 72.25)
		(width 0.19)
		(layer "F.Cu")
		(net 596)
	)
	(segment
		(start 136.255 72.425)
		(end 136.405 72.575)
		(width 0.19)
		(layer "F.Cu")
		(net 596)
	)
	(segment
		(start 122.987488 120.04)
		(end 122.75 119.802512)
		(width 0.19)
		(layer "F.Cu")
		(net 596)
	)
	(via
		(at 119.5 116.675)
		(size 0.45)
		(drill 0.2)
		(layers "F.Cu" "B.Cu")
		(remove_unused_layers yes)
		(keep_end_layers yes)
		(zone_layer_connections)
		(net 596)
	)
	(via
		(at 136.255 72.425)
		(size 0.45)
		(drill 0.2)
		(layers "F.Cu" "B.Cu")
		(remove_unused_layers yes)
		(keep_end_layers yes)
		(zone_layer_connections)
		(net 596)
	)
	(arc
		(start 123.595 120.24)
		(mid 123.561771 120.262203)
		(end 123.522574 120.27)
		(width 0.1)
		(layer "F.Cu")
		(net 596)
	)
	(arc
		(start 123.625 120.142426)
		(mid 123.617204 120.103229)
		(end 123.595 120.07)
		(width 0.1)
		(layer "F.Cu")
		(net 596)
	)
	(arc
		(start 123.595 120.07)
		(mid 123.561771 120.047796)
		(end 123.522574 120.04)
		(width 0.1)
		(layer "F.Cu")
		(net 596)
	)
	(arc
		(start 123.595 120.24)
		(mid 123.617204 120.20677)
		(end 123.625 120.167573)
		(width 0.1)
		(layer "F.Cu")
		(net 596)
	)
	(segment
		(start 119.5 116.675)
		(end 119.65 116.825)
		(width 0.19)
		(layer "B.Cu")
		(net 596)
	)
	(segment
		(start 130.5 83.472488)
		(end 130.225 83.197488)
		(width 0.19)
		(layer "B.Cu")
		(net 596)
	)
	(segment
		(start 120.625 116.427512)
		(end 120.625 112.619974)
		(width 0.19)
		(layer "B.Cu")
		(net 596)
	)
	(segment
		(start 130.225 83.197488)
		(end 130.225 76.927512)
		(width 0.19)
		(layer "B.Cu")
		(net 596)
	)
	(segment
		(start 119.65 116.825)
		(end 120.227512 116.825)
		(width 0.19)
		(layer "B.Cu")
		(net 596)
	)
	(segment
		(start 120.227512 116.825)
		(end 120.625 116.427512)
		(width 0.19)
		(layer "B.Cu")
		(net 596)
	)
	(segment
		(start 130.5 91.052513)
		(end 130.5 83.472488)
		(width 0.19)
		(layer "B.Cu")
		(net 596)
	)
	(segment
		(start 136.105 72.575)
		(end 136.255 72.425)
		(width 0.19)
		(layer "B.Cu")
		(net 596)
	)
	(segment
		(start 121.827512 96.725)
		(end 124.827513 96.725)
		(width 0.19)
		(layer "B.Cu")
		(net 596)
	)
	(segment
		(start 119.550001 99.002511)
		(end 121.827512 96.725)
		(width 0.19)
		(layer "B.Cu")
		(net 596)
	)
	(segment
		(start 134.577512 72.575)
		(end 136.105 72.575)
		(width 0.19)
		(layer "B.Cu")
		(net 596)
	)
	(segment
		(start 124.827513 96.725)
		(end 130.5 91.052513)
		(width 0.19)
		(layer "B.Cu")
		(net 596)
	)
	(segment
		(start 130.225 76.927512)
		(end 134.577512 72.575)
		(width 0.19)
		(layer "B.Cu")
		(net 596)
	)
	(segment
		(start 120.625 112.619974)
		(end 119.550001 111.544975)
		(width 0.19)
		(layer "B.Cu")
		(net 596)
	)
	(segment
		(start 119.550001 111.544975)
		(end 119.550001 99.002511)
		(width 0.19)
		(layer "B.Cu")
		(net 596)
	)
	(segment
		(start 137.495 73.25)
		(end 137.52 73.25)
		(width 0.19)
		(layer "F.Cu")
		(net 597)
	)
	(segment
		(start 122.952512 120.5)
		(end 122.4 119.947488)
		(width 0.19)
		(layer "F.Cu")
		(net 597)
	)
	(segment
		(start 136.405 72.925)
		(end 137.17 72.925)
		(width 0.19)
		(layer "F.Cu")
		(net 597)
	)
	(segment
		(start 136.255 73.075)
		(end 136.405 72.925)
		(width 0.19)
		(layer "F.Cu")
		(net 597)
	)
	(segment
		(start 122.952512 120.5)
		(end 123.507366 120.5)
		(width 0.1)
		(layer "F.Cu")
		(net 597)
	)
	(segment
		(start 122.4 119.947488)
		(end 122.4 118.872488)
		(width 0.19)
		(layer "F.Cu")
		(net 597)
	)
	(segment
		(start 122.4 118.872488)
		(end 120.702512 117.175)
		(width 0.19)
		(layer "F.Cu")
		(net 597)
	)
	(segment
		(start 119.65 117.175)
		(end 119.5 117.325)
		(width 0.19)
		(layer "F.Cu")
		(net 597)
	)
	(segment
		(start 120.702512 117.175)
		(end 119.65 117.175)
		(width 0.19)
		(layer "F.Cu")
		(net 597)
	)
	(segment
		(start 123.785 120.385)
		(end 123.9 120.27)
		(width 0.1)
		(layer "F.Cu")
		(net 597)
	)
	(segment
		(start 137.17 72.925)
		(end 137.495 73.25)
		(width 0.19)
		(layer "F.Cu")
		(net 597)
	)
	(via
		(at 136.255 73.075)
		(size 0.45)
		(drill 0.2)
		(layers "F.Cu" "B.Cu")
		(remove_unused_layers yes)
		(keep_end_layers yes)
		(zone_layer_connections)
		(net 597)
	)
	(via
		(at 119.5 117.325)
		(size 0.45)
		(drill 0.2)
		(layers "F.Cu" "B.Cu")
		(remove_unused_layers yes)
		(keep_end_layers yes)
		(zone_layer_connections)
		(net 597)
	)
	(arc
		(start 123.785 120.385)
		(mid 123.657621 120.470112)
		(end 123.507366 120.5)
		(width 0.1)
		(layer "F.Cu")
		(net 597)
	)
	(segment
		(start 130.575 83.052512)
		(end 130.575 77.072488)
		(width 0.19)
		(layer "B.Cu")
		(net 597)
	)
	(segment
		(start 120.975 116.572488)
		(end 120.975 112.475)
		(width 0.19)
		(layer "B.Cu")
		(net 597)
	)
	(segment
		(start 130.575 77.072488)
		(end 134.722488 72.925)
		(width 0.19)
		(layer "B.Cu")
		(net 597)
	)
	(segment
		(start 120.975 112.475)
		(end 119.9 111.4)
		(width 0.19)
		(layer "B.Cu")
		(net 597)
	)
	(segment
		(start 121.972488 97.075)
		(end 124.972487 97.075)
		(width 0.19)
		(layer "B.Cu")
		(net 597)
	)
	(segment
		(start 136.105 72.925)
		(end 136.255 73.075)
		(width 0.19)
		(layer "B.Cu")
		(net 597)
	)
	(segment
		(start 134.722488 72.925)
		(end 136.105 72.925)
		(width 0.19)
		(layer "B.Cu")
		(net 597)
	)
	(segment
		(start 124.972487 97.075)
		(end 130.85 91.197487)
		(width 0.19)
		(layer "B.Cu")
		(net 597)
	)
	(segment
		(start 119.65 117.175)
		(end 120.372488 117.175)
		(width 0.19)
		(layer "B.Cu")
		(net 597)
	)
	(segment
		(start 119.5 117.325)
		(end 119.65 117.175)
		(width 0.19)
		(layer "B.Cu")
		(net 597)
	)
	(segment
		(start 119.9 99.147488)
		(end 121.972488 97.075)
		(width 0.19)
		(layer "B.Cu")
		(net 597)
	)
	(segment
		(start 130.85 83.327512)
		(end 130.575 83.052512)
		(width 0.19)
		(layer "B.Cu")
		(net 597)
	)
	(segment
		(start 130.85 91.197487)
		(end 130.85 83.327512)
		(width 0.19)
		(layer "B.Cu")
		(net 597)
	)
	(segment
		(start 120.372488 117.175)
		(end 120.975 116.572488)
		(width 0.19)
		(layer "B.Cu")
		(net 597)
	)
	(segment
		(start 119.9 111.4)
		(end 119.9 99.147488)
		(width 0.19)
		(layer "B.Cu")
		(net 597)
	)
	(segment
		(start 136.255 78.575)
		(end 136.405 78.425)
		(width 0.19)
		(layer "F.Cu")
		(net 598)
	)
	(segment
		(start 136.405 78.425)
		(end 137.17 78.425)
		(width 0.19)
		(layer "F.Cu")
		(net 598)
	)
	(segment
		(start 123.9 123.95)
		(end 123.785 124.065)
		(width 0.1)
		(layer "F.Cu")
		(net 598)
	)
	(segment
		(start 123.155 124.18)
		(end 123.08 124.18)
		(width 0.1)
		(layer "F.Cu")
		(net 598)
	)
	(segment
		(start 137.495 78.75)
		(end 137.52 78.75)
		(width 0.19)
		(layer "F.Cu")
		(net 598)
	)
	(segment
		(start 123.507366 124.18)
		(end 123.155 124.18)
		(width 0.1)
		(layer "F.Cu")
		(net 598)
	)
	(segment
		(start 137.17 78.425)
		(end 137.495 78.75)
		(width 0.19)
		(layer "F.Cu")
		(net 598)
	)
	(segment
		(start 123.08 124.18)
		(end 123.025 124.125)
		(width 0.1)
		(layer "F.Cu")
		(net 598)
	)
	(segment
		(start 119.5 123.325)
		(end 119.65 123.175)
		(width 0.19)
		(layer "F.Cu")
		(net 598)
	)
	(segment
		(start 119.65 123.175)
		(end 120.327512 123.175)
		(width 0.19)
		(layer "F.Cu")
		(net 598)
	)
	(segment
		(start 123.025 124.125)
		(end 121.277512 124.125)
		(width 0.19)
		(layer "F.Cu")
		(net 598)
	)
	(segment
		(start 120.327512 123.175)
		(end 121.277512 124.125)
		(width 0.19)
		(layer "F.Cu")
		(net 598)
	)
	(via
		(at 119.5 123.325)
		(size 0.45)
		(drill 0.2)
		(layers "F.Cu" "B.Cu")
		(remove_unused_layers yes)
		(keep_end_layers yes)
		(zone_layer_connections)
		(net 598)
	)
	(via
		(at 136.255 78.575)
		(size 0.45)
		(drill 0.2)
		(layers "F.Cu" "B.Cu")
		(remove_unused_layers yes)
		(keep_end_layers yes)
		(zone_layer_connections)
		(net 598)
	)
	(arc
		(start 123.785 124.065)
		(mid 123.657621 124.150112)
		(end 123.507366 124.18)
		(width 0.1)
		(layer "F.Cu")
		(net 598)
	)
	(segment
		(start 135.614213 96.385787)
		(end 136.2883 95.7117)
		(width 0.19)
		(layer "B.Cu")
		(net 598)
	)
	(segment
		(start 122.449999 103.952945)
		(end 127.352945 99.049999)
		(width 0.19)
		(layer "B.Cu")
		(net 598)
	)
	(segment
		(start 121.875 122.172488)
		(end 121.875 118.572488)
		(width 0.19)
		(layer "B.Cu")
		(net 598)
	)
	(segment
		(start 119.5 123.325)
		(end 119.65 123.175)
		(width 0.19)
		(layer "B.Cu")
		(net 598)
	)
	(segment
		(start 133.461701 96.385787)
		(end 135.614213 96.385787)
		(width 0.19)
		(layer "B.Cu")
		(net 598)
	)
	(segment
		(start 136.105 78.425)
		(end 136.255 78.575)
		(width 0.19)
		(layer "B.Cu")
		(net 598)
	)
	(segment
		(start 134.822488 78.425)
		(end 136.105 78.425)
		(width 0.19)
		(layer "B.Cu")
		(net 598)
	)
	(segment
		(start 120.872488 123.175)
		(end 121.875 122.172488)
		(width 0.19)
		(layer "B.Cu")
		(net 598)
	)
	(segment
		(start 136.2883 95.7117)
		(end 136.2883 91.793324)
		(width 0.19)
		(layer "B.Cu")
		(net 598)
	)
	(segment
		(start 130.797489 99.049999)
		(end 133.461701 96.385787)
		(width 0.19)
		(layer "B.Cu")
		(net 598)
	)
	(segment
		(start 122.449999 110.555887)
		(end 122.449999 103.952945)
		(width 0.19)
		(layer "B.Cu")
		(net 598)
	)
	(segment
		(start 127.352945 99.049999)
		(end 130.797489 99.049999)
		(width 0.19)
		(layer "B.Cu")
		(net 598)
	)
	(segment
		(start 123.375 111.480888)
		(end 122.449999 110.555887)
		(width 0.19)
		(layer "B.Cu")
		(net 598)
	)
	(segment
		(start 121.875 118.572488)
		(end 123.375 117.072488)
		(width 0.19)
		(layer "B.Cu")
		(net 598)
	)
	(segment
		(start 136.2883 91.793324)
		(end 133.65 89.155024)
		(width 0.19)
		(layer "B.Cu")
		(net 598)
	)
	(segment
		(start 133.65 89.155024)
		(end 133.65 79.597488)
		(width 0.19)
		(layer "B.Cu")
		(net 598)
	)
	(segment
		(start 119.65 123.175)
		(end 120.872488 123.175)
		(width 0.19)
		(layer "B.Cu")
		(net 598)
	)
	(segment
		(start 133.65 79.597488)
		(end 134.822488 78.425)
		(width 0.19)
		(layer "B.Cu")
		(net 598)
	)
	(segment
		(start 123.375 117.072488)
		(end 123.375 111.480888)
		(width 0.19)
		(layer "B.Cu")
		(net 598)
	)
	(segment
		(start 137.495 75.75)
		(end 137.52 75.75)
		(width 0.19)
		(layer "F.Cu")
		(net 599)
	)
	(segment
		(start 136.255 75.575)
		(end 136.405 75.425)
		(width 0.19)
		(layer "F.Cu")
		(net 599)
	)
	(segment
		(start 119.5 120.325)
		(end 119.65 120.175)
		(width 0.19)
		(layer "F.Cu")
		(net 599)
	)
	(segment
		(start 123.015 122.34)
		(end 122.975 122.3)
		(width 0.1)
		(layer "F.Cu")
		(net 599)
	)
	(segment
		(start 123.175 122.34)
		(end 123.015 122.34)
		(width 0.1)
		(layer "F.Cu")
		(net 599)
	)
	(segment
		(start 137.17 75.425)
		(end 137.495 75.75)
		(width 0.19)
		(layer "F.Cu")
		(net 599)
	)
	(segment
		(start 123.9 122.11)
		(end 123.785 122.225)
		(width 0.1)
		(layer "F.Cu")
		(net 599)
	)
	(segment
		(start 122.452512 122.3)
		(end 122.975 122.3)
		(width 0.19)
		(layer "F.Cu")
		(net 599)
	)
	(segment
		(start 136.405 75.425)
		(end 137.17 75.425)
		(width 0.19)
		(layer "F.Cu")
		(net 599)
	)
	(segment
		(start 120.327512 120.175)
		(end 122.452512 122.3)
		(width 0.19)
		(layer "F.Cu")
		(net 599)
	)
	(segment
		(start 119.65 120.175)
		(end 120.327512 120.175)
		(width 0.19)
		(layer "F.Cu")
		(net 599)
	)
	(segment
		(start 123.507366 122.34)
		(end 123.175 122.34)
		(width 0.1)
		(layer "F.Cu")
		(net 599)
	)
	(via
		(at 136.255 75.575)
		(size 0.45)
		(drill 0.2)
		(layers "F.Cu" "B.Cu")
		(remove_unused_layers yes)
		(keep_end_layers yes)
		(zone_layer_connections)
		(net 599)
	)
	(via
		(at 119.5 120.325)
		(size 0.45)
		(drill 0.2)
		(layers "F.Cu" "B.Cu")
		(remove_unused_layers yes)
		(keep_end_layers yes)
		(zone_layer_connections)
		(net 599)
	)
	(arc
		(start 123.785 122.225)
		(mid 123.657621 122.310112)
		(end 123.507366 122.34)
		(width 0.1)
		(layer "F.Cu")
		(net 599)
	)
	(segment
		(start 120.372488 120.175)
		(end 120.975 119.572488)
		(width 0.19)
		(layer "B.Cu")
		(net 599)
	)
	(segment
		(start 121.249999 103.197489)
		(end 128.675 95.772488)
		(width 0.19)
		(layer "B.Cu")
		(net 599)
	)
	(segment
		(start 128.675 95.222054)
		(end 132.25 91.647054)
		(width 0.19)
		(layer "B.Cu")
		(net 599)
	)
	(segment
		(start 121.249999 111.052943)
		(end 121.249999 103.197489)
		(width 0.19)
		(layer "B.Cu")
		(net 599)
	)
	(segment
		(start 122.175 111.977944)
		(end 121.249999 111.052943)
		(width 0.19)
		(layer "B.Cu")
		(net 599)
	)
	(segment
		(start 120.975 119.572488)
		(end 120.975 117.872488)
		(width 0.19)
		(layer "B.Cu")
		(net 599)
	)
	(segment
		(start 132.25 78.197488)
		(end 135.022488 75.425)
		(width 0.19)
		(layer "B.Cu")
		(net 599)
	)
	(segment
		(start 136.105 75.425)
		(end 136.255 75.575)
		(width 0.19)
		(layer "B.Cu")
		(net 599)
	)
	(segment
		(start 120.975 117.872488)
		(end 122.175 116.672488)
		(width 0.19)
		(layer "B.Cu")
		(net 599)
	)
	(segment
		(start 128.675 95.772488)
		(end 128.675 95.222054)
		(width 0.19)
		(layer "B.Cu")
		(net 599)
	)
	(segment
		(start 119.65 120.175)
		(end 120.372488 120.175)
		(width 0.19)
		(layer "B.Cu")
		(net 599)
	)
	(segment
		(start 122.175 116.672488)
		(end 122.175 111.977944)
		(width 0.19)
		(layer "B.Cu")
		(net 599)
	)
	(segment
		(start 119.5 120.325)
		(end 119.65 120.175)
		(width 0.19)
		(layer "B.Cu")
		(net 599)
	)
	(segment
		(start 132.25 91.647054)
		(end 132.25 78.197488)
		(width 0.19)
		(layer "B.Cu")
		(net 599)
	)
	(segment
		(start 135.022488 75.425)
		(end 136.105 75.425)
		(width 0.19)
		(layer "B.Cu")
		(net 599)
	)
	(segment
		(start 123.045 121.88)
		(end 123.522574 121.88)
		(width 0.1)
		(layer "F.Cu")
		(net 600)
	)
	(segment
		(start 119.65 119.825)
		(end 120.472488 119.825)
		(width 0.19)
		(layer "F.Cu")
		(net 600)
	)
	(segment
		(start 123.045 121.88)
		(end 122.975 121.95)
		(width 0.1)
		(layer "F.Cu")
		(net 600)
	)
	(segment
		(start 120.472488 119.825)
		(end 122.597488 121.95)
		(width 0.19)
		(layer "F.Cu")
		(net 600)
	)
	(segment
		(start 136.255 74.925)
		(end 136.405 75.075)
		(width 0.19)
		(layer "F.Cu")
		(net 600)
	)
	(segment
		(start 137.495 74.75)
		(end 137.52 74.75)
		(width 0.19)
		(layer "F.Cu")
		(net 600)
	)
	(segment
		(start 136.405 75.075)
		(end 137.17 75.075)
		(width 0.19)
		(layer "F.Cu")
		(net 600)
	)
	(segment
		(start 119.5 119.675)
		(end 119.65 119.825)
		(width 0.19)
		(layer "F.Cu")
		(net 600)
	)
	(segment
		(start 137.17 75.075)
		(end 137.495 74.75)
		(width 0.19)
		(layer "F.Cu")
		(net 600)
	)
	(segment
		(start 123.625 122.007573)
		(end 123.625 121.982426)
		(width 0.1)
		(layer "F.Cu")
		(net 600)
	)
	(segment
		(start 123.44 122.11)
		(end 123.522574 122.11)
		(width 0.1)
		(layer "F.Cu")
		(net 600)
	)
	(segment
		(start 122.597488 121.95)
		(end 122.975 121.95)
		(width 0.19)
		(layer "F.Cu")
		(net 600)
	)
	(via
		(at 119.5 119.675)
		(size 0.45)
		(drill 0.2)
		(layers "F.Cu" "B.Cu")
		(remove_unused_layers yes)
		(keep_end_layers yes)
		(zone_layer_connections)
		(net 600)
	)
	(via
		(at 136.255 74.925)
		(size 0.45)
		(drill 0.2)
		(layers "F.Cu" "B.Cu")
		(remove_unused_layers yes)
		(keep_end_layers yes)
		(zone_layer_connections)
		(net 600)
	)
	(arc
		(start 123.595 121.91)
		(mid 123.561771 121.887796)
		(end 123.522574 121.88)
		(width 0.1)
		(layer "F.Cu")
		(net 600)
	)
	(arc
		(start 123.625 121.982426)
		(mid 123.617204 121.943229)
		(end 123.595 121.91)
		(width 0.1)
		(layer "F.Cu")
		(net 600)
	)
	(arc
		(start 123.595 122.08)
		(mid 123.617204 122.04677)
		(end 123.625 122.007573)
		(width 0.1)
		(layer "F.Cu")
		(net 600)
	)
	(arc
		(start 123.522574 122.11)
		(mid 123.561771 122.102203)
		(end 123.595 122.08)
		(width 0.1)
		(layer "F.Cu")
		(net 600)
	)
	(segment
		(start 128.325 95.077082)
		(end 131.900001 91.502081)
		(width 0.19)
		(layer "B.Cu")
		(net 600)
	)
	(segment
		(start 119.5 119.675)
		(end 119.65 119.825)
		(width 0.19)
		(layer "B.Cu")
		(net 600)
	)
	(segment
		(start 134.877512 75.075)
		(end 136.105 75.075)
		(width 0.19)
		(layer "B.Cu")
		(net 600)
	)
	(segment
		(start 120.625 119.427512)
		(end 120.625 117.727512)
		(width 0.19)
		(layer "B.Cu")
		(net 600)
	)
	(segment
		(start 136.105 75.075)
		(end 136.255 74.925)
		(width 0.19)
		(layer "B.Cu")
		(net 600)
	)
	(segment
		(start 120.9 111.197918)
		(end 120.9 103.052512)
		(width 0.19)
		(layer "B.Cu")
		(net 600)
	)
	(segment
		(start 120.625 117.727512)
		(end 121.825 116.527512)
		(width 0.19)
		(layer "B.Cu")
		(net 600)
	)
	(segment
		(start 120.227512 119.825)
		(end 120.625 119.427512)
		(width 0.19)
		(layer "B.Cu")
		(net 600)
	)
	(segment
		(start 119.65 119.825)
		(end 120.227512 119.825)
		(width 0.19)
		(layer "B.Cu")
		(net 600)
	)
	(segment
		(start 121.825 116.527512)
		(end 121.825 112.122918)
		(width 0.19)
		(layer "B.Cu")
		(net 600)
	)
	(segment
		(start 121.825 112.122918)
		(end 120.9 111.197918)
		(width 0.19)
		(layer "B.Cu")
		(net 600)
	)
	(segment
		(start 128.325 95.627512)
		(end 128.325 95.077082)
		(width 0.19)
		(layer "B.Cu")
		(net 600)
	)
	(segment
		(start 131.900001 91.502081)
		(end 131.900001 78.052511)
		(width 0.19)
		(layer "B.Cu")
		(net 600)
	)
	(segment
		(start 120.9 103.052512)
		(end 128.325 95.627512)
		(width 0.19)
		(layer "B.Cu")
		(net 600)
	)
	(segment
		(start 131.900001 78.052511)
		(end 134.877512 75.075)
		(width 0.19)
		(layer "B.Cu")
		(net 600)
	)
	(segment
		(start 123.125 125.615)
		(end 121.812512 125.615)
		(width 0.19)
		(layer "F.Cu")
		(net 601)
	)
	(segment
		(start 136.25 80.925)
		(end 136.4 81.075)
		(width 0.19)
		(layer "F.Cu")
		(net 601)
	)
	(segment
		(start 123.175 125.565)
		(end 123.125 125.615)
		(width 0.1)
		(layer "F.Cu")
		(net 601)
	)
	(segment
		(start 137.495 80.75)
		(end 137.52 80.75)
		(width 0.19)
		(layer "F.Cu")
		(net 601)
	)
	(segment
		(start 123.44 125.79)
		(end 123.522574 125.79)
		(width 0.1)
		(layer "F.Cu")
		(net 601)
	)
	(segment
		(start 121.812512 125.615)
		(end 121.602512 125.825)
		(width 0.19)
		(layer "F.Cu")
		(net 601)
	)
	(segment
		(start 123.522574 125.56)
		(end 123.175 125.56)
		(width 0.1)
		(layer "F.Cu")
		(net 601)
	)
	(segment
		(start 123.175 125.56)
		(end 123.175 125.565)
		(width 0.1)
		(layer "F.Cu")
		(net 601)
	)
	(segment
		(start 119.5 125.675)
		(end 119.65 125.825)
		(width 0.19)
		(layer "F.Cu")
		(net 601)
	)
	(segment
		(start 136.4 81.075)
		(end 137.17 81.075)
		(width 0.19)
		(layer "F.Cu")
		(net 601)
	)
	(segment
		(start 137.17 81.075)
		(end 137.495 80.75)
		(width 0.19)
		(layer "F.Cu")
		(net 601)
	)
	(segment
		(start 119.65 125.825)
		(end 121.602512 125.825)
		(width 0.19)
		(layer "F.Cu")
		(net 601)
	)
	(segment
		(start 123.625 125.687573)
		(end 123.625 125.662426)
		(width 0.1)
		(layer "F.Cu")
		(net 601)
	)
	(via
		(at 119.5 125.675)
		(size 0.45)
		(drill 0.2)
		(layers "F.Cu" "B.Cu")
		(remove_unused_layers yes)
		(keep_end_layers yes)
		(zone_layer_connections)
		(net 601)
	)
	(via
		(at 136.25 80.925)
		(size 0.45)
		(drill 0.2)
		(layers "F.Cu" "B.Cu")
		(remove_unused_layers yes)
		(keep_end_layers yes)
		(zone_layer_connections)
		(net 601)
	)
	(arc
		(start 123.595 125.76)
		(mid 123.617204 125.72677)
		(end 123.625 125.687573)
		(width 0.1)
		(layer "F.Cu")
		(net 601)
	)
	(arc
		(start 123.595 125.59)
		(mid 123.561771 125.567796)
		(end 123.522574 125.56)
		(width 0.1)
		(layer "F.Cu")
		(net 601)
	)
	(arc
		(start 123.625 125.662426)
		(mid 123.617204 125.623229)
		(end 123.595 125.59)
		(width 0.1)
		(layer "F.Cu")
		(net 601)
	)
	(arc
		(start 123.522574 125.79)
		(mid 123.561771 125.782203)
		(end 123.595 125.76)
		(width 0.1)
		(layer "F.Cu")
		(net 601)
	)
	(segment
		(start 122.525 125.127512)
		(end 122.525 118.927512)
		(width 0.19)
		(layer "B.Cu")
		(net 601)
	)
	(segment
		(start 124.225 111.128806)
		(end 123.25 110.153806)
		(width 0.19)
		(layer "B.Cu")
		(net 601)
	)
	(segment
		(start 133.902512 97.45)
		(end 136.055024 97.45)
		(width 0.19)
		(layer "B.Cu")
		(net 601)
	)
	(segment
		(start 124.225 117.227512)
		(end 124.225 111.128806)
		(width 0.19)
		(layer "B.Cu")
		(net 601)
	)
	(segment
		(start 136.055024 97.45)
		(end 137.352512 96.152512)
		(width 0.19)
		(layer "B.Cu")
		(net 601)
	)
	(segment
		(start 137.352512 96.152512)
		(end 137.352512 91.352512)
		(width 0.19)
		(layer "B.Cu")
		(net 601)
	)
	(segment
		(start 134.85 88.85)
		(end 134.85 81.527512)
		(width 0.19)
		(layer "B.Cu")
		(net 601)
	)
	(segment
		(start 123.25 104.355026)
		(end 126.905026 100.7)
		(width 0.19)
		(layer "B.Cu")
		(net 601)
	)
	(segment
		(start 137.352512 91.352512)
		(end 134.85 88.85)
		(width 0.19)
		(layer "B.Cu")
		(net 601)
	)
	(segment
		(start 122.525 118.927512)
		(end 124.225 117.227512)
		(width 0.19)
		(layer "B.Cu")
		(net 601)
	)
	(segment
		(start 123.25 110.153806)
		(end 123.25 104.355026)
		(width 0.19)
		(layer "B.Cu")
		(net 601)
	)
	(segment
		(start 135.302512 81.075)
		(end 136.1 81.075)
		(width 0.19)
		(layer "B.Cu")
		(net 601)
	)
	(segment
		(start 136.1 81.075)
		(end 136.25 80.925)
		(width 0.19)
		(layer "B.Cu")
		(net 601)
	)
	(segment
		(start 134.85 81.527512)
		(end 135.302512 81.075)
		(width 0.19)
		(layer "B.Cu")
		(net 601)
	)
	(segment
		(start 119.65 125.825)
		(end 121.827512 125.825)
		(width 0.19)
		(layer "B.Cu")
		(net 601)
	)
	(segment
		(start 121.827512 125.825)
		(end 122.525 125.127512)
		(width 0.19)
		(layer "B.Cu")
		(net 601)
	)
	(segment
		(start 130.652512 100.7)
		(end 133.902512 97.45)
		(width 0.19)
		(layer "B.Cu")
		(net 601)
	)
	(segment
		(start 119.5 125.675)
		(end 119.65 125.825)
		(width 0.19)
		(layer "B.Cu")
		(net 601)
	)
	(segment
		(start 126.905026 100.7)
		(end 130.652512 100.7)
		(width 0.19)
		(layer "B.Cu")
		(net 601)
	)
	(segment
		(start 123.08 123.72)
		(end 123.025 123.775)
		(width 0.1)
		(layer "F.Cu")
		(net 602)
	)
	(segment
		(start 123.44 123.95)
		(end 123.522574 123.95)
		(width 0.1)
		(layer "F.Cu")
		(net 602)
	)
	(segment
		(start 136.405 78.075)
		(end 137.17 78.075)
		(width 0.19)
		(layer "F.Cu")
		(net 602)
	)
	(segment
		(start 119.5 122.675)
		(end 119.65 122.825)
		(width 0.19)
		(layer "F.Cu")
		(net 602)
	)
	(segment
		(start 123.025 123.775)
		(end 121.422488 123.775)
		(width 0.19)
		(layer "F.Cu")
		(net 602)
	)
	(segment
		(start 123.15 123.72)
		(end 123.08 123.72)
		(width 0.1)
		(layer "F.Cu")
		(net 602)
	)
	(segment
		(start 123.625 123.847573)
		(end 123.625 123.822426)
		(width 0.1)
		(layer "F.Cu")
		(net 602)
	)
	(segment
		(start 136.255 77.925)
		(end 136.405 78.075)
		(width 0.19)
		(layer "F.Cu")
		(net 602)
	)
	(segment
		(start 137.495 77.75)
		(end 137.52 77.75)
		(width 0.19)
		(layer "F.Cu")
		(net 602)
	)
	(segment
		(start 137.17 78.075)
		(end 137.495 77.75)
		(width 0.19)
		(layer "F.Cu")
		(net 602)
	)
	(segment
		(start 120.472488 122.825)
		(end 121.422488 123.775)
		(width 0.19)
		(layer "F.Cu")
		(net 602)
	)
	(segment
		(start 123.522574 123.72)
		(end 123.15 123.72)
		(width 0.1)
		(layer "F.Cu")
		(net 602)
	)
	(segment
		(start 119.65 122.825)
		(end 120.472488 122.825)
		(width 0.19)
		(layer "F.Cu")
		(net 602)
	)
	(via
		(at 136.255 77.925)
		(size 0.45)
		(drill 0.2)
		(layers "F.Cu" "B.Cu")
		(remove_unused_layers yes)
		(keep_end_layers yes)
		(zone_layer_connections)
		(net 602)
	)
	(via
		(at 119.5 122.675)
		(size 0.45)
		(drill 0.2)
		(layers "F.Cu" "B.Cu")
		(remove_unused_layers yes)
		(keep_end_layers yes)
		(zone_layer_connections)
		(net 602)
	)
	(arc
		(start 123.625 123.822426)
		(mid 123.617204 123.783229)
		(end 123.595 123.75)
		(width 0.1)
		(layer "F.Cu")
		(net 602)
	)
	(arc
		(start 123.522574 123.95)
		(mid 123.561771 123.942203)
		(end 123.595 123.92)
		(width 0.1)
		(layer "F.Cu")
		(net 602)
	)
	(arc
		(start 123.595 123.75)
		(mid 123.561771 123.727796)
		(end 123.522574 123.72)
		(width 0.1)
		(layer "F.Cu")
		(net 602)
	)
	(arc
		(start 123.595 123.92)
		(mid 123.617204 123.88677)
		(end 123.625 123.847573)
		(width 0.1)
		(layer "F.Cu")
		(net 602)
	)
	(segment
		(start 135.938299 91.938299)
		(end 133.299999 89.299999)
		(width 0.19)
		(layer "B.Cu")
		(net 602)
	)
	(segment
		(start 133.299999 79.452513)
		(end 134.677512 78.075)
		(width 0.19)
		(layer "B.Cu")
		(net 602)
	)
	(segment
		(start 130.652512 98.7)
		(end 133.316726 96.035786)
		(width 0.19)
		(layer "B.Cu")
		(net 602)
	)
	(segment
		(start 133.316726 96.035786)
		(end 135.469238 96.035786)
		(width 0.19)
		(layer "B.Cu")
		(net 602)
	)
	(segment
		(start 123.025 111.625862)
		(end 122.1 110.700862)
		(width 0.19)
		(layer "B.Cu")
		(net 602)
	)
	(segment
		(start 135.469238 96.035786)
		(end 135.938299 95.566725)
		(width 0.19)
		(layer "B.Cu")
		(net 602)
	)
	(segment
		(start 119.65 122.825)
		(end 120.727512 122.825)
		(width 0.19)
		(layer "B.Cu")
		(net 602)
	)
	(segment
		(start 121.525 122.027512)
		(end 121.525 118.427512)
		(width 0.19)
		(layer "B.Cu")
		(net 602)
	)
	(segment
		(start 122.1 110.700862)
		(end 122.1 103.80797)
		(width 0.19)
		(layer "B.Cu")
		(net 602)
	)
	(segment
		(start 121.525 118.427512)
		(end 123.025 116.927512)
		(width 0.19)
		(layer "B.Cu")
		(net 602)
	)
	(segment
		(start 134.677512 78.075)
		(end 136.105 78.075)
		(width 0.19)
		(layer "B.Cu")
		(net 602)
	)
	(segment
		(start 119.5 122.675)
		(end 119.65 122.825)
		(width 0.19)
		(layer "B.Cu")
		(net 602)
	)
	(segment
		(start 127.20797 98.7)
		(end 130.652512 98.7)
		(width 0.19)
		(layer "B.Cu")
		(net 602)
	)
	(segment
		(start 120.727512 122.825)
		(end 121.525 122.027512)
		(width 0.19)
		(layer "B.Cu")
		(net 602)
	)
	(segment
		(start 123.025 116.927512)
		(end 123.025 111.625862)
		(width 0.19)
		(layer "B.Cu")
		(net 602)
	)
	(segment
		(start 136.105 78.075)
		(end 136.255 77.925)
		(width 0.19)
		(layer "B.Cu")
		(net 602)
	)
	(segment
		(start 135.938299 95.566725)
		(end 135.938299 91.938299)
		(width 0.19)
		(layer "B.Cu")
		(net 602)
	)
	(segment
		(start 133.299999 89.299999)
		(end 133.299999 79.452513)
		(width 0.19)
		(layer "B.Cu")
		(net 602)
	)
	(segment
		(start 122.1 103.80797)
		(end 127.20797 98.7)
		(width 0.19)
		(layer "B.Cu")
		(net 602)
	)
	(zone
		(net 40)
		(net_name "+5V")
		(layer "F.Cu")
		(hatch edge 0.5)
		(priority 7)
		(connect_pads yes
			(clearance 0.15)
		)
		(min_thickness 0.25)
		(filled_areas_thickness no)
		(fill yes
			(thermal_gap 0.5)
			(thermal_bridge_width 0.5)
			(smoothing fillet)
			(radius 0.2)
		)
		(polygon
			(pts
				(xy 162.7 109.979997) (xy 162.699999 115.004997) (xy 164.249999 115.004998) (xy 164.249999 111.304996)
				(xy 163.599999 110.654996) (xy 163.599999 109.979997)
			)
		)
	)
	(zone
		(net 6)
		(net_name "DVDD")
		(layer "F.Cu")
		(hatch edge 0.5)
		(priority 39)
		(connect_pads yes
			(clearance 0.15)
		)
		(min_thickness 0.15)
		(filled_areas_thickness no)
		(fill yes
			(thermal_gap 0.5)
			(thermal_bridge_width 0.5)
			(smoothing fillet)
			(radius 0.2)
		)
		(polygon
			(pts
				(xy 142.15 102.849998) (xy 143.4 102.849998) (xy 143.4 101.649998) (xy 145.05 101.649998) (xy 145.05 99.749998)
				(xy 141.05 99.749998) (xy 141.05 102.549998) (xy 142.15 102.549998)
			)
		)
	)
	(zone
		(net 399)
		(net_name "Net-(D4-A)")
		(layer "F.Cu")
		(hatch edge 0.5)
		(priority 55)
		(connect_pads yes
			(clearance 0.1)
		)
		(min_thickness 0.1)
		(filled_areas_thickness no)
		(fill yes
			(thermal_gap 0.5)
			(thermal_bridge_width 0.5)
		)
		(polygon
			(pts
				(xy 121.8 107) (xy 121.8 108.6) (xy 124.2 108.6) (xy 124.2 99.2) (xy 122.65 96) (xy 121.2 96) (xy 121.2 101)
				(xy 122.2 101) (xy 122.2 107)
			)
		)
	)
	(zone
		(net 426)
		(net_name "Net-(L2-Pad1)")
		(layer "F.Cu")
		(hatch edge 0.5)
		(priority 3)
		(connect_pads yes
			(clearance 0.1)
		)
		(min_thickness 0.1)
		(filled_areas_thickness no)
		(fill yes
			(thermal_gap 0.5)
			(thermal_bridge_width 0.5)
		)
		(polygon
			(pts
				(xy 132.9 128.3) (xy 134.399391 128.3) (xy 137.3 127.7) (xy 139.7 127.7) (xy 139.7 125.5) (xy 137.3 125.5)
				(xy 134.4 127.5) (xy 132.9 127.5)
			)
		)
	)
	(zone
		(net 40)
		(net_name "+5V")
		(layer "F.Cu")
		(hatch edge 0.5)
		(priority 49)
		(connect_pads yes
			(clearance 0.15)
		)
		(min_thickness 0.25)
		(filled_areas_thickness no)
		(fill yes
			(thermal_gap 0.5)
			(thermal_bridge_width 0.5)
			(smoothing fillet)
			(radius 0.2)
		)
		(polygon
			(pts
				(xy 128.8 96.2) (xy 134.2 96.2) (xy 134.2 97.6) (xy 132.8 97.6) (xy 132.8 98.4) (xy 131.4 98.4)
				(xy 131 98) (xy 128.8 98)
			)
		)
	)
	(zone
		(net 23)
		(net_name "GND")
		(layer "F.Cu")
		(hatch edge 0.5)
		(priority 17)
		(connect_pads yes
			(clearance 0.15)
		)
		(min_thickness 0.25)
		(filled_areas_thickness no)
		(fill yes
			(thermal_gap 0.5)
			(thermal_bridge_width 0.5)
			(smoothing fillet)
			(radius 0.2)
		)
		(polygon
			(pts
				(xy 134.449988 107.229998) (xy 137.100001 107.229998) (xy 137.100001 105.669998) (xy 134.449989 105.669998)
			)
		)
	)
	(zone
		(net 182)
		(net_name "VBUS")
		(layer "F.Cu")
		(hatch edge 0.5)
		(priority 1)
		(connect_pads yes
			(clearance 0.1)
		)
		(min_thickness 0.1)
		(filled_areas_thickness no)
		(fill yes
			(thermal_gap 0.5)
			(thermal_bridge_width 0.5)
		)
		(polygon
			(pts
				(xy 129.25 137.5) (xy 131 137.5) (xy 131 141) (xy 132.75 141) (xy 132.8 140.95) (xy 132.8 139.75)
				(xy 134.25 139.75) (xy 134.25 141.75) (xy 129.25 141.75)
			)
		)
	)
	(zone
		(net 53)
		(net_name "+5V_USB")
		(layer "F.Cu")
		(hatch edge 0.5)
		(priority 36)
		(connect_pads yes
			(clearance 0)
		)
		(min_thickness 0.25)
		(filled_areas_thickness no)
		(fill yes
			(thermal_gap 0.5)
			(thermal_bridge_width 0.5)
		)
		(polygon
			(pts
				(xy 132.75 61.5) (xy 136.5 61.5) (xy 136.5 64.5) (xy 132.75 64.5)
			)
		)
	)
	(zone
		(net 23)
		(net_name "GND")
		(layer "F.Cu")
		(hatch edge 0.5)
		(priority 48)
		(connect_pads yes
			(clearance 0.15)
		)
		(min_thickness 0.25)
		(filled_areas_thickness no)
		(fill yes
			(thermal_gap 0.5)
			(thermal_bridge_width 0.5)
			(smoothing fillet)
			(radius 0.2)
		)
		(polygon
			(pts
				(xy 131.3 90.8) (xy 131.265745 94.6) (xy 128.8 94.6) (xy 128.8 96.1) (xy 132.7 96.1) (xy 133.000002 95.799998)
				(xy 134.2 95.799998) (xy 134.2 95.3) (xy 132.9 95.3) (xy 132.9 94.7) (xy 132.2 94.7) (xy 132.2 93.2)
				(xy 135.2 93.2) (xy 135.2 90.8) (xy 133 90.8)
			)
		)
	)
	(zone
		(net 5)
		(net_name "P0_AVDDL")
		(layer "F.Cu")
		(hatch edge 0.5)
		(priority 23)
		(connect_pads yes
			(clearance 0.15)
		)
		(min_thickness 0.25)
		(filled_areas_thickness no)
		(fill yes
			(thermal_gap 0.5)
			(thermal_bridge_width 0.5)
			(smoothing fillet)
			(radius 0.2)
		)
		(polygon
			(pts
				(xy 160.7 99.075) (xy 160.7 98.325) (xy 161.3 97.725) (xy 161.3 92.975) (xy 159.5 92.975) (xy 159.5 99.075)
			)
		)
	)
	(zone
		(net 21)
		(net_name "XFI_PVDD")
		(layer "F.Cu")
		(hatch edge 0.5)
		(priority 34)
		(connect_pads yes
			(clearance 0.15)
		)
		(min_thickness 0.15)
		(filled_areas_thickness no)
		(fill yes
			(thermal_gap 0.5)
			(thermal_bridge_width 0.5)
			(smoothing fillet)
			(radius 0.2)
		)
		(polygon
			(pts
				(xy 155.995 96.075) (xy 155.995 94.775) (xy 154.645 94.775) (xy 154.645 92.125) (xy 153.395 92.125)
				(xy 153.395 96.075)
			)
		)
	)
	(zone
		(net 215)
		(net_name "/USB-C connector/VBUS")
		(layer "F.Cu")
		(hatch edge 0.5)
		(priority 30)
		(connect_pads yes
			(clearance 0.125)
		)
		(min_thickness 0.125)
		(filled_areas_thickness no)
		(fill yes
			(thermal_gap 0.5)
			(thermal_bridge_width 0.5)
		)
		(polygon
			(pts
				(xy 118 143.3) (xy 119.4 143.3) (xy 119.4 146.8) (xy 118 146.8)
			)
		)
	)
	(zone
		(net 53)
		(net_name "+5V_USB")
		(layer "F.Cu")
		(hatch edge 0.5)
		(priority 60)
		(connect_pads yes
			(clearance 0.1)
		)
		(min_thickness 0.1)
		(filled_areas_thickness no)
		(fill yes
			(thermal_gap 0.5)
			(thermal_bridge_width 0.5)
		)
		(polygon
			(pts
				(xy 115.8 111.2) (xy 115.8 112.6) (xy 117.8 112.6) (xy 117.8 111.2)
			)
		)
	)
	(zone
		(net 1)
		(net_name "VCCA")
		(layer "F.Cu")
		(hatch edge 0.5)
		(priority 3)
		(connect_pads yes
			(clearance 0.15)
		)
		(min_thickness 0.25)
		(filled_areas_thickness no)
		(fill yes
			(thermal_gap 0.15)
			(thermal_bridge_width 0.25)
			(smoothing fillet)
			(radius 0.2)
		)
		(polygon
			(pts
				(xy 153.55 66.025) (xy 153.55 64.075) (xy 143.55 64.075) (xy 143.55 66.025)
			)
		)
	)
	(zone
		(net 427)
		(net_name "Net-(U14H-SVR_IND)")
		(layer "F.Cu")
		(hatch edge 0.5)
		(priority 4)
		(connect_pads yes
			(clearance 0.15)
		)
		(min_thickness 0.25)
		(filled_areas_thickness no)
		(fill yes
			(thermal_gap 0.15)
			(thermal_bridge_width 0.25)
			(smoothing fillet)
			(radius 0.3)
		)
		(polygon
			(pts
				(xy 146.595 72.075) (xy 146.595 69.725) (xy 146.695 69.625) (xy 146.795 69.525) (xy 147.145 69.525)
				(xy 147.145 68.025) (xy 143.645 68.025001) (xy 143.645 69.524989) (xy 144.245 69.525001) (xy 145.895 71.175)
				(xy 145.895 72.075)
			)
		)
	)
	(zone
		(net 23)
		(net_name "GND")
		(layer "F.Cu")
		(hatch edge 0.5)
		(priority 52)
		(connect_pads yes
			(clearance 0.1)
		)
		(min_thickness 0.1)
		(filled_areas_thickness no)
		(fill yes
			(thermal_gap 0.5)
			(thermal_bridge_width 0.5)
		)
		(polygon
			(pts
				(xy 131.25 89) (xy 140 89) (xy 140 87.5) (xy 134.75 87.5) (xy 134.75 87.25) (xy 131.25 87.25)
			)
		)
	)
	(zone
		(net 40)
		(net_name "+5V")
		(layer "F.Cu")
		(hatch edge 0.5)
		(priority 7)
		(connect_pads yes
			(clearance 0.15)
		)
		(min_thickness 0.25)
		(filled_areas_thickness no)
		(fill yes
			(thermal_gap 0.5)
			(thermal_bridge_width 0.5)
			(smoothing fillet)
			(radius 0.2)
		)
		(polygon
			(pts
				(xy 155.000001 109.979997) (xy 155 115.004997) (xy 156.55 115.004998) (xy 156.55 111.304996) (xy 155.9 110.654996)
				(xy 155.9 109.979997)
			)
		)
	)
	(zone
		(net 10)
		(net_name "AVDDH")
		(layer "F.Cu")
		(hatch edge 0.5)
		(priority 40)
		(connect_pads yes
			(clearance 0.1)
		)
		(min_thickness 0.1)
		(filled_areas_thickness no)
		(fill yes
			(thermal_gap 0.5)
			(thermal_bridge_width 0.5)
		)
		(polygon
			(pts
				(xy 148 97.25) (xy 149.5 97.25) (xy 149.5 93.25) (xy 148 93.25)
			)
		)
	)
	(zone
		(net 23)
		(net_name "GND")
		(layer "F.Cu")
		(hatch edge 0.5)
		(priority 8)
		(connect_pads yes
			(clearance 0.15)
		)
		(min_thickness 0.25)
		(filled_areas_thickness no)
		(fill yes
			(thermal_gap 0.5)
			(thermal_bridge_width 0.5)
			(smoothing fillet)
			(radius 0.2)
		)
		(polygon
			(pts
				(xy 138.574998 110.029996) (xy 138.574998 110.829996) (xy 137.849998 111.554996) (xy 137.849999 115.004996)
				(xy 139.399998 115.004996) (xy 139.399998 110.954996) (xy 138.999998 110.554996) (xy 138.999998 110.029996)
			)
		)
	)
	(zone
		(net 310)
		(net_name "/X710 DCDC converters/1V0_SW")
		(layer "F.Cu")
		(hatch edge 0.5)
		(priority 6)
		(connect_pads yes
			(clearance 0.15)
		)
		(min_thickness 0.25)
		(filled_areas_thickness no)
		(fill yes
			(thermal_gap 0.5)
			(thermal_bridge_width 0.5)
			(smoothing fillet)
			(radius 0.2)
		)
		(polygon
			(pts
				(xy 162.25 110.499999) (xy 162.55 110.499999) (xy 162.550001 109.574999) (xy 163.525001 108.599999)
				(xy 164.299999 108.6) (xy 164.3 107.1) (xy 160.8 107.1) (xy 160.800002 108.600001) (xy 161.625 108.599999)
				(xy 162.25 109.224999)
			)
		)
	)
	(zone
		(net 12)
		(net_name "XFI_VDD")
		(layer "F.Cu")
		(hatch edge 0.5)
		(priority 63)
		(connect_pads yes
			(clearance 0.1)
		)
		(min_thickness 0.1)
		(filled_areas_thickness no)
		(fill yes
			(thermal_gap 0.5)
			(thermal_bridge_width 0.5)
		)
		(polygon
			(pts
				(xy 153.3 95.9) (xy 153.3 92.1) (xy 150.8 92.1) (xy 150.8 93.35) (xy 151.75 93.35) (xy 151.8 93.4)
				(xy 151.8 94.7) (xy 150.7 94.7) (xy 150.7 95.9)
			)
		)
	)
	(zone
		(net 23)
		(net_name "GND")
		(layer "F.Cu")
		(hatch edge 0.5)
		(priority 17)
		(connect_pads yes
			(clearance 0.15)
		)
		(min_thickness 0.25)
		(filled_areas_thickness no)
		(fill yes
			(thermal_gap 0.5)
			(thermal_bridge_width 0.5)
			(smoothing fillet)
			(radius 0.2)
		)
		(polygon
			(pts
				(xy 142.149988 107.239998) (xy 144.800001 107.239998) (xy 144.800001 105.679998) (xy 142.149989 105.679998)
			)
		)
	)
	(zone
		(net 349)
		(net_name "/Power input/5V_OUT")
		(layer "F.Cu")
		(hatch edge 0.5)
		(priority 25)
		(connect_pads yes
			(clearance 0.125)
		)
		(min_thickness 0.125)
		(filled_areas_thickness no)
		(fill yes
			(thermal_gap 0.5)
			(thermal_bridge_width 0.5)
		)
		(polygon
			(pts
				(xy 144.6 57.2) (xy 144.6 58.8) (xy 157.6 58.8) (xy 157.6 54.1) (xy 154.2 54.1) (xy 154.2 57.2)
			)
		)
	)
	(zone
		(net 23)
		(net_name "GND")
		(layer "F.Cu")
		(hatch edge 0.5)
		(priority 17)
		(connect_pads yes
			(clearance 0.15)
		)
		(min_thickness 0.25)
		(filled_areas_thickness no)
		(fill yes
			(thermal_gap 0.5)
			(thermal_bridge_width 0.5)
			(smoothing fillet)
			(radius 0.2)
		)
		(polygon
			(pts
				(xy 157.549988 107.249998) (xy 160.200001 107.249998) (xy 160.200001 105.689998) (xy 157.549989 105.689998)
			)
		)
	)
	(zone
		(net 23)
		(net_name "GND")
		(layer "F.Cu")
		(hatch edge 0.5)
		(priority 54)
		(connect_pads yes
			(clearance 0.1)
		)
		(min_thickness 0.1)
		(filled_areas_thickness no)
		(fill yes
			(thermal_gap 0.5)
			(thermal_bridge_width 0.5)
		)
		(polygon
			(pts
				(xy 120.8 103.6) (xy 119.6 103.6) (xy 119.6 112.75) (xy 118.75 112.75) (xy 118.75 115.85) (xy 121.8 115.85)
				(xy 121.8 107) (xy 122.2 107) (xy 122.2 101.4) (xy 120.8 101.4)
			)
		)
	)
	(zone
		(net 334)
		(net_name "/X710 DCDC converters/+3V3_OUT")
		(layer "F.Cu")
		(hatch edge 0.5)
		(priority 50)
		(connect_pads yes
			(clearance 0.15)
		)
		(min_thickness 0.25)
		(filled_areas_thickness no)
		(fill yes
			(thermal_gap 0.5)
			(thermal_bridge_width 0.5)
			(smoothing fillet)
			(radius 0.2)
		)
		(polygon
			(pts
				(xy 135.3 90.7) (xy 137.8 90.7) (xy 137.8 93.1) (xy 138.95 94.3) (xy 139.7 94.3) (xy 139.7 98.2)
				(xy 137.3 98.2) (xy 137.3 94.8) (xy 136.7 94.2) (xy 136.3 94.2) (xy 136.25 94.15) (xy 136.25 93.3)
				(xy 135.3 93.3)
			)
		)
	)
	(zone
		(net 354)
		(net_name "/Power input/5V_SW")
		(layer "F.Cu")
		(hatch edge 0.5)
		(priority 11)
		(connect_pads yes
			(clearance 0.1)
		)
		(min_thickness 0.25)
		(filled_areas_thickness no)
		(fill yes
			(thermal_gap 0.5)
			(thermal_bridge_width 0.5)
		)
		(polygon
			(pts
				(xy 156 51.75) (xy 158.75 51.75) (xy 158.75 52.5) (xy 159.5 53.25) (xy 163 53.25) (xy 163 58.25)
				(xy 157.75 58.25) (xy 157.75 54.1) (xy 157.65 54) (xy 156 54)
			)
		)
	)
	(zone
		(net 335)
		(net_name "/X710 DCDC converters/+VCCD_OUT")
		(layer "F.Cu")
		(hatch edge 0.5)
		(priority 37)
		(connect_pads yes
			(clearance 0.15)
		)
		(min_thickness 0.25)
		(filled_areas_thickness no)
		(fill yes
			(thermal_gap 0.5)
			(thermal_bridge_width 0.5)
			(smoothing fillet)
			(radius 0.2)
		)
		(polygon
			(pts
				(xy 134.450002 103.129998) (xy 134.450002 105.529998) (xy 141.500002 105.529998) (xy 141.500002 103.129998)
			)
		)
	)
	(zone
		(net 53)
		(net_name "+5V_USB")
		(layer "F.Cu")
		(hatch edge 0.5)
		(priority 30)
		(connect_pads yes
			(clearance 0.125)
		)
		(min_thickness 0.125)
		(filled_areas_thickness no)
		(fill yes
			(thermal_gap 0.5)
			(thermal_bridge_width 0.5)
		)
		(polygon
			(pts
				(xy 118.1 142.2) (xy 118.1 140.8) (xy 121 140.8) (xy 121 142.2)
			)
		)
	)
	(zone
		(net 23)
		(net_name "GND")
		(layer "F.Cu")
		(hatch edge 0.5)
		(priority 8)
		(connect_pads yes
			(clearance 0.15)
		)
		(min_thickness 0.25)
		(filled_areas_thickness no)
		(fill yes
			(thermal_gap 0.5)
			(thermal_bridge_width 0.5)
			(smoothing fillet)
			(radius 0.2)
		)
		(polygon
			(pts
				(xy 153.975 110.029997) (xy 153.975 110.829997) (xy 153.25 111.554997) (xy 153.250001 115.004997)
				(xy 154.8 115.004997) (xy 154.8 110.954997) (xy 154.4 110.554997) (xy 154.4 110.029997)
			)
		)
	)
	(zone
		(net 23)
		(net_name "GND")
		(layer "F.Cu")
		(hatch edge 0.5)
		(priority 24)
		(connect_pads yes
			(clearance 0.125)
		)
		(min_thickness 0.125)
		(filled_areas_thickness no)
		(fill yes
			(thermal_gap 0.5)
			(thermal_bridge_width 0.5)
		)
		(polygon
			(pts
				(xy 139.9 50.1) (xy 139.9 54.75) (xy 146 54.75) (xy 146 56.5) (xy 153.75 56.5) (xy 153.75 51.7)
				(xy 158.55 51.7) (xy 158.55 50.8) (xy 159.4 50.8) (xy 159.4 48.9) (xy 157.6 48.9) (xy 157.6 50.1)
			)
		)
	)
	(zone
		(net 23)
		(net_name "GND")
		(layer "F.Cu")
		(hatch edge 0.5)
		(priority 43)
		(connect_pads yes
			(clearance 0.15)
		)
		(min_thickness 0.25)
		(filled_areas_thickness no)
		(fill yes
			(thermal_gap 0.5)
			(thermal_bridge_width 0.5)
			(smoothing fillet)
			(radius 0.2)
		)
		(polygon
			(pts
				(xy 140.75 99.575) (xy 140.75 98.575) (xy 132.45 98.575) (xy 132.45 99.575)
			)
		)
	)
	(zone
		(net 40)
		(net_name "+5V")
		(layer "F.Cu")
		(hatch edge 0.5)
		(priority 27)
		(connect_pads yes
			(clearance 0.125)
		)
		(min_thickness 0.125)
		(filled_areas_thickness no)
		(fill yes
			(thermal_gap 0.5)
			(thermal_bridge_width 0.5)
		)
		(polygon
			(pts
				(xy 136.8 62.2) (xy 136.8 64.2) (xy 140.2 64.2) (xy 140.2 59.2) (xy 140 59.2) (xy 140 58.4) (xy 141.4 58.4)
				(xy 141.4 56.2) (xy 139 56.2) (xy 139 57.4) (xy 136.6 57.4) (xy 136.6 59.8) (xy 138.2 59.8) (xy 138.2 62.2)
			)
		)
	)
	(zone
		(net 57)
		(net_name "+3V3_TB")
		(layer "F.Cu")
		(hatch edge 0.5)
		(priority 2)
		(connect_pads yes
			(clearance 0.1)
		)
		(min_thickness 0.1)
		(filled_areas_thickness no)
		(fill yes
			(thermal_gap 0.5)
			(thermal_bridge_width 0.5)
		)
		(polygon
			(pts
				(xy 137.4 129.2) (xy 138.6 130.4) (xy 140.6 130.4) (xy 140.6 132.6) (xy 138.1 132.6) (xy 138.1 132.1)
				(xy 138 132) (xy 137.1 131.1) (xy 134.2 131.1) (xy 134.2 131.6) (xy 133 131.6) (xy 133 129.8) (xy 132.4 129.8)
				(xy 132.4 128.4) (xy 133 128.4) (xy 133.4 128.8) (xy 133.4 129.2)
			)
		)
	)
	(zone
		(net 13)
		(net_name "/Power input/5V_JACK")
		(layer "F.Cu")
		(hatch edge 0.5)
		(priority 26)
		(connect_pads yes
			(clearance 0.125)
		)
		(min_thickness 0.125)
		(filled_areas_thickness no)
		(fill yes
			(thermal_gap 0.5)
			(thermal_bridge_width 0.5)
		)
		(polygon
			(pts
				(xy 141.75 56) (xy 141.75 59) (xy 144.5 59) (xy 144.5 57) (xy 146 57) (xy 146 54.75) (xy 144.25 54.75)
				(xy 144.25 56)
			)
		)
	)
	(zone
		(net 338)
		(net_name "/X710 DCDC converters/+1V88_OUT")
		(layer "F.Cu")
		(hatch edge 0.5)
		(priority 37)
		(connect_pads yes
			(clearance 0.15)
		)
		(min_thickness 0.25)
		(filled_areas_thickness no)
		(fill yes
			(thermal_gap 0.5)
			(thermal_bridge_width 0.5)
			(smoothing fillet)
			(radius 0.2)
		)
		(polygon
			(pts
				(xy 149.850002 103.129998) (xy 149.850002 105.529998) (xy 156.900003 105.529998) (xy 156.900002 103.129998)
			)
		)
	)
	(zone
		(net 153)
		(net_name "/X710 DCDC converters/VCCD_SW")
		(layer "F.Cu")
		(hatch edge 0.5)
		(priority 6)
		(connect_pads yes
			(clearance 0.15)
		)
		(min_thickness 0.25)
		(filled_areas_thickness no)
		(fill yes
			(thermal_gap 0.5)
			(thermal_bridge_width 0.5)
			(smoothing fillet)
			(radius 0.2)
		)
		(polygon
			(pts
				(xy 139.149999 110.499998) (xy 139.449999 110.499998) (xy 139.45 109.574998) (xy 140.425 108.599998)
				(xy 141.199998 108.599999) (xy 141.199999 107.099999) (xy 137.699999 107.099999) (xy 137.700001 108.6)
				(xy 138.524999 108.599998) (xy 139.149999 109.224998)
			)
		)
	)
	(zone
		(net 23)
		(net_name "GND")
		(layer "F.Cu")
		(hatch edge 0.5)
		(priority 8)
		(connect_pads yes
			(clearance 0.15)
		)
		(min_thickness 0.25)
		(filled_areas_thickness no)
		(fill yes
			(thermal_gap 0.5)
			(thermal_bridge_width 0.5)
			(smoothing fillet)
			(radius 0.2)
		)
		(polygon
			(pts
				(xy 146.274999 110.029998) (xy 146.274999 110.829998) (xy 145.549999 111.554998) (xy 145.55 115.004998)
				(xy 147.099999 115.004998) (xy 147.099999 110.954998) (xy 146.699999 110.554998) (xy 146.699999 110.029998)
			)
		)
	)
	(zone
		(net 40)
		(net_name "+5V")
		(layer "F.Cu")
		(hatch edge 0.5)
		(priority 7)
		(connect_pads yes
			(clearance 0.15)
		)
		(min_thickness 0.25)
		(filled_areas_thickness no)
		(fill yes
			(thermal_gap 0.5)
			(thermal_bridge_width 0.5)
			(smoothing fillet)
			(radius 0.2)
		)
		(polygon
			(pts
				(xy 147.3 109.979998) (xy 147.299999 115.004998) (xy 148.849999 115.004999) (xy 148.849999 111.304997)
				(xy 148.199999 110.654997) (xy 148.199999 109.979998)
			)
		)
	)
	(zone
		(net 23)
		(net_name "GND")
		(layer "F.Cu")
		(hatch edge 0.5)
		(priority 17)
		(connect_pads yes
			(clearance 0.15)
		)
		(min_thickness 0.25)
		(filled_areas_thickness no)
		(fill yes
			(thermal_gap 0.5)
			(thermal_bridge_width 0.5)
			(smoothing fillet)
			(radius 0.2)
		)
		(polygon
			(pts
				(xy 149.859988 107.259998) (xy 152.510001 107.259998) (xy 152.510001 105.699998) (xy 149.859989 105.699998)
			)
		)
	)
	(zone
		(net 40)
		(net_name "+5V")
		(layer "F.Cu")
		(hatch edge 0.5)
		(priority 7)
		(connect_pads yes
			(clearance 0.15)
		)
		(min_thickness 0.25)
		(filled_areas_thickness no)
		(fill yes
			(thermal_gap 0.5)
			(thermal_bridge_width 0.5)
			(smoothing fillet)
			(radius 0.2)
		)
		(polygon
			(pts
				(xy 139.599999 109.979996) (xy 139.599998 115.004996) (xy 141.149998 115.004997) (xy 141.149998 111.304995)
				(xy 140.499998 110.654995) (xy 140.499998 109.979996)
			)
		)
	)
	(zone
		(net 339)
		(net_name "/X710 DCDC converters/+1V0_OUT")
		(layer "F.Cu")
		(hatch edge 0.5)
		(priority 37)
		(connect_pads yes
			(clearance 0.15)
		)
		(min_thickness 0.25)
		(filled_areas_thickness no)
		(fill yes
			(thermal_gap 0.5)
			(thermal_bridge_width 0.5)
			(smoothing fillet)
			(radius 0.2)
		)
		(polygon
			(pts
				(xy 157.550001 103.129998) (xy 157.550001 105.529998) (xy 164.600001 105.529998) (xy 164.600001 103.129998)
			)
		)
	)
	(zone
		(net 7)
		(net_name "+3V3")
		(layer "F.Cu")
		(hatch edge 0.5)
		(priority 1)
		(connect_pads yes
			(clearance 0.15)
		)
		(min_thickness 0.25)
		(filled_areas_thickness no)
		(fill yes
			(thermal_gap 0.15)
			(thermal_bridge_width 0.25)
			(smoothing fillet)
			(radius 0.2)
		)
		(polygon
			(pts
				(xy 153.545 68.675) (xy 148.445 68.675) (xy 148.445 70.125) (xy 147.695 70.875) (xy 147.695 72.025)
				(xy 148.395 72.025) (xy 148.395 71.125) (xy 148.795 70.725) (xy 153.545 70.725)
			)
		)
	)
	(zone
		(net 7)
		(net_name "+3V3")
		(layer "F.Cu")
		(name "INNER_GND")
		(hatch edge 0.5)
		(priority 38)
		(connect_pads yes
			(clearance 0.1)
		)
		(min_thickness 0.15)
		(filled_areas_thickness no)
		(fill yes
			(thermal_gap 0.2)
			(thermal_bridge_width 0.3)
			(smoothing fillet)
			(radius 0.2)
		)
		(polygon
			(pts
				(xy 128.4 85.6) (xy 131.2 85.6) (xy 131.2 89.25) (xy 140.5 89.25) (xy 140.75 89.5) (xy 140.75 93.25)
				(xy 139.5 93.25) (xy 139.5 92) (xy 137.75 92) (xy 137.6 91.85) (xy 137.6 90.6) (xy 128.4 90.6)
			)
		)
	)
	(zone
		(net 163)
		(net_name "Net-(U2-SW)")
		(layer "F.Cu")
		(hatch edge 0.5)
		(priority 53)
		(connect_pads yes
			(clearance 0.1)
		)
		(min_thickness 0.1)
		(filled_areas_thickness no)
		(fill yes
			(thermal_gap 0.5)
			(thermal_bridge_width 0.5)
		)
		(polygon
			(pts
				(xy 119.2 104.4) (xy 119.6 104.4) (xy 119.6 102.6) (xy 119.4 101) (xy 119.4 96) (xy 117.8 96) (xy 117.8 101)
				(xy 119.15 102.8)
			)
		)
	)
	(zone
		(net 23)
		(net_name "GND")
		(layer "F.Cu")
		(hatch edge 0.5)
		(priority 22)
		(connect_pads yes
			(clearance 0.15)
		)
		(min_thickness 0.25)
		(filled_areas_thickness no)
		(fill yes
			(thermal_gap 0.5)
			(thermal_bridge_width 0.5)
			(smoothing fillet)
			(radius 0.2)
		)
		(polygon
			(pts
				(xy 167.2 99.075) (xy 164.9 99.075) (xy 164.9 98.475) (xy 165.5 97.875) (xy 165.5 92.975) (xy 167.2 92.975)
			)
		)
	)
	(zone
		(net 136)
		(net_name "+1V0")
		(layer "F.Cu")
		(hatch edge 0.5)
		(priority 33)
		(connect_pads yes
			(clearance 0.15)
		)
		(min_thickness 0.25)
		(filled_areas_thickness no)
		(fill yes
			(thermal_gap 0.5)
			(thermal_bridge_width 0.5)
			(smoothing fillet)
			(radius 0.2)
		)
		(polygon
			(pts
				(xy 167.2 99.275) (xy 154.7 99.275) (xy 154.7 98.025) (xy 156 98.025) (xy 156 96.675) (xy 150.65 96.675)
				(xy 150.65 98.025) (xy 151.95 98.025) (xy 151.95 99.125) (xy 151.45 99.125) (xy 151.45 101.825)
				(xy 152.7 101.825) (xy 152.7 102.975) (xy 158.8 102.975) (xy 158.8 101.825) (xy 167.2 101.825)
			)
		)
	)
	(zone
		(net 9)
		(net_name "VCCD")
		(layer "F.Cu")
		(hatch edge 0.5)
		(priority 28)
		(connect_pads yes
			(clearance 0.15)
		)
		(min_thickness 0.15)
		(filled_areas_thickness no)
		(fill yes
			(thermal_gap 0.5)
			(thermal_bridge_width 0.5)
			(smoothing fillet)
			(radius 0.2)
		)
		(polygon
			(pts
				(xy 135.7 102.899998) (xy 135.7 101.749998) (xy 137.15 101.749998) (xy 137.15 102.549998) (xy 140.75 102.549998)
				(xy 140.75 99.749998) (xy 132.45 99.749998) (xy 132.45 102.899998)
			)
		)
	)
	(zone
		(net 117)
		(net_name "/X710 DCDC converters/3V3_SW")
		(layer "F.Cu")
		(hatch edge 0.5)
		(priority 6)
		(connect_pads yes
			(clearance 0.15)
		)
		(min_thickness 0.25)
		(filled_areas_thickness no)
		(fill yes
			(thermal_gap 0.5)
			(thermal_bridge_width 0.5)
			(smoothing fillet)
			(radius 0.2)
		)
		(polygon
			(pts
				(xy 134.025 95.9) (xy 134.025 96.2) (xy 134.55 96.200001) (xy 135.425 97.075001) (xy 135.424999 97.949999)
				(xy 136.524999 97.95) (xy 136.524999 94.45) (xy 135.424998 94.450002) (xy 135.425 95.375) (xy 134.9 95.9)
			)
		)
	)
	(zone
		(net 313)
		(net_name "/X710 DCDC converters/DVDD_SW")
		(layer "F.Cu")
		(hatch edge 0.5)
		(priority 6)
		(connect_pads yes
			(clearance 0.15)
		)
		(min_thickness 0.25)
		(filled_areas_thickness no)
		(fill yes
			(thermal_gap 0.5)
			(thermal_bridge_width 0.5)
			(smoothing fillet)
			(radius 0.2)
		)
		(polygon
			(pts
				(xy 146.85 110.5) (xy 147.15 110.5) (xy 147.150001 109.575) (xy 148.125001 108.6) (xy 148.899999 108.600001)
				(xy 148.9 107.100001) (xy 145.4 107.100001) (xy 145.400002 108.600002) (xy 146.225 108.6) (xy 146.85 109.225)
			)
		)
	)
	(zone
		(net 23)
		(net_name "GND")
		(layer "F.Cu")
		(hatch edge 0.5)
		(priority 2)
		(connect_pads yes
			(clearance 0.15)
		)
		(min_thickness 0.25)
		(filled_areas_thickness no)
		(fill yes
			(thermal_gap 0.15)
			(thermal_bridge_width 0.25)
			(smoothing fillet)
			(radius 0.2)
		)
		(polygon
			(pts
				(xy 153.545 66.125) (xy 147.945 66.125) (xy 147.445 66.625) (xy 147.445 69.775) (xy 146.795 70.425)
				(xy 146.795 71.575) (xy 147.395 71.575) (xy 147.395 70.925) (xy 148.245 70.075) (xy 148.245 68.475)
				(xy 153.545 68.475)
			)
		)
	)
	(zone
		(net 14)
		(net_name "P1_AVDDL")
		(layer "F.Cu")
		(hatch edge 0.5)
		(priority 23)
		(connect_pads yes
			(clearance 0.15)
		)
		(min_thickness 0.25)
		(filled_areas_thickness no)
		(fill yes
			(thermal_gap 0.5)
			(thermal_bridge_width 0.5)
			(smoothing fillet)
			(radius 0.2)
		)
		(polygon
			(pts
				(xy 164.65 99.075) (xy 164.65 98.325) (xy 165.25 97.725) (xy 165.25 92.975) (xy 163.45 92.975) (xy 163.45 99.075)
			)
		)
	)
	(zone
		(net 68)
		(net_name "/TB Controller - Power/VCC_0P9")
		(layer "F.Cu")
		(hatch edge 0.5)
		(priority 4)
		(connect_pads yes
			(clearance 0.1)
		)
		(min_thickness 0.25)
		(filled_areas_thickness no)
		(fill yes
			(thermal_gap 0.5)
			(thermal_bridge_width 0.5)
		)
		(polygon
			(pts
				(xy 137.25 123.75) (xy 140 123.75) (xy 140.8 122.95) (xy 144 122.95) (xy 144 120.25) (xy 137.25 120.25)
			)
		)
	)
	(zone
		(net 23)
		(net_name "GND")
		(layer "F.Cu")
		(hatch edge 0.5)
		(priority 8)
		(connect_pads yes
			(clearance 0.15)
		)
		(min_thickness 0.25)
		(filled_areas_thickness no)
		(fill yes
			(thermal_gap 0.5)
			(thermal_bridge_width 0.5)
			(smoothing fillet)
			(radius 0.2)
		)
		(polygon
			(pts
				(xy 161.674999 110.029997) (xy 161.674999 110.829997) (xy 160.949999 111.554997) (xy 160.95 115.004997)
				(xy 162.499999 115.004997) (xy 162.499999 110.954997) (xy 162.099999 110.554997) (xy 162.099999 110.029997)
			)
		)
	)
	(zone
		(net 23)
		(net_name "GND")
		(layer "F.Cu")
		(hatch edge 0.5)
		(priority 43)
		(connect_pads yes
			(clearance 0.15)
		)
		(min_thickness 0.25)
		(filled_areas_thickness no)
		(fill yes
			(thermal_gap 0.5)
			(thermal_bridge_width 0.5)
			(smoothing fillet)
			(radius 0.2)
		)
		(polygon
			(pts
				(xy 145.049999 99.575) (xy 145.049999 98.575) (xy 141.049999 98.575) (xy 141.049999 99.575)
			)
		)
	)
	(zone
		(net 18)
		(net_name "+1V88")
		(layer "F.Cu")
		(hatch edge 0.5)
		(priority 21)
		(connect_pads yes
			(clearance 0.15)
		)
		(min_thickness 0.25)
		(filled_areas_thickness no)
		(fill yes
			(thermal_gap 0.5)
			(thermal_bridge_width 0.5)
			(smoothing fillet)
			(radius 0.2)
		)
		(polygon
			(pts
				(xy 150.45 97.475) (xy 145.7 97.475) (xy 145.7 102.975) (xy 151.1 102.975) (xy 151.1 99.425) (xy 150.45 98.775)
			)
		)
	)
	(zone
		(net 57)
		(net_name "+3V3_TB")
		(layer "F.Cu")
		(hatch edge 0.5)
		(priority 62)
		(connect_pads yes
			(clearance 0.1)
		)
		(min_thickness 0.1)
		(filled_areas_thickness no)
		(fill yes
			(thermal_gap 0.5)
			(thermal_bridge_width 0.5)
		)
		(polygon
			(pts
				(xy 123.75 109) (xy 121.75 109) (xy 121.75 116) (xy 127 116) (xy 127 113) (xy 123.75 109.75)
			)
		)
	)
	(zone
		(net 161)
		(net_name "Net-(U2-VIN)")
		(layer "F.Cu")
		(hatch edge 0.5)
		(priority 57)
		(connect_pads yes
			(clearance 0.1)
		)
		(min_thickness 0.1)
		(filled_areas_thickness no)
		(fill yes
			(thermal_gap 0.5)
			(thermal_bridge_width 0.5)
		)
		(polygon
			(pts
				(xy 115.8 111.2) (xy 115.8 109.8) (xy 117.8 109.8) (xy 117.8 105.6) (xy 118.6 105) (xy 118.6 103.8)
				(xy 119.2 103.8) (xy 119.2 105) (xy 119.6 105.4) (xy 119.6 112.6) (xy 117.8 112.6) (xy 117.8 111.2)
			)
		)
	)
	(zone
		(net 241)
		(net_name "/X710 DCDC converters/1V88_SW")
		(layer "F.Cu")
		(hatch edge 0.5)
		(priority 6)
		(connect_pads yes
			(clearance 0.15)
		)
		(min_thickness 0.25)
		(filled_areas_thickness no)
		(fill yes
			(thermal_gap 0.5)
			(thermal_bridge_width 0.5)
			(smoothing fillet)
			(radius 0.2)
		)
		(polygon
			(pts
				(xy 154.550001 110.499999) (xy 154.850001 110.499999) (xy 154.850002 109.574999) (xy 155.825002 108.599999)
				(xy 156.6 108.6) (xy 156.600001 107.1) (xy 153.100001 107.1) (xy 153.100003 108.600001) (xy 153.925001 108.599999)
				(xy 154.550001 109.224999)
			)
		)
	)
	(zone
		(net 23)
		(net_name "GND")
		(layer "F.Cu")
		(hatch edge 0.5)
		(priority 22)
		(connect_pads yes
			(clearance 0.15)
		)
		(min_thickness 0.25)
		(filled_areas_thickness no)
		(fill yes
			(thermal_gap 0.5)
			(thermal_bridge_width 0.5)
			(smoothing fillet)
			(radius 0.2)
		)
		(polygon
			(pts
				(xy 163.25 99.075) (xy 160.95 99.075) (xy 160.95 98.475) (xy 161.55 97.875) (xy 161.55 92.975) (xy 163.25 92.975)
			)
		)
	)
	(zone
		(net 341)
		(net_name "/X710 DCDC converters/+DVDD_OUT")
		(layer "F.Cu")
		(hatch edge 0.5)
		(priority 37)
		(connect_pads yes
			(clearance 0.15)
		)
		(min_thickness 0.25)
		(filled_areas_thickness no)
		(fill yes
			(thermal_gap 0.5)
			(thermal_bridge_width 0.5)
			(smoothing fillet)
			(radius 0.2)
		)
		(polygon
			(pts
				(xy 142.15 103.129999) (xy 142.15 105.529999) (xy 149.2 105.529999) (xy 149.2 103.129999)
			)
		)
	)
	(zone
		(net 136)
		(net_name "+1V0")
		(layer "B.Cu")
		(hatch edge 0.5)
		(priority 41)
		(connect_pads yes
			(clearance 0.1)
		)
		(min_thickness 0.1)
		(filled_areas_thickness no)
		(fill yes
			(thermal_gap 0.5)
			(thermal_bridge_width 0.5)
		)
		(polygon
			(pts
				(xy 155.5 93.385117) (xy 155.5 102.8) (xy 161.8 102.8) (xy 161.8 98.8) (xy 159.4 98.8) (xy 159.4 93.385117)
			)
		)
	)
	(zone
		(net 18)
		(net_name "+1V88")
		(layer "B.Cu")
		(hatch edge 0.5)
		(priority 56)
		(connect_pads yes
			(clearance 0.15)
		)
		(min_thickness 0.25)
		(filled_areas_thickness no)
		(fill yes
			(thermal_gap 0.5)
			(thermal_bridge_width 0.5)
			(smoothing fillet)
			(radius 0.2)
		)
		(polygon
			(pts
				(xy 152.7 90.325) (xy 152.7 89.675) (xy 151 89.675) (xy 151 90.325)
			)
		)
	)
	(zone
		(net 23)
		(net_name "GND")
		(layer "B.Cu")
		(hatch edge 0.5)
		(priority 56)
		(connect_pads yes
			(clearance 0.15)
		)
		(min_thickness 0.25)
		(filled_areas_thickness no)
		(fill yes
			(thermal_gap 0.5)
			(thermal_bridge_width 0.5)
			(smoothing fillet)
			(radius 0.2)
		)
		(polygon
			(pts
				(xy 152.7 89.375) (xy 152.7 88.725) (xy 151 88.725) (xy 151 89.375)
			)
		)
	)
	(zone
		(net 9)
		(net_name "VCCD")
		(layer "B.Cu")
		(hatch edge 0.5)
		(priority 5)
		(connect_pads yes
			(clearance 0.15)
		)
		(min_thickness 0.25)
		(filled_areas_thickness no)
		(fill yes
			(thermal_gap 0.15)
			(thermal_bridge_width 0.25)
			(smoothing fillet)
			(radius 0.2)
		)
		(polygon
			(pts
				(xy 149.25 81.625) (xy 149.25 76.875) (xy 148.45 76.875) (xy 148.45 81.625)
			)
		)
	)
	(zone
		(net 23)
		(net_name "GND")
		(layer "B.Cu")
		(hatch edge 0.5)
		(priority 5)
		(connect_pads yes
			(clearance 0.15)
		)
		(min_thickness 0.25)
		(filled_areas_thickness no)
		(fill yes
			(thermal_gap 0.15)
			(thermal_bridge_width 0.25)
			(smoothing fillet)
			(radius 0.2)
		)
		(polygon
			(pts
				(xy 154.25 81.625) (xy 154.25 74.825) (xy 154.8 74.825) (xy 154.8 73.875) (xy 153 73.875) (xy 153 81.625)
			)
		)
	)
	(zone
		(net 23)
		(net_name "GND")
		(layer "B.Cu")
		(hatch edge 0.5)
		(priority 44)
		(connect_pads yes
			(clearance 0.1)
		)
		(min_thickness 0.1)
		(filled_areas_thickness no)
		(fill yes
			(thermal_gap 0.5)
			(thermal_bridge_width 0.5)
		)
		(polygon
			(pts
				(xy 140 105) (xy 138.75 105) (xy 138.75 107.5) (xy 161.8 107.5) (xy 161.8 104) (xy 154.75 104) (xy 154.75 97)
				(xy 152.5 97) (xy 152.5 99.5) (xy 146.7 99.5) (xy 146.7 104) (xy 140 104)
			)
		)
	)
	(zone
		(net 23)
		(net_name "GND")
		(layer "B.Cu")
		(hatch edge 0.5)
		(priority 5)
		(connect_pads yes
			(clearance 0.15)
		)
		(min_thickness 0.25)
		(filled_areas_thickness no)
		(fill yes
			(thermal_gap 0.15)
			(thermal_bridge_width 0.25)
			(smoothing fillet)
			(radius 0.2)
		)
		(polygon
			(pts
				(xy 150.15 81.625) (xy 150.15 75.775) (xy 149.45 75.775) (xy 149.45 81.625)
			)
		)
	)
	(zone
		(net 23)
		(net_name "GND")
		(layer "B.Cu")
		(hatch edge 0.5)
		(priority 13)
		(connect_pads yes
			(clearance 0.15)
		)
		(min_thickness 0.25)
		(filled_areas_thickness no)
		(fill yes
			(thermal_gap 0.5)
			(thermal_bridge_width 0.5)
			(smoothing fillet)
			(radius 0.2)
		)
		(polygon
			(pts
				(xy 156.91 82.515) (xy 156.91 85.635) (xy 157.92 85.635) (xy 157.92 86.555) (xy 158.76 86.555) (xy 158.76 87.305)
				(xy 158.04 87.305) (xy 157.81 87.535) (xy 156.91 87.535) (xy 156.91 91.525) (xy 158.1 91.525) (xy 158.1 88.465)
				(xy 158.74 88.465) (xy 158.74 93.225) (xy 157.26 93.225) (xy 157.26 91.975) (xy 156.86 91.975) (xy 156.23 91.975)
				(xy 156.23 82.515)
			)
		)
	)
	(zone
		(net 23)
		(net_name "GND")
		(layer "B.Cu")
		(hatch edge 0.5)
		(priority 17)
		(connect_pads yes
			(clearance 0.15)
		)
		(min_thickness 0.25)
		(filled_areas_thickness no)
		(fill yes
			(thermal_gap 0.5)
			(thermal_bridge_width 0.5)
			(smoothing fillet)
			(radius 0.2)
		)
		(polygon
			(pts
				(xy 155.12 83.525) (xy 155.12 89.975) (xy 154.41 89.975) (xy 154.41 83.525)
			)
		)
	)
	(zone
		(net 22)
		(net_name "PLL_VDD")
		(layer "B.Cu")
		(hatch edge 0.5)
		(priority 35)
		(connect_pads yes
			(clearance 0.125)
		)
		(min_thickness 0.125)
		(filled_areas_thickness no)
		(fill yes
			(thermal_gap 0.5)
			(thermal_bridge_width 0.5)
		)
		(polygon
			(pts
				(xy 155.2 90.075) (xy 155.2 92.625) (xy 155.8 93.225) (xy 157 93.225) (xy 157 92.125) (xy 156.65 92.125)
				(xy 156.65 91.275) (xy 155.95 91.275) (xy 155.95 90.075)
			)
		)
	)
	(zone
		(net 12)
		(net_name "XFI_VDD")
		(layer "B.Cu")
		(hatch edge 0.5)
		(priority 18)
		(connect_pads yes
			(clearance 0.15)
		)
		(min_thickness 0.25)
		(filled_areas_thickness no)
		(fill yes
			(thermal_gap 0.5)
			(thermal_bridge_width 0.5)
			(smoothing fillet)
			(radius 0.2)
		)
		(polygon
			(pts
				(xy 153.42 83.915) (xy 153.42 86.585) (xy 154.25 86.585) (xy 154.25 83.915)
			)
		)
	)
	(zone
		(net 10)
		(net_name "AVDDH")
		(layer "B.Cu")
		(hatch edge 0.5)
		(priority 15)
		(connect_pads yes
			(clearance 0.15)
		)
		(min_thickness 0.25)
		(filled_areas_thickness no)
		(fill yes
			(thermal_gap 0.5)
			(thermal_bridge_width 0.5)
			(smoothing fillet)
			(radius 0.2)
		)
		(polygon
			(pts
				(xy 157.07 83.625) (xy 157.92 83.625) (xy 157.93 83.635) (xy 157.93 85.295) (xy 158.16 85.525) (xy 158.76 85.525)
				(xy 158.76 86.375) (xy 157.97 86.375) (xy 157.97 85.765) (xy 157.68 85.475) (xy 157.07 85.475)
			)
		)
	)
	(zone
		(net 7)
		(net_name "+3V3")
		(layer "B.Cu")
		(hatch edge 0.5)
		(priority 5)
		(connect_pads yes
			(clearance 0.15)
		)
		(min_thickness 0.25)
		(filled_areas_thickness no)
		(fill yes
			(thermal_gap 0.15)
			(thermal_bridge_width 0.25)
			(smoothing fillet)
			(radius 0.2)
		)
		(polygon
			(pts
				(xy 152.9 75.625) (xy 152.9 73.875) (xy 152.1 73.875) (xy 152.1 75.625)
			)
		)
	)
	(zone
		(net 53)
		(net_name "+5V_USB")
		(layer "B.Cu")
		(hatch edge 0.5)
		(priority 32)
		(connect_pads yes
			(clearance 0)
		)
		(min_thickness 0.25)
		(filled_areas_thickness no)
		(fill yes
			(thermal_gap 0.5)
			(thermal_bridge_width 0.5)
		)
		(polygon
			(pts
				(xy 116.5 139.75) (xy 116.5 141.25) (xy 118.25 141.25) (xy 119.25 142.25) (xy 121 142.25) (xy 121 139.75)
			)
		)
	)
	(zone
		(net 23)
		(net_name "GND")
		(layer "B.Cu")
		(hatch edge 0.5)
		(priority 5)
		(connect_pads yes
			(clearance 0.15)
		)
		(min_thickness 0.25)
		(filled_areas_thickness no)
		(fill yes
			(thermal_gap 0.15)
			(thermal_bridge_width 0.25)
			(smoothing fillet)
			(radius 0.2)
		)
		(polygon
			(pts
				(xy 146.5 84.675) (xy 146.5 75.675) (xy 147.35 75.675) (xy 147.35 74.875) (xy 145.75 74.875) (xy 145.75 84.675)
			)
		)
	)
	(zone
		(net 5)
		(net_name "P0_AVDDL")
		(layer "B.Cu")
		(hatch edge 0.5)
		(priority 9)
		(connect_pads yes
			(clearance 0.15)
		)
		(min_thickness 0.25)
		(filled_areas_thickness no)
		(fill yes
			(thermal_gap 0.5)
			(thermal_bridge_width 0.5)
			(smoothing fillet)
			(radius 0.2)
		)
		(polygon
			(pts
				(xy 159.69 91.005) (xy 158.93 91.005) (xy 158.93 86.745) (xy 159.69 86.745)
			)
		)
	)
	(zone
		(net 9)
		(net_name "VCCD")
		(layer "B.Cu")
		(hatch edge 0.5)
		(priority 5)
		(connect_pads yes
			(clearance 0.15)
		)
		(min_thickness 0.25)
		(filled_areas_thickness no)
		(fill yes
			(thermal_gap 0.15)
			(thermal_bridge_width 0.25)
			(smoothing fillet)
			(radius 0.2)
		)
		(polygon
			(pts
				(xy 147.45 80.625) (xy 147.45 75.875) (xy 146.65 75.875) (xy 146.65 80.625)
			)
		)
	)
	(zone
		(net 1)
		(net_name "VCCA")
		(layer "B.Cu")
		(hatch edge 0.5)
		(priority 5)
		(connect_pads yes
			(clearance 0.15)
		)
		(min_thickness 0.25)
		(filled_areas_thickness no)
		(fill yes
			(thermal_gap 0.15)
			(thermal_bridge_width 0.25)
			(smoothing fillet)
			(radius 0.2)
		)
		(polygon
			(pts
				(xy 152.9 79.625) (xy 152.9 75.825) (xy 152.1 75.825) (xy 152.1 79.625)
			)
		)
	)
	(zone
		(net 23)
		(net_name "GND")
		(layer "B.Cu")
		(hatch edge 0.5)
		(priority 5)
		(connect_pads yes
			(clearance 0.15)
		)
		(min_thickness 0.25)
		(filled_areas_thickness no)
		(fill yes
			(thermal_gap 0.15)
			(thermal_bridge_width 0.25)
			(smoothing fillet)
			(radius 0.2)
		)
		(polygon
			(pts
				(xy 151.95 81.625) (xy 151.95 74.875) (xy 151.2 74.875) (xy 151.2 81.625)
			)
		)
	)
	(zone
		(net 1)
		(net_name "VCCA")
		(layer "B.Cu")
		(hatch edge 0.5)
		(priority 5)
		(connect_pads yes
			(clearance 0.15)
		)
		(min_thickness 0.25)
		(filled_areas_thickness no)
		(fill yes
			(thermal_gap 0.15)
			(thermal_bridge_width 0.25)
			(smoothing fillet)
			(radius 0.2)
		)
		(polygon
			(pts
				(xy 151.1 78.625) (xy 151.1 75.825) (xy 150.3 75.825) (xy 150.3 78.625)
			)
		)
	)
	(zone
		(net 23)
		(net_name "GND")
		(layer "B.Cu")
		(hatch edge 0.5)
		(priority 5)
		(connect_pads yes
			(clearance 0.15)
		)
		(min_thickness 0.25)
		(filled_areas_thickness no)
		(fill yes
			(thermal_gap 0.15)
			(thermal_bridge_width 0.25)
			(smoothing fillet)
			(radius 0.2)
		)
		(polygon
			(pts
				(xy 148.3 81.625) (xy 148.3 75.775) (xy 147.6 75.775) (xy 147.6 81.625)
			)
		)
	)
	(zone
		(net 10)
		(net_name "AVDDH")
		(layer "B.Cu")
		(hatch edge 0.5)
		(priority 12)
		(connect_pads yes
			(clearance 0.15)
		)
		(min_thickness 0.25)
		(filled_areas_thickness no)
		(fill yes
			(thermal_gap 0.5)
			(thermal_bridge_width 0.5)
			(smoothing fillet)
			(radius 0.2)
		)
		(polygon
			(pts
				(xy 157.94 87.735) (xy 157.94 89.475) (xy 157.12 89.475) (xy 157.12 87.735)
			)
		)
	)
	(zone
		(net 9)
		(net_name "VCCD")
		(layer "B.Cu")
		(hatch edge 0.5)
		(priority 5)
		(connect_pads yes
			(clearance 0.15)
		)
		(min_thickness 0.25)
		(filled_areas_thickness no)
		(fill yes
			(thermal_gap 0.15)
			(thermal_bridge_width 0.25)
			(smoothing fillet)
			(radius 0.2)
		)
		(polygon
			(pts
				(xy 151.1 81.625) (xy 151.1 78.825) (xy 150.3 78.825) (xy 150.3 81.625)
			)
		)
	)
	(zone
		(net 53)
		(net_name "+5V_USB")
		(layer "B.Cu")
		(hatch edge 0.5)
		(priority 59)
		(connect_pads yes
			(clearance 0.1)
		)
		(min_thickness 0.1)
		(filled_areas_thickness no)
		(fill yes
			(thermal_gap 0.5)
			(thermal_bridge_width 0.5)
		)
		(polygon
			(pts
				(xy 115.4 111.2) (xy 116.6 111.2) (xy 117.2 110.6) (xy 118.6 110.6) (xy 118.6 113.4) (xy 115.4 113.4)
			)
		)
	)
	(zone
		(net 9)
		(net_name "VCCD")
		(layer "B.Cu")
		(hatch edge 0.5)
		(priority 5)
		(connect_pads yes
			(clearance 0.15)
		)
		(min_thickness 0.25)
		(filled_areas_thickness no)
		(fill yes
			(thermal_gap 0.15)
			(thermal_bridge_width 0.25)
			(smoothing fillet)
			(radius 0.2)
		)
		(polygon
			(pts
				(xy 152.9 81.625) (xy 152.9 79.875) (xy 152.1 79.875) (xy 152.1 81.625)
			)
		)
	)
	(zone
		(net 7)
		(net_name "+3V3")
		(layer "B.Cu")
		(hatch edge 0.5)
		(priority 58)
		(connect_pads yes
			(clearance 0.15)
		)
		(min_thickness 0.25)
		(filled_areas_thickness no)
		(fill yes
			(thermal_gap 0.2)
			(thermal_bridge_width 0.3)
			(smoothing fillet)
			(radius 0.2)
		)
		(polygon
			(pts
				(xy 148.75 69.875) (xy 148.75 68.675) (xy 153.25 68.675) (xy 153.25 69.225) (xy 154.45 69.225) (xy 154.45 69.875)
			)
		)
	)
	(zone
		(net 6)
		(net_name "DVDD")
		(layer "B.Cu")
		(hatch edge 0.5)
		(priority 16)
		(connect_pads yes
			(clearance 0.15)
		)
		(min_thickness 0.25)
		(filled_areas_thickness no)
		(fill yes
			(thermal_gap 0.5)
			(thermal_bridge_width 0.5)
			(smoothing fillet)
			(radius 0.2)
		)
		(polygon
			(pts
				(xy 155.99 83.855) (xy 155.99 88.485) (xy 155.28 88.485) (xy 155.28 83.855)
			)
		)
	)
	(zone
		(net 14)
		(net_name "P1_AVDDL")
		(layer "B.Cu")
		(hatch edge 0.5)
		(priority 10)
		(connect_pads yes
			(clearance 0.15)
		)
		(min_thickness 0.25)
		(filled_areas_thickness no)
		(fill yes
			(thermal_gap 0.5)
			(thermal_bridge_width 0.5)
			(smoothing fillet)
			(radius 0.2)
		)
		(polygon
			(pts
				(xy 158.93 85.475) (xy 159.69 85.475) (xy 159.69 80.825) (xy 158.93 80.825)
			)
		)
	)
	(zone
		(net 23)
		(net_name "GND")
		(layer "B.Cu")
		(hatch edge 0.5)
		(priority 14)
		(connect_pads yes
			(clearance 0.15)
		)
		(min_thickness 0.25)
		(filled_areas_thickness no)
		(fill yes
			(thermal_gap 0.5)
			(thermal_bridge_width 0.5)
			(smoothing fillet)
			(radius 0.2)
		)
		(polygon
			(pts
				(xy 158.76 85.365) (xy 158.05 85.365) (xy 158.05 81.52) (xy 158.76 81.52)
			)
		)
	)
	(zone
		(net 23)
		(net_name "GND")
		(layer "B.Cu")
		(hatch edge 0.5)
		(priority 65)
		(connect_pads yes
			(clearance 0.1)
		)
		(min_thickness 0.1)
		(filled_areas_thickness no)
		(fill yes
			(thermal_gap 0.5)
			(thermal_bridge_width 0.5)
		)
		(polygon
			(pts
				(xy 144.75 99.5) (xy 142 99.5) (xy 142 98) (xy 142.5 97.5) (xy 144.75 97.5)
			)
		)
	)
	(zone
		(net 6)
		(net_name "DVDD")
		(layer "B.Cu")
		(hatch edge 0.5)
		(priority 42)
		(connect_pads yes
			(clearance 0.1)
		)
		(min_thickness 0.1)
		(filled_areas_thickness no)
		(fill yes
			(thermal_gap 0.5)
			(thermal_bridge_width 0.5)
		)
		(polygon
			(pts
				(xy 140.6 99.75) (xy 140.6 101.5) (xy 139.8 102.3) (xy 139.8 103.6) (xy 146.35 103.6) (xy 146.35 99.75)
			)
		)
	)
	(zone
		(net 1)
		(net_name "VCCA")
		(layer "B.Cu")
		(hatch edge 0.5)
		(priority 5)
		(connect_pads yes
			(clearance 0.15)
		)
		(min_thickness 0.25)
		(filled_areas_thickness no)
		(fill yes
			(thermal_gap 0.15)
			(thermal_bridge_width 0.25)
			(smoothing fillet)
			(radius 0.2)
		)
		(polygon
			(pts
				(xy 145.6 81.625) (xy 145.6 76.875) (xy 144.8 76.875) (xy 144.8 81.625)
			)
		)
	)
	(zone
		(net 0)
		(net_name "")
		(layers "In1.Cu" "In2.Cu")
		(hatch edge 0.5)
		(connect_pads yes
			(clearance 0)
		)
		(min_thickness 0.125)
		(filled_areas_thickness no)
		(keepout
			(tracks not_allowed)
			(vias not_allowed)
			(pads not_allowed)
			(copperpour not_allowed)
			(footprints allowed)
		)
		(placement
			(enabled no)
			(sheetname "")
		)
		(fill
			(thermal_gap 0.5)
			(thermal_bridge_width 0.5)
		)
		(polygon
			(pts
				(xy 117.05 125.35) (xy 117.05 124.65) (xy 118.55 124.65) (xy 118.55 125.35)
			)
		)
	)
	(zone
		(net 0)
		(net_name "")
		(layers "In1.Cu" "In2.Cu")
		(hatch edge 0.5)
		(connect_pads yes
			(clearance 0)
		)
		(min_thickness 0.125)
		(filled_areas_thickness no)
		(keepout
			(tracks not_allowed)
			(vias not_allowed)
			(pads not_allowed)
			(copperpour not_allowed)
			(footprints allowed)
		)
		(placement
			(enabled no)
			(sheetname "")
		)
		(fill
			(thermal_gap 0.5)
			(thermal_bridge_width 0.5)
		)
		(polygon
			(pts
				(xy 117.05 127.348372) (xy 117.05 126.648372) (xy 118.55 126.648372) (xy 118.55 127.348372)
			)
		)
	)
	(zone
		(net 0)
		(net_name "")
		(layers "In1.Cu" "In2.Cu")
		(hatch edge 0.5)
		(connect_pads yes
			(clearance 0)
		)
		(min_thickness 0.125)
		(filled_areas_thickness no)
		(keepout
			(tracks not_allowed)
			(vias not_allowed)
			(pads not_allowed)
			(copperpour not_allowed)
			(footprints allowed)
		)
		(placement
			(enabled no)
			(sheetname "")
		)
		(fill
			(thermal_gap 0.5)
			(thermal_bridge_width 0.5)
		)
		(polygon
			(pts
				(xy 117.05 124.35) (xy 117.05 123.65) (xy 118.55 123.65) (xy 118.55 124.35)
			)
		)
	)
	(zone
		(net 0)
		(net_name "")
		(layers "In1.Cu" "In2.Cu")
		(hatch edge 0.5)
		(connect_pads yes
			(clearance 0)
		)
		(min_thickness 0.125)
		(filled_areas_thickness no)
		(keepout
			(tracks not_allowed)
			(vias not_allowed)
			(pads not_allowed)
			(copperpour not_allowed)
			(footprints allowed)
		)
		(placement
			(enabled no)
			(sheetname "")
		)
		(fill
			(thermal_gap 0.5)
			(thermal_bridge_width 0.5)
		)
		(polygon
			(pts
				(xy 137.275 72.575) (xy 137.275 71.875) (xy 138.775 71.875) (xy 138.775 72.575)
			)
		)
	)
	(zone
		(net 0)
		(net_name "")
		(layers "In1.Cu" "In2.Cu")
		(hatch edge 0.5)
		(connect_pads yes
			(clearance 0)
		)
		(min_thickness 0.125)
		(filled_areas_thickness no)
		(keepout
			(tracks not_allowed)
			(vias not_allowed)
			(pads not_allowed)
			(copperpour not_allowed)
			(footprints allowed)
		)
		(placement
			(enabled no)
			(sheetname "")
		)
		(fill
			(thermal_gap 0.5)
			(thermal_bridge_width 0.5)
		)
		(polygon
			(pts
				(xy 138.25 67.85) (xy 138.25 67.15) (xy 139.75 67.15) (xy 139.75 67.85)
			)
		)
	)
	(zone
		(net 0)
		(net_name "")
		(layers "In1.Cu" "In2.Cu")
		(hatch edge 0.5)
		(connect_pads yes
			(clearance 0)
		)
		(min_thickness 0.125)
		(filled_areas_thickness no)
		(keepout
			(tracks not_allowed)
			(vias not_allowed)
			(pads not_allowed)
			(copperpour not_allowed)
			(footprints allowed)
		)
		(placement
			(enabled no)
			(sheetname "")
		)
		(fill
			(thermal_gap 0.5)
			(thermal_bridge_width 0.5)
		)
		(polygon
			(pts
				(xy 117.05 122.35) (xy 117.05 121.65) (xy 118.55 121.65) (xy 118.55 122.35)
			)
		)
	)
	(zone
		(net 0)
		(net_name "")
		(layers "In1.Cu" "In2.Cu")
		(hatch edge 0.5)
		(connect_pads yes
			(clearance 0)
		)
		(min_thickness 0.125)
		(filled_areas_thickness no)
		(keepout
			(tracks not_allowed)
			(vias not_allowed)
			(pads not_allowed)
			(copperpour not_allowed)
			(footprints allowed)
		)
		(placement
			(enabled no)
			(sheetname "")
		)
		(fill
			(thermal_gap 0.5)
			(thermal_bridge_width 0.5)
		)
		(polygon
			(pts
				(xy 138.25 68.85) (xy 138.25 68.15) (xy 139.75 68.15) (xy 139.75 68.85)
			)
		)
	)
	(zone
		(net 0)
		(net_name "")
		(layers "In1.Cu" "In2.Cu")
		(hatch edge 0.5)
		(connect_pads yes
			(clearance 0)
		)
		(min_thickness 0.125)
		(filled_areas_thickness no)
		(keepout
			(tracks not_allowed)
			(vias not_allowed)
			(pads not_allowed)
			(copperpour not_allowed)
			(footprints allowed)
		)
		(placement
			(enabled no)
			(sheetname "")
		)
		(fill
			(thermal_gap 0.5)
			(thermal_bridge_width 0.5)
		)
		(polygon
			(pts
				(xy 125.4 134) (xy 126.1 134) (xy 126.1 135.5) (xy 125.4 135.5)
			)
		)
	)
	(zone
		(net 0)
		(net_name "")
		(layers "In1.Cu" "In2.Cu")
		(hatch edge 0.5)
		(connect_pads yes
			(clearance 0)
		)
		(min_thickness 0.125)
		(filled_areas_thickness no)
		(keepout
			(tracks not_allowed)
			(vias not_allowed)
			(pads not_allowed)
			(copperpour not_allowed)
			(footprints allowed)
		)
		(placement
			(enabled no)
			(sheetname "")
		)
		(fill
			(thermal_gap 0.5)
			(thermal_bridge_width 0.5)
		)
		(polygon
			(pts
				(xy 117.05 119.35) (xy 117.05 118.65) (xy 118.55 118.65) (xy 118.55 119.35)
			)
		)
	)
	(zone
		(net 0)
		(net_name "")
		(layers "In1.Cu" "In2.Cu")
		(hatch edge 0.5)
		(connect_pads yes
			(clearance 0)
		)
		(min_thickness 0.125)
		(filled_areas_thickness no)
		(keepout
			(tracks not_allowed)
			(vias not_allowed)
			(pads not_allowed)
			(copperpour not_allowed)
			(footprints allowed)
		)
		(placement
			(enabled no)
			(sheetname "")
		)
		(fill
			(thermal_gap 0.5)
			(thermal_bridge_width 0.5)
		)
		(polygon
			(pts
				(xy 124.4 134) (xy 125.1 134) (xy 125.1 135.5) (xy 124.4 135.5)
			)
		)
	)
	(zone
		(net 0)
		(net_name "")
		(layers "In1.Cu" "In2.Cu")
		(hatch edge 0.5)
		(connect_pads yes
			(clearance 0)
		)
		(min_thickness 0.125)
		(filled_areas_thickness no)
		(keepout
			(tracks not_allowed)
			(vias not_allowed)
			(pads not_allowed)
			(copperpour not_allowed)
			(footprints allowed)
		)
		(placement
			(enabled no)
			(sheetname "")
		)
		(fill
			(thermal_gap 0.5)
			(thermal_bridge_width 0.5)
		)
		(polygon
			(pts
				(xy 137.275 78.101628) (xy 137.275 77.401628) (xy 138.775 77.401628) (xy 138.775 78.101628)
			)
		)
	)
	(zone
		(net 0)
		(net_name "")
		(layers "In1.Cu" "In2.Cu")
		(hatch edge 0.5)
		(connect_pads yes
			(clearance 0)
		)
		(min_thickness 0.125)
		(filled_areas_thickness no)
		(keepout
			(tracks not_allowed)
			(vias not_allowed)
			(pads not_allowed)
			(copperpour not_allowed)
			(footprints allowed)
		)
		(placement
			(enabled no)
			(sheetname "")
		)
		(fill
			(thermal_gap 0.5)
			(thermal_bridge_width 0.5)
		)
		(polygon
			(pts
				(xy 137.275 79.101628) (xy 137.275 78.401628) (xy 138.775 78.401628) (xy 138.775 79.101628)
			)
		)
	)
	(zone
		(net 0)
		(net_name "")
		(layers "In1.Cu" "In2.Cu")
		(hatch edge 0.5)
		(connect_pads yes
			(clearance 0)
		)
		(min_thickness 0.125)
		(filled_areas_thickness no)
		(keepout
			(tracks not_allowed)
			(vias not_allowed)
			(pads not_allowed)
			(copperpour not_allowed)
			(footprints allowed)
		)
		(placement
			(enabled no)
			(sheetname "")
		)
		(fill
			(thermal_gap 0.5)
			(thermal_bridge_width 0.5)
		)
		(polygon
			(pts
				(xy 137.275 82.1) (xy 137.275 81.4) (xy 138.775 81.4) (xy 138.775 82.1)
			)
		)
	)
	(zone
		(net 0)
		(net_name "")
		(layers "In1.Cu" "In2.Cu")
		(hatch edge 0.5)
		(connect_pads yes
			(clearance 0)
		)
		(min_thickness 0.125)
		(filled_areas_thickness no)
		(keepout
			(tracks not_allowed)
			(vias not_allowed)
			(pads not_allowed)
			(copperpour not_allowed)
			(footprints allowed)
		)
		(placement
			(enabled no)
			(sheetname "")
		)
		(fill
			(thermal_gap 0.5)
			(thermal_bridge_width 0.5)
		)
		(polygon
			(pts
				(xy 117.05 128.348372) (xy 117.05 127.648372) (xy 118.55 127.648372) (xy 118.55 128.348372)
			)
		)
	)
	(zone
		(net 0)
		(net_name "")
		(layers "In1.Cu" "In2.Cu")
		(hatch edge 0.5)
		(connect_pads yes
			(clearance 0)
		)
		(min_thickness 0.125)
		(filled_areas_thickness no)
		(keepout
			(tracks not_allowed)
			(vias not_allowed)
			(pads not_allowed)
			(copperpour not_allowed)
			(footprints allowed)
		)
		(placement
			(enabled no)
			(sheetname "")
		)
		(fill
			(thermal_gap 0.5)
			(thermal_bridge_width 0.5)
		)
		(polygon
			(pts
				(xy 137.275 75.101628) (xy 137.275 74.401628) (xy 138.775 74.401628) (xy 138.775 75.101628)
			)
		)
	)
	(zone
		(net 0)
		(net_name "")
		(layers "In1.Cu" "In2.Cu")
		(hatch edge 0.5)
		(connect_pads yes
			(clearance 0)
		)
		(min_thickness 0.125)
		(filled_areas_thickness no)
		(keepout
			(tracks not_allowed)
			(vias not_allowed)
			(pads not_allowed)
			(copperpour not_allowed)
			(footprints allowed)
		)
		(placement
			(enabled no)
			(sheetname "")
		)
		(fill
			(thermal_gap 0.5)
			(thermal_bridge_width 0.5)
		)
		(polygon
			(pts
				(xy 137.275 76.101628) (xy 137.275 75.401628) (xy 138.775 75.401628) (xy 138.775 76.101628)
			)
		)
	)
	(zone
		(net 0)
		(net_name "")
		(layers "In1.Cu" "In2.Cu")
		(hatch edge 0.5)
		(connect_pads yes
			(clearance 0)
		)
		(min_thickness 0.125)
		(filled_areas_thickness no)
		(keepout
			(tracks not_allowed)
			(vias not_allowed)
			(pads not_allowed)
			(copperpour not_allowed)
			(footprints allowed)
		)
		(placement
			(enabled no)
			(sheetname "")
		)
		(fill
			(thermal_gap 0.5)
			(thermal_bridge_width 0.5)
		)
		(polygon
			(pts
				(xy 117.05 121.35) (xy 117.05 120.65) (xy 118.55 120.65) (xy 118.55 121.35)
			)
		)
	)
	(zone
		(net 0)
		(net_name "")
		(layers "In1.Cu" "In2.Cu")
		(hatch edge 0.5)
		(connect_pads yes
			(clearance 0)
		)
		(min_thickness 0.125)
		(filled_areas_thickness no)
		(keepout
			(tracks not_allowed)
			(vias not_allowed)
			(pads not_allowed)
			(copperpour not_allowed)
			(footprints allowed)
		)
		(placement
			(enabled no)
			(sheetname "")
		)
		(fill
			(thermal_gap 0.5)
			(thermal_bridge_width 0.5)
		)
		(polygon
			(pts
				(xy 137.275 73.575) (xy 137.275 72.875) (xy 138.775 72.875) (xy 138.775 73.575)
			)
		)
	)
	(zone
		(net 0)
		(net_name "")
		(layers "In1.Cu" "In2.Cu")
		(hatch edge 0.5)
		(connect_pads yes
			(clearance 0)
		)
		(min_thickness 0.125)
		(filled_areas_thickness no)
		(keepout
			(tracks not_allowed)
			(vias not_allowed)
			(pads not_allowed)
			(copperpour not_allowed)
			(footprints allowed)
		)
		(placement
			(enabled no)
			(sheetname "")
		)
		(fill
			(thermal_gap 0.5)
			(thermal_bridge_width 0.5)
		)
		(polygon
			(pts
				(xy 137.275 81.1) (xy 137.275 80.4) (xy 138.775 80.4) (xy 138.775 81.1)
			)
		)
	)
	(zone
		(net 0)
		(net_name "")
		(layers "In1.Cu" "In2.Cu")
		(hatch edge 0.5)
		(connect_pads yes
			(clearance 0)
		)
		(min_thickness 0.125)
		(filled_areas_thickness no)
		(keepout
			(tracks not_allowed)
			(vias not_allowed)
			(pads not_allowed)
			(copperpour not_allowed)
			(footprints allowed)
		)
		(placement
			(enabled no)
			(sheetname "")
		)
		(fill
			(thermal_gap 0.5)
			(thermal_bridge_width 0.5)
		)
		(polygon
			(pts
				(xy 117.05 118.35) (xy 117.05 117.65) (xy 118.55 117.65) (xy 118.55 118.35)
			)
		)
	)
	(zone
		(net 23)
		(net_name "GND")
		(layers "In1.Cu" "In4.Cu" "In6.Cu")
		(hatch edge 0.5)
		(connect_pads
			(clearance 0.1)
		)
		(min_thickness 0.12)
		(filled_areas_thickness no)
		(fill yes
			(thermal_gap 0.5)
			(thermal_bridge_width 0.5)
		)
		(polygon
			(pts
				(xy 110 160) (xy 190 160) (xy 190 40) (xy 110 40)
			)
		)
	)
	(zone
		(net 14)
		(net_name "P1_AVDDL")
		(layer "In2.Cu")
		(hatch edge 0.5)
		(priority 25)
		(connect_pads yes
			(clearance 0.1)
		)
		(min_thickness 0.1)
		(filled_areas_thickness no)
		(fill yes
			(thermal_gap 0.5)
			(thermal_bridge_width 0.5)
			(smoothing fillet)
			(radius 0.2)
		)
		(polygon
			(pts
				(xy 165.16 96.275) (xy 165.16 93.025) (xy 164.74 93.025) (xy 163.35 91.635) (xy 163.35 81.925) (xy 158.25 81.925)
				(xy 158.25 86.175) (xy 160.795042 86.175) (xy 161.69 87.045) (xy 161.69 96.275)
			)
		)
	)
	(zone
		(net 20)
		(net_name "XGB_AVDDH")
		(layer "In2.Cu")
		(hatch edge 0.5)
		(priority 61)
		(connect_pads yes
			(clearance 0.1)
		)
		(min_thickness 0.1)
		(filled_areas_thickness no)
		(fill yes
			(thermal_gap 0.5)
			(thermal_bridge_width 0.5)
			(smoothing fillet)
			(radius 0.2)
		)
		(polygon
			(pts
				(xy 145.25 96.975) (xy 145.25 94.464612) (xy 150.6 94.475) (xy 150.86 94.825) (xy 154 94.825) (xy 156.96 91.865)
				(xy 156.96 87.375) (xy 158.83 87.375) (xy 158.83 97.1) (xy 146.65 97.1) (xy 146.65 96.975)
			)
		)
	)
	(zone
		(net 215)
		(net_name "/USB-C connector/VBUS")
		(layer "In2.Cu")
		(hatch edge 0.5)
		(priority 45)
		(connect_pads
			(clearance 0.1)
		)
		(min_thickness 0.1)
		(filled_areas_thickness no)
		(fill yes
			(thermal_gap 0.5)
			(thermal_bridge_width 0.5)
		)
		(polygon
			(pts
				(xy 115 144.5) (xy 126 144.5) (xy 126 155.5) (xy 115 155.5)
			)
		)
	)
	(zone
		(net 18)
		(net_name "+1V88")
		(layer "In2.Cu")
		(hatch edge 0.5)
		(priority 100)
		(connect_pads yes
			(clearance 0.1)
		)
		(min_thickness 0.1)
		(filled_areas_thickness no)
		(fill yes
			(thermal_gap 0.5)
			(thermal_bridge_width 0.5)
			(smoothing fillet)
			(radius 0.2)
		)
		(polygon
			(pts
				(xy 145.2 97.2) (xy 145.2 101.9) (xy 170.1 101.9) (xy 170.1 80.4) (xy 174.4 80.4) (xy 174.4 72.925)
				(xy 165.95 72.925) (xy 165.95 66.15) (xy 162.8 66.15) (xy 162.8 69.6) (xy 153.45 69.6) (xy 153.45 73.9)
				(xy 153.4 73.9) (xy 153.4 81.5) (xy 163.6 81.6) (xy 163.6 91.635) (xy 165.2 93.2) (xy 165.2 96.4)
				(xy 159 96.4) (xy 159 97.2)
			)
		)
	)
	(zone
		(net 7)
		(net_name "+3V3")
		(layer "In2.Cu")
		(hatch edge 0.5)
		(priority 19)
		(connect_pads
			(clearance 0.1)
		)
		(min_thickness 0.12)
		(filled_areas_thickness no)
		(fill yes
			(thermal_gap 0.5)
			(thermal_bridge_width 0.5)
		)
		(polygon
			(pts
				(xy 110 160) (xy 190 160) (xy 190 40) (xy 110 40)
			)
		)
	)
	(zone
		(net 6)
		(net_name "DVDD")
		(layer "In2.Cu")
		(name "INNER_GND")
		(hatch edge 0.5)
		(priority 32)
		(connect_pads yes
			(clearance 0.1)
		)
		(min_thickness 0.1)
		(filled_areas_thickness no)
		(fill yes
			(thermal_gap 0.2)
			(thermal_bridge_width 0.3)
			(smoothing fillet)
			(radius 0.2)
		)
		(polygon
			(pts
				(xy 140.8 101.975) (xy 145.05 101.975) (xy 145.05 94.475) (xy 150.6 94.475) (xy 150.6 86.895) (xy 153.72 83.775)
				(xy 154.2 83.775) (xy 155.05 84.625) (xy 155.05 94.575) (xy 158.05 94.575) (xy 158.05 81.925) (xy 140.8 81.925)
			)
		)
	)
	(zone
		(net 5)
		(net_name "P0_AVDDL")
		(layer "In2.Cu")
		(hatch edge 0.5)
		(priority 26)
		(connect_pads yes
			(clearance 0.15)
		)
		(min_thickness 0.25)
		(filled_areas_thickness no)
		(fill yes
			(thermal_gap 0.5)
			(thermal_bridge_width 0.5)
			(smoothing fillet)
			(radius 0.2)
		)
		(polygon
			(pts
				(xy 161.599998 96.275) (xy 161.598519 87.169849) (xy 160.754519 86.325) (xy 158.25 86.325) (xy 158.25 96.275)
			)
		)
	)
	(zone
		(net 68)
		(net_name "/TB Controller - Power/VCC_0P9")
		(layer "In2.Cu")
		(hatch edge 0.5)
		(priority 29)
		(connect_pads yes
			(clearance 0.1)
		)
		(min_thickness 0.1)
		(filled_areas_thickness no)
		(fill yes
			(thermal_gap 0.5)
			(thermal_bridge_width 0.5)
		)
		(polygon
			(pts
				(xy 137.4 120) (xy 137.4 124) (xy 126 124) (xy 126 130) (xy 142 130) (xy 142 120)
			)
		)
	)
	(zone
		(net 57)
		(net_name "+3V3_TB")
		(layer "In2.Cu")
		(hatch edge 0.5)
		(priority 21)
		(connect_pads
			(clearance 0.1)
		)
		(min_thickness 0.12)
		(filled_areas_thickness no)
		(fill yes
			(thermal_gap 0.5)
			(thermal_bridge_width 0.5)
		)
		(polygon
			(pts
				(xy 115 157) (xy 138 157) (xy 138 147) (xy 149 147) (xy 149 112) (xy 127 112) (xy 125 110) (xy 125 101)
				(xy 132.4 101) (xy 132.4 94) (xy 123 94) (xy 122 93) (xy 122 87) (xy 115 87)
			)
		)
	)
	(zone
		(net 9)
		(net_name "VCCD")
		(layer "In2.Cu")
		(hatch edge 0.5)
		(priority 30)
		(connect_pads
			(clearance 0.1)
		)
		(min_thickness 0.1)
		(filled_areas_thickness no)
		(fill yes
			(thermal_gap 0.5)
			(thermal_bridge_width 0.5)
			(smoothing fillet)
			(radius 0.2)
		)
		(polygon
			(pts
				(xy 140.7 101.975) (xy 140.7 81.575) (xy 153.41 81.575) (xy 153.41 73.075) (xy 132.35 73.075) (xy 132.35 101.975)
			)
		)
	)
	(zone
		(net 12)
		(net_name "XFI_VDD")
		(layers "In2.Cu" "In5.Cu")
		(hatch edge 0.5)
		(priority 26)
		(connect_pads yes
			(clearance 0.1)
		)
		(min_thickness 0.1)
		(filled_areas_thickness no)
		(fill yes
			(thermal_gap 0.5)
			(thermal_bridge_width 0.5)
		)
		(polygon
			(pts
				(xy 150.85 94.575) (xy 154.75 94.575) (xy 154.75 84.635) (xy 154.12 84.005) (xy 153.81 84.005) (xy 150.85 86.965)
			)
		)
	)
	(zone
		(net 180)
		(net_name "Net-(U4A-VCC0P9_LVR_SENSE)")
		(layer "In3.Cu")
		(hatch edge 0.5)
		(priority 46)
		(connect_pads yes
			(clearance 0.1)
		)
		(min_thickness 0.1)
		(filled_areas_thickness no)
		(fill yes
			(thermal_gap 0.5)
			(thermal_bridge_width 0.5)
			(smoothing fillet)
			(radius 0.2)
		)
		(polygon
			(pts
				(xy 125.2 128.4) (xy 128.6 128.4) (xy 128.6 129.8) (xy 129.6 129.8) (xy 129.6 125.4) (xy 125.2 125.4)
			)
		)
	)
	(zone
		(net 40)
		(net_name "+5V")
		(layer "In3.Cu")
		(hatch edge 0.5)
		(priority 31)
		(connect_pads
			(clearance 0.1)
		)
		(min_thickness 0.12)
		(filled_areas_thickness no)
		(fill yes
			(thermal_gap 0.5)
			(thermal_bridge_width 0.5)
		)
		(polygon
			(pts
				(xy 145.9 113.4) (xy 148 115.5) (xy 165 115.5) (xy 165 103.5) (xy 143 103.5) (xy 134.5 95) (xy 125.5 95)
				(xy 124 93.75) (xy 124 77.5) (xy 131.5 70) (xy 140.5 70) (xy 142 68.5) (xy 142 59) (xy 115 59) (xy 115 97)
				(xy 123 105) (xy 128.5 105) (xy 131.5 108.5) (xy 131.5 113.4)
			)
		)
	)
	(zone
		(net 402)
		(net_name "Net-(C52-Pad2)")
		(layer "In3.Cu")
		(hatch edge 0.5)
		(priority 47)
		(connect_pads yes
			(clearance 0.1)
		)
		(min_thickness 0.1)
		(filled_areas_thickness no)
		(fill yes
			(thermal_gap 0.5)
			(thermal_bridge_width 0.5)
			(smoothing fillet)
			(radius 0.2)
		)
		(polygon
			(pts
				(xy 127.5 120.5) (xy 127.5 125.25) (xy 132 125.25) (xy 132 121.75) (xy 130.75 120.5)
			)
		)
	)
	(zone
		(net 21)
		(net_name "XFI_PVDD")
		(layer "In5.Cu")
		(hatch edge 0.5)
		(priority 64)
		(connect_pads yes
			(clearance 0.1)
		)
		(min_thickness 0.1)
		(filled_areas_thickness no)
		(fill yes
			(thermal_gap 0.5)
			(thermal_bridge_width 0.5)
		)
		(polygon
			(pts
				(xy 153.4 93.4) (xy 156.6 93.4) (xy 156.6 86.8) (xy 153.6 86.8) (xy 153.6 87.6) (xy 154.8 87.6)
				(xy 154.8 92.4) (xy 153.4 92.4)
			)
		)
	)
	(zone
		(net 1)
		(net_name "VCCA")
		(layer "In5.Cu")
		(hatch edge 0.5)
		(priority 51)
		(connect_pads yes
			(clearance 0.1)
		)
		(min_thickness 0.1)
		(filled_areas_thickness no)
		(fill yes
			(thermal_gap 0.5)
			(thermal_bridge_width 0.5)
			(smoothing fillet)
			(radius 0.2)
		)
		(polygon
			(pts
				(xy 144.5 82) (xy 153.5 82) (xy 153.5 75) (xy 152.5 74) (xy 152.5 71.5) (xy 153.5 70.5) (xy 153.5 64)
				(xy 144.5 64)
			)
		)
	)
	(zone
		(net 0)
		(net_name "")
		(layers "In5.Cu" "In6.Cu")
		(hatch edge 0.5)
		(connect_pads yes
			(clearance 0)
		)
		(min_thickness 0.125)
		(filled_areas_thickness no)
		(keepout
			(tracks not_allowed)
			(vias not_allowed)
			(pads not_allowed)
			(copperpour not_allowed)
			(footprints allowed)
		)
		(placement
			(enabled no)
			(sheetname "")
		)
		(fill
			(thermal_gap 0.5)
			(thermal_bridge_width 0.5)
		)
		(polygon
			(pts
				(xy 126.6 134) (xy 125.9 134) (xy 125.9 135.5) (xy 126.6 135.5)
			)
		)
	)
	(zone
		(net 0)
		(net_name "")
		(layers "In5.Cu" "In6.Cu")
		(hatch edge 0.5)
		(connect_pads yes
			(clearance 0)
		)
		(min_thickness 0.125)
		(filled_areas_thickness no)
		(keepout
			(tracks not_allowed)
			(vias not_allowed)
			(pads not_allowed)
			(copperpour not_allowed)
			(footprints allowed)
		)
		(placement
			(enabled no)
			(sheetname "")
		)
		(fill
			(thermal_gap 0.5)
			(thermal_bridge_width 0.5)
		)
		(polygon
			(pts
				(xy 127.6 134) (xy 126.9 134) (xy 126.9 135.5) (xy 127.6 135.5)
			)
		)
	)
	(zone
		(net 10)
		(net_name "AVDDH")
		(layer "In6.Cu")
		(hatch edge 0.5)
		(priority 27)
		(connect_pads yes
			(clearance 0.1)
		)
		(min_thickness 0.1)
		(filled_areas_thickness no)
		(fill yes
			(thermal_gap 0.5)
			(thermal_bridge_width 0.5)
			(smoothing fillet)
			(radius 0.2)
		)
		(polygon
			(pts
				(xy 157.24 92.725) (xy 157.24 83.875) (xy 159.2 83.875) (xy 159.2 96.625) (xy 147.65 96.625) (xy 147.65 92.725)
			)
		)
	)
	(zone
		(net 18)
		(net_name "+1V88")
		(layer "In6.Cu")
		(name "INNER_GND")
		(hatch edge 0.5)
		(priority 29)
		(connect_pads yes
			(clearance 0.1)
		)
		(min_thickness 0.1)
		(filled_areas_thickness no)
		(fill yes
			(thermal_gap 0.2)
			(thermal_bridge_width 0.3)
			(smoothing fillet)
			(radius 0.2)
		)
		(polygon
			(pts
				(xy 157.1 82.725) (xy 157.1 92.425) (xy 147.35 92.425) (xy 147.35 96.875) (xy 149.75 96.875) (xy 149.75 99.615)
				(xy 144.55 99.615) (xy 144.55 89.125) (xy 153.55 89.125) (xy 153.55 83.975) (xy 154.8 82.725)
			)
		)
	)
	(zone
		(net 7)
		(net_name "+3V3")
		(layer "In6.Cu")
		(name "INNER_GND")
		(hatch edge 0.5)
		(priority 20)
		(connect_pads yes
			(clearance 0.1)
		)
		(min_thickness 0.1)
		(filled_areas_thickness no)
		(fill yes
			(thermal_gap 0.2)
			(thermal_bridge_width 0.3)
			(smoothing fillet)
			(radius 0.2)
		)
		(polygon
			(pts
				(xy 140.4 89.4) (xy 139.2 89.4) (xy 139.2 92.4) (xy 139.8 92.4) (xy 139.8 93.2) (xy 144.4 93.2)
				(xy 144.4 89) (xy 153.4 89) (xy 153.4 83.8) (xy 155.4 81.8) (xy 155.4 74) (xy 155.2 73.8) (xy 152.4 73.8)
				(xy 152.2 73.8) (xy 144.8 73.8) (xy 144.8 82.8) (xy 142.19 85.4) (xy 140.4 85.4)
			)
		)
	)
)
